; Packager-XL run on 01-Oct-2015 AT 15:49:50 CONSTRAINTS_VIEW_GENERATED
( ConstraintFile "baseboard_fab2"
	( constraintHeader
		( objectKey
			( physical )
		)
		( version
			( 16.6 )
		)
		( revisionNumber
			( logicalViewRevNum 302 )
			( physicalViewRevNum 0 )
			( otherViewRevNum 0 )
		)
		( contents
			( dictionaryExtensions )
			( worksheetCustomizations )
			( electricalConstraints )
			( netClasses )
			( properties )
		)
		( precision
			( units mil )
			( numberOfDecimalPlaces 2 )
		)
	)
	( DictionaryExtensions
		( Attribute
			( Name "BOM_COST" )
			( Description " " )
			( Value
				( DataType ( dString ) )
				( Status  sProperty  sPackage )
			)
			( Objects
				( ValidObjects  oGate  oGateDefn  oBlock  oPart  oDesign  oSystem  oPartDefn  oNet )
				( NoInherit
					( oGate oPin )
				)
			)
			( Analysis
			)
		)
		( Attribute
			( Name "MATERIAL" )
			( Description " " )
			( Value
				( DataType ( dString ) )
				( Status  sProperty  sPackage )
			)
			( Objects
				( ValidObjects  oGate  oGateDefn  oBlock  oPart  oDesign  oSystem  oPartDefn )
				( NoInherit
					( oGate oPin )
				)
			)
			( Analysis
			)
		)
		( Attribute
			( Name "SEC_TYPE" )
			( Description " " )
			( Value
				( DataType ( dString ) )
				( Status  sProperty  sPackage )
			)
			( Objects
				( ValidObjects  oGate  oGateDefn  oBlock  oPart  oDesign  oSystem  oPartDefn )
				( NoInherit
					( oGate oPin )
				)
			)
			( Analysis
			)
		)
		( Attribute
			( Name "TOLERANCE" )
			( Description " " )
			( Value
				( DataType ( dString ) )
				( Status  sProperty  sPackage )
			)
			( Objects
				( ValidObjects  oGate  oGateDefn  oBlock  oPart  oDesign  oSystem  oPartDefn )
				( NoInherit
					( oGate oPin )
				)
			)
			( Analysis
			)
		)
		( Attribute
			( Name "WATTAGE" )
			( Description " " )
			( Value
				( DataType ( dString ) )
				( Status  sProperty  sPackage )
			)
			( Objects
				( ValidObjects  oGate  oGateDefn  oBlock  oPart  oDesign  oSystem  oPartDefn )
				( NoInherit
					( oGate oPin )
				)
			)
			( Analysis
			)
		)
		( Attribute
			( Name "SKT_NUMBER" )
			( Description " " )
			( Value
				( DataType ( dString ) )
				( Status  sProperty  sPackage )
			)
			( Objects
				( ValidObjects  oGate  oGateDefn  oBlock  oPart  oDesign  oSystem  oPartDefn )
				( NoInherit
					( oGate oPin )
				)
			)
			( Analysis
			)
		)
		( Attribute
			( Name "CD_SEC" )
			( Description " " )
			( Value
				( DataType ( dString ) )
				( Status  sProperty  sPackage )
			)
			( Objects
				( ValidObjects  oGate  oGateDefn  oBlock  oPart  oDesign  oSystem  oPartDefn )
				( NoInherit
					( oGate oPin )
				)
			)
			( Analysis
			)
		)
		( Attribute
			( Name "CDS_LMAN_SYM_OUTLINE" )
			( Description " " )
			( Value
				( DataType ( dString ) )
				( Status  sProperty  sPackage )
			)
			( Objects
				( ValidObjects  oGate  oGateDefn  oBlock  oPart  oDesign  oSystem  oPartDefn )
				( NoInherit
					( oGate oPin )
				)
			)
			( Analysis
			)
		)
		( Attribute
			( Name "SKU" )
			( Description " " )
			( Value
				( DataType ( dString ) )
				( Status  sProperty  sPackage )
			)
			( Objects
				( ValidObjects  oGate  oGateDefn  oBlock  oPart  oDesign  oSystem  oPartDefn )
				( NoInherit
					( oGate oPin )
				)
			)
			( Analysis
			)
		)
		( Attribute
			( Name "COLOR" )
			( Description " " )
			( Value
				( DataType ( dString ) )
				( Status  sProperty  sPackage )
			)
			( Objects
				( ValidObjects  oGate  oGateDefn  oBlock  oPart  oDesign  oSystem  oPartDefn )
				( NoInherit
					( oGate oPin )
				)
			)
			( Analysis
			)
		)
		( Attribute
			( Name "VOLATGE" )
			( Description " " )
			( Value
				( DataType ( dString ) )
				( Status  sProperty  sPackage )
			)
			( Objects
				( ValidObjects  oNet  oXnet  oPinPair  oBus  oDiffPair  oECSet )
			)
			( Analysis
			)
		)
		( Attribute
			( Name "SPOF" )
			( Description " " )
			( Value
				( DataType ( dString ) )
				( Status  sProperty  sPackage )
			)
			( Objects
				( ValidObjects  oGate  oGateDefn  oBlock  oPart  oDesign  oSystem  oPartDefn )
				( NoInherit
					( oGate oPin )
				)
			)
			( Analysis
			)
		)
		( Attribute
			( Name "BOM" )
			( Description " " )
			( Value
				( DataType ( dString ) )
				( Status  sProperty  sPackage )
			)
			( Objects
				( ValidObjects  oGate  oGateDefn  oBlock  oPart  oDesign  oSystem  oPartDefn )
				( NoInherit
					( oGate oPin )
				)
			)
			( Analysis
			)
		)
		( Attribute
			( Name "FIN" )
			( Description " " )
			( Value
				( DataType ( dString ) )
				( Status  sProperty  sPackage )
			)
			( Objects
				( ValidObjects  oGate  oGateDefn  oBlock  oPart  oDesign  oSystem  oPartDefn )
				( NoInherit
					( oGate oPin )
				)
			)
			( Analysis
			)
		)
		( Attribute
			( Name "P1V5_STBY_IBMC" )
			( Description " " )
			( Value
				( DataType ( dString ) )
				( Status  sProperty  sPackage )
			)
			( Objects
				( ValidObjects  oGate  oGateDefn  oBlock  oPart  oDesign  oSystem  oPartDefn )
				( NoInherit
					( oGate oPin )
				)
			)
			( Analysis
			)
		)
		( Attribute
			( Name "P1V5_STBY_IBMC_VR" )
			( Description " " )
			( Value
				( DataType ( dString ) )
				( Status  sProperty  sPackage )
			)
			( Objects
				( ValidObjects  oGate  oGateDefn  oBlock  oPart  oDesign  oSystem  oPartDefn )
				( NoInherit
					( oGate oPin )
				)
			)
			( Analysis
			)
		)
		( Attribute
			( Name "$location" )
			( Description "" )
			( Value
				( DataType ( dString ) )
				( Status  sProperty )
			)
			( Objects
				( ValidObjects  oAll )
			)
			( Analysis
			)
		)
		( Attribute
			( Name "$sec" )
			( Description "" )
			( Value
				( DataType ( dString ) )
				( Status  sProperty )
			)
			( Objects
				( ValidObjects  oAll )
			)
			( Analysis
			)
		)
		( Attribute
			( Name "WACKO" )
			( Description " " )
			( Value
				( DataType ( dString ) )
				( Status  sProperty  sPackage )
			)
			( Objects
				( ValidObjects  oGate  oGateDefn  oBlock  oPart  oDesign  oSystem  oPartDefn )
				( NoInherit
					( oGate oPin )
				)
			)
			( Analysis
			)
		)
		( Attribute
			( Name "BODY_TYPE" )
			( Description " " )
			( Value
				( DataType ( dString ) )
				( Status  sProperty  sPackage )
			)
			( Objects
				( ValidObjects  oGate  oGateDefn  oBlock  oPart  oDesign  oSystem  oPartDefn )
			)
			( Analysis
			)
		)
	)
	( designConstraints
		( ruleChanges
			( allRules )
			( design "baseboard_fab2"
				( objectFlag fObjectReadOnly )
				( objectStatus sObjectLogicalNet )
			)
			( signal "A_CPU0_ABC_RCOMP0"
				( objectStatus "@baseboard_fab2_lib.baseboard_fab2(sch_1):a_cpu0_abc_rcomp0" )
			)
			( signal "A_CPU0_ABC_RCOMP1"
				( objectStatus "@baseboard_fab2_lib.baseboard_fab2(sch_1):a_cpu0_abc_rcomp1" )
			)
			( signal "A_CPU0_ABC_RCOMP2"
				( objectStatus "@baseboard_fab2_lib.baseboard_fab2(sch_1):a_cpu0_abc_rcomp2" )
			)
			( signal "A_CPU0_DEF_RCOMP0"
				( objectStatus "@baseboard_fab2_lib.baseboard_fab2(sch_1):a_cpu0_def_rcomp0" )
			)
			( signal "A_CPU0_DEF_RCOMP1"
				( objectStatus "@baseboard_fab2_lib.baseboard_fab2(sch_1):a_cpu0_def_rcomp1" )
			)
			( signal "A_CPU0_DEF_RCOMP2"
				( objectStatus "@baseboard_fab2_lib.baseboard_fab2(sch_1):a_cpu0_def_rcomp2" )
			)
			( signal "A_CPU0_MCP01_RBIAS"
				( objectStatus "@baseboard_fab2_lib.baseboard_fab2(sch_1):a_cpu0_mcp01_rbias" )
			)
			( signal "A_CPU0_PE012_RBIAS"
				( objectStatus "@baseboard_fab2_lib.baseboard_fab2(sch_1):a_cpu0_pe012_rbias" )
			)
			( signal "A_CPU0_PE3_RBIAS"
				( objectStatus "@baseboard_fab2_lib.baseboard_fab2(sch_1):a_cpu0_pe3_rbias" )
			)
			( signal "A_CPU0_UPI01_RBIAS"
				( objectStatus "@baseboard_fab2_lib.baseboard_fab2(sch_1):a_cpu0_upi01_rbias" )
			)
			( signal "A_CPU0_UPI2_RBIAS"
				( objectStatus "@baseboard_fab2_lib.baseboard_fab2(sch_1):a_cpu0_upi2_rbias" )
			)
			( signal "CLK_100M_CPU0_BCLK0_DN"
				( objectStatus "@baseboard_fab2_lib.baseboard_fab2(sch_1):clk_100m_cpu0_bclk0_dn" )
			)
			( signal "CLK_100M_CPU0_BCLK0_DP"
				( objectStatus "@baseboard_fab2_lib.baseboard_fab2(sch_1):clk_100m_cpu0_bclk0_dp" )
			)
			( signal "CLK_100M_CPU0_BCLK1_DN"
				( objectStatus "@baseboard_fab2_lib.baseboard_fab2(sch_1):clk_100m_cpu0_bclk1_dn" )
			)
			( signal "CLK_100M_CPU0_BCLK1_DP"
				( objectStatus "@baseboard_fab2_lib.baseboard_fab2(sch_1):clk_100m_cpu0_bclk1_dp" )
			)
			( signal "CLK_100M_CPU0_BCLK2_DN"
				( objectStatus "@baseboard_fab2_lib.baseboard_fab2(sch_1):clk_100m_cpu0_bclk2_dn" )
			)
			( signal "CLK_100M_CPU0_BCLK2_DP"
				( objectStatus "@baseboard_fab2_lib.baseboard_fab2(sch_1):clk_100m_cpu0_bclk2_dp" )
			)
			( signal "FM_CPU0_PKGID0"
				( objectStatus "@baseboard_fab2_lib.baseboard_fab2(sch_1):fm_cpu0_pkgid0" )
			)
			( signal "FM_CPU0_PKGID1"
				( objectStatus "@baseboard_fab2_lib.baseboard_fab2(sch_1):fm_cpu0_pkgid1" )
			)
			( signal "FM_CPU0_PKGID2"
				( objectStatus "@baseboard_fab2_lib.baseboard_fab2(sch_1):fm_cpu0_pkgid2" )
			)
			( signal "FM_CPU0_PROC_ID0"
				( objectStatus "@baseboard_fab2_lib.baseboard_fab2(sch_1):fm_cpu0_proc_id0" )
			)
			( signal "FM_CPU0_PROC_ID1"
				( objectStatus "@baseboard_fab2_lib.baseboard_fab2(sch_1):fm_cpu0_proc_id1" )
			)
			( signal "FM_CPU0_SKTOCC_LVT3_N"
				( objectStatus "@baseboard_fab2_lib.baseboard_fab2(sch_1):fm_cpu0_sktocc_lvt3_n" )
			)
			( signal "FM_CPU0_SM_WP"
				( objectStatus "@baseboard_fab2_lib.baseboard_fab2(sch_1):fm_cpu0_sm_wp" )
			)
			( signal "GND"
				( attribute "VOLTAGE" "0.0V"
					( Units "uVoltage" "V" 1.000000)
					( Status sAliasFlattened )
					( Status sAliasConflict )
					( Origin gFrontEnd )
				)
				( objectStatus "@baseboard_fab2_lib.baseboard_fab2(sch_1):gnd" )
			)
			( signal "H_CPU0_BMCINIT"
				( objectStatus "@baseboard_fab2_lib.baseboard_fab2(sch_1):h_cpu0_bmcinit" )
			)
			( signal "H_CPU0_CATERR_G_N"
				( objectStatus "@baseboard_fab2_lib.baseboard_fab2(sch_1):h_cpu0_caterr_g_n" )
			)
			( signal "H_CPU0_ERR0_G_N"
				( objectStatus "@baseboard_fab2_lib.baseboard_fab2(sch_1):h_cpu0_err0_g_n" )
			)
			( signal "H_CPU0_ERR1_G_N"
				( objectStatus "@baseboard_fab2_lib.baseboard_fab2(sch_1):h_cpu0_err1_g_n" )
			)
			( signal "H_CPU0_ERR2_G_N"
				( objectStatus "@baseboard_fab2_lib.baseboard_fab2(sch_1):h_cpu0_err2_g_n" )
			)
			( signal "H_CPU0_FAST_WAKE_N"
				( objectStatus "@baseboard_fab2_lib.baseboard_fab2(sch_1):h_cpu0_fast_wake_n" )
			)
			( signal "H_CPU0_MEMABC_MEMHOT_G_N"
				( objectStatus "@baseboard_fab2_lib.baseboard_fab2(sch_1):h_cpu0_memabc_memhot_g_n" )
			)
			( signal "H_CPU0_MEMDEF_MEMHOT_G_N"
				( objectStatus "@baseboard_fab2_lib.baseboard_fab2(sch_1):h_cpu0_memdef_memhot_g_n" )
			)
			( signal "H_CPU0_MSMI_G_N"
				( objectStatus "@baseboard_fab2_lib.baseboard_fab2(sch_1):h_cpu0_msmi_g_n" )
			)
			( signal "H_CPU0_PROCHOT_G_N"
				( objectStatus "@baseboard_fab2_lib.baseboard_fab2(sch_1):h_cpu0_prochot_g_n" )
			)
			( signal "H_CPU0_THERMTRIP_G_N"
				( objectStatus "@baseboard_fab2_lib.baseboard_fab2(sch_1):h_cpu0_thermtrip_g_n" )
			)
			( signal "H_PM_SYNC_GTL"
				( objectStatus "@baseboard_fab2_lib.baseboard_fab2(sch_1):h_pm_sync_gtl" )
			)
			( signal "H_PM_SYNC_GTL_R1"
				( objectStatus "@baseboard_fab2_lib.baseboard_fab2(sch_1):h_pm_sync_gtl_r1" )
			)
			( signal "H_PMSYNC_CLK_24M"
				( objectStatus "@baseboard_fab2_lib.baseboard_fab2(sch_1):h_pmsync_clk_24m" )
			)
			( signal "H_PMSYNC_CLK_24M_CPU0"
				( objectStatus "@baseboard_fab2_lib.baseboard_fab2(sch_1):h_pmsync_clk_24m_cpu0" )
			)
			( signal "M_A_CPU_VREF"
				( objectStatus "@baseboard_fab2_lib.baseboard_fab2(sch_1):m_a_cpu_vref" )
			)
			( signal "M_ABC_RST_N"
				( objectStatus "@baseboard_fab2_lib.baseboard_fab2(sch_1):m_abc_rst_n" )
			)
			( signal "M_B_CPU_VREF"
				( objectStatus "@baseboard_fab2_lib.baseboard_fab2(sch_1):m_b_cpu_vref" )
			)
			( signal "M_C_CPU_VREF"
				( objectStatus "@baseboard_fab2_lib.baseboard_fab2(sch_1):m_c_cpu_vref" )
			)
			( signal "M_D_CPU_VREF"
				( objectStatus "@baseboard_fab2_lib.baseboard_fab2(sch_1):m_d_cpu_vref" )
			)
			( signal "M_DEF_RST_N"
				( objectStatus "@baseboard_fab2_lib.baseboard_fab2(sch_1):m_def_rst_n" )
			)
			( signal "M_E_CPU_VREF"
				( objectStatus "@baseboard_fab2_lib.baseboard_fab2(sch_1):m_e_cpu_vref" )
			)
			( signal "M_F_CPU_VREF"
				( objectStatus "@baseboard_fab2_lib.baseboard_fab2(sch_1):m_f_cpu_vref" )
			)
			( signal "P3V3_STBY"
				( attribute "VOLTAGE" "3.3V"
					( Units "uVoltage" "V" 1.000000)
					( Status sAliasFlattened )
					( Status sAliasConflict )
					( Origin gFrontEnd )
				)
				( objectStatus "@baseboard_fab2_lib.baseboard_fab2(sch_1):p3v3_stby" )
			)
			( signal "PD_CPU0_BIST_ENABLE"
				( objectStatus "@baseboard_fab2_lib.baseboard_fab2(sch_1):pd_cpu0_bist_enable" )
			)
			( signal "PD_CPU0_KSFC_DIS"
				( objectStatus "@baseboard_fab2_lib.baseboard_fab2(sch_1):pd_cpu0_ksfc_dis" )
			)
			( signal "PD_CPU0_TEST12"
				( objectStatus "@baseboard_fab2_lib.baseboard_fab2(sch_1):pd_cpu0_test12" )
			)
			( signal "PD_CPU0_TEST13"
				( objectStatus "@baseboard_fab2_lib.baseboard_fab2(sch_1):pd_cpu0_test13" )
			)
			( signal "PD_CPU0_TEST14"
				( objectStatus "@baseboard_fab2_lib.baseboard_fab2(sch_1):pd_cpu0_test14" )
			)
			( signal "PD_CPU0_TXT_PLTEN"
				( objectStatus "@baseboard_fab2_lib.baseboard_fab2(sch_1):pd_cpu0_txt_plten" )
			)
			( signal "PD_PIROM_CPU0_ADDR0"
				( objectStatus "@baseboard_fab2_lib.baseboard_fab2(sch_1):pd_pirom_cpu0_addr0" )
			)
			( signal "PD_PIROM_CPU0_ADDR1"
				( objectStatus "@baseboard_fab2_lib.baseboard_fab2(sch_1):pd_pirom_cpu0_addr1" )
			)
			( signal "PD_PIROM_CPU0_ADDR2"
				( objectStatus "@baseboard_fab2_lib.baseboard_fab2(sch_1):pd_pirom_cpu0_addr2" )
			)
			( signal "PECI_CPU_G"
				( objectStatus "@baseboard_fab2_lib.baseboard_fab2(sch_1):peci_cpu_g" )
			)
			( signal "PU_CPU0_EAR_N"
				( objectStatus "@baseboard_fab2_lib.baseboard_fab2(sch_1):pu_cpu0_ear_n" )
			)
			( signal "PU_CPU0_FRMAGENT"
				( objectStatus "@baseboard_fab2_lib.baseboard_fab2(sch_1):pu_cpu0_frmagent" )
			)
			( signal "PU_CPU0_LEGACY_SKT"
				( objectStatus "@baseboard_fab2_lib.baseboard_fab2(sch_1):pu_cpu0_legacy_skt" )
			)
			( signal "PU_CPU0_SAFE_MODE_BOOT"
				( objectStatus "@baseboard_fab2_lib.baseboard_fab2(sch_1):pu_cpu0_safe_mode_boot" )
			)
			( signal "PU_CPU0_SOCKET_ID_0"
				( objectStatus "@baseboard_fab2_lib.baseboard_fab2(sch_1):pu_cpu0_socket_id_0" )
			)
			( signal "PU_CPU0_SOCKET_ID_1"
				( objectStatus "@baseboard_fab2_lib.baseboard_fab2(sch_1):pu_cpu0_socket_id_1" )
			)
			( signal "PU_CPU0_TSC_SYNC"
				( objectStatus "@baseboard_fab2_lib.baseboard_fab2(sch_1):pu_cpu0_tsc_sync" )
			)
			( signal "PU_CPU0_TXT_AGENT"
				( objectStatus "@baseboard_fab2_lib.baseboard_fab2(sch_1):pu_cpu0_txt_agent" )
			)
			( signal "PVCCIO_CPU0"
				( attribute "VOLTAGE" "1.1V"
					( Units "uVoltage" "V" 1.000000)
					( Status sAliasFlattened )
					( Origin gFrontEnd )
				)
				( objectStatus "@baseboard_fab2_lib.baseboard_fab2(sch_1):pvccio_cpu0" )
			)
			( signal "PWRGD_CPU0_DRAMPWROK_ABC_G"
				( objectStatus "@baseboard_fab2_lib.baseboard_fab2(sch_1):pwrgd_cpu0_drampwrok_abc_g" )
			)
			( signal "PWRGD_CPU0_DRAMPWROK_DEF_G"
				( objectStatus "@baseboard_fab2_lib.baseboard_fab2(sch_1):pwrgd_cpu0_drampwrok_def_g" )
			)
			( signal "PWRGD_CPU0_G"
				( objectStatus "@baseboard_fab2_lib.baseboard_fab2(sch_1):pwrgd_cpu0_g" )
			)
			( signal "RST_CPU0_G_N"
				( objectStatus "@baseboard_fab2_lib.baseboard_fab2(sch_1):rst_cpu0_g_n" )
			)
			( signal "SMB_DDR_ABC_SCL_G_R"
				( objectStatus "@baseboard_fab2_lib.baseboard_fab2(sch_1):smb_ddr_abc_scl_g_r" )
			)
			( signal "SMB_DDR_ABC_SDA_G_R"
				( objectStatus "@baseboard_fab2_lib.baseboard_fab2(sch_1):smb_ddr_abc_sda_g_r" )
			)
			( signal "SMB_DDR_DEF_SCL_G_R"
				( objectStatus "@baseboard_fab2_lib.baseboard_fab2(sch_1):smb_ddr_def_scl_g_r" )
			)
			( signal "SMB_DDR_DEF_SDA_G_R"
				( objectStatus "@baseboard_fab2_lib.baseboard_fab2(sch_1):smb_ddr_def_sda_g_r" )
			)
			( signal "SMB_PIROM_CPU0_SCL"
				( objectStatus "@baseboard_fab2_lib.baseboard_fab2(sch_1):smb_pirom_cpu0_scl" )
			)
			( signal "SMB_PIROM_CPU0_SDA"
				( objectStatus "@baseboard_fab2_lib.baseboard_fab2(sch_1):smb_pirom_cpu0_sda" )
			)
			( signal "SVID_ALERT0_CPU0_N"
				( objectStatus "@baseboard_fab2_lib.baseboard_fab2(sch_1):svid_alert0_cpu0_n" )
			)
			( signal "SVID_ALERT0_CPU0_R_N"
				( objectStatus "@baseboard_fab2_lib.baseboard_fab2(sch_1):svid_alert0_cpu0_r_n" )
			)
			( signal "SVID_ALERT1_CPU0_N"
				( objectStatus "@baseboard_fab2_lib.baseboard_fab2(sch_1):svid_alert1_cpu0_n" )
			)
			( signal "SVID_ALERT1_CPU0_R_N"
				( objectStatus "@baseboard_fab2_lib.baseboard_fab2(sch_1):svid_alert1_cpu0_r_n" )
			)
			( signal "SVID_CLK0_CPU0"
				( objectStatus "@baseboard_fab2_lib.baseboard_fab2(sch_1):svid_clk0_cpu0" )
			)
			( signal "SVID_CLK0_CPU0_R"
				( objectStatus "@baseboard_fab2_lib.baseboard_fab2(sch_1):svid_clk0_cpu0_r" )
			)
			( signal "SVID_CLK1_CPU0"
				( objectStatus "@baseboard_fab2_lib.baseboard_fab2(sch_1):svid_clk1_cpu0" )
			)
			( signal "SVID_CLK1_CPU0_R"
				( objectStatus "@baseboard_fab2_lib.baseboard_fab2(sch_1):svid_clk1_cpu0_r" )
			)
			( signal "SVID_DIO0_CPU0"
				( objectStatus "@baseboard_fab2_lib.baseboard_fab2(sch_1):svid_dio0_cpu0" )
			)
			( signal "SVID_DIO0_CPU0_R"
				( objectStatus "@baseboard_fab2_lib.baseboard_fab2(sch_1):svid_dio0_cpu0_r" )
			)
			( signal "SVID_DIO1_CPU0"
				( objectStatus "@baseboard_fab2_lib.baseboard_fab2(sch_1):svid_dio1_cpu0" )
			)
			( signal "SVID_DIO1_CPU0_R"
				( objectStatus "@baseboard_fab2_lib.baseboard_fab2(sch_1):svid_dio1_cpu0_r" )
			)
			( signal "TP_CPU0_PE_HP_SCL"
				( objectStatus "@baseboard_fab2_lib.baseboard_fab2(sch_1):tp_cpu0_pe_hp_scl" )
			)
			( signal "TP_CPU0_PE_HP_SDA"
				( objectStatus "@baseboard_fab2_lib.baseboard_fab2(sch_1):tp_cpu0_pe_hp_sda" )
			)
			( signal "TP_CPU0_PROCDIS_G_N"
				( objectStatus "@baseboard_fab2_lib.baseboard_fab2(sch_1):tp_cpu0_procdis_g_n" )
			)
			( signal "TP_CPU0_SOCKET_ID_2"
				( objectStatus "@baseboard_fab2_lib.baseboard_fab2(sch_1):tp_cpu0_socket_id_2" )
			)
			( signal "TP_NMI_CPU0"
				( objectStatus "@baseboard_fab2_lib.baseboard_fab2(sch_1):tp_nmi_cpu0" )
			)
			( signal "TP_XDP_CPU0_OBSDATA_A0_MBP2_N"
				( objectStatus "@baseboard_fab2_lib.baseboard_fab2(sch_1):tp_xdp_cpu0_obsdata_a0_mbp2_n" )
			)
			( signal "TP_XDP_CPU0_OBSDATA_A1_MBP3_N"
				( objectStatus "@baseboard_fab2_lib.baseboard_fab2(sch_1):tp_xdp_cpu0_obsdata_a1_mbp3_n" )
			)
			( signal "TP_XDP_CPU0_OBSDATA_A2_MBP4_N"
				( objectStatus "@baseboard_fab2_lib.baseboard_fab2(sch_1):tp_xdp_cpu0_obsdata_a2_mbp4_n" )
			)
			( signal "TP_XDP_CPU0_OBSDATA_A3_MBP5_N"
				( objectStatus "@baseboard_fab2_lib.baseboard_fab2(sch_1):tp_xdp_cpu0_obsdata_a3_mbp5_n" )
			)
			( signal "XDP_CPU0_TDO"
				( objectStatus "@baseboard_fab2_lib.baseboard_fab2(sch_1):xdp_cpu0_tdo" )
			)
			( signal "XDP_CPU_MBP0_N"
				( objectStatus "@baseboard_fab2_lib.baseboard_fab2(sch_1):xdp_cpu_mbp0_n" )
			)
			( signal "XDP_CPU_MBP1_N"
				( objectStatus "@baseboard_fab2_lib.baseboard_fab2(sch_1):xdp_cpu_mbp1_n" )
			)
			( signal "XDP_CPU_OBSFN_B0_MBP6_N"
				( objectStatus "@baseboard_fab2_lib.baseboard_fab2(sch_1):xdp_cpu_obsfn_b0_mbp6_n" )
			)
			( signal "XDP_CPU_OBSFN_B1_MBP7_N"
				( objectStatus "@baseboard_fab2_lib.baseboard_fab2(sch_1):xdp_cpu_obsfn_b1_mbp7_n" )
			)
			( signal "XDP_CPU_PRDY_N"
				( objectStatus "@baseboard_fab2_lib.baseboard_fab2(sch_1):xdp_cpu_prdy_n" )
			)
			( signal "XDP_CPU_PREQ_N"
				( objectStatus "@baseboard_fab2_lib.baseboard_fab2(sch_1):xdp_cpu_preq_n" )
			)
			( signal "XDP_CPU_TCK0"
				( objectStatus "@baseboard_fab2_lib.baseboard_fab2(sch_1):xdp_cpu_tck0" )
			)
			( signal "XDP_CPU_TDI"
				( objectStatus "@baseboard_fab2_lib.baseboard_fab2(sch_1):xdp_cpu_tdi" )
			)
			( signal "XDP_CPU_TMS"
				( objectStatus "@baseboard_fab2_lib.baseboard_fab2(sch_1):xdp_cpu_tms" )
			)
			( signal "XDP_CPU_TRST_N"
				( objectStatus "@baseboard_fab2_lib.baseboard_fab2(sch_1):xdp_cpu_trst_n" )
			)
			( signal "CLK_100M_CPU0_RC_REFCLK0_DN"
				( objectStatus "@baseboard_fab2_lib.baseboard_fab2(sch_1):clk_100m_cpu0_rc_refclk0_dn" )
			)
			( signal "CLK_100M_CPU0_RC_REFCLK0_DP"
				( objectStatus "@baseboard_fab2_lib.baseboard_fab2(sch_1):clk_100m_cpu0_rc_refclk0_dp" )
			)
			( signal "CLK_322M_OSC_CPU0_RC_DN"
				( objectStatus "@baseboard_fab2_lib.baseboard_fab2(sch_1):clk_322m_osc_cpu0_rc_dn" )
			)
			( signal "CLK_322M_OSC_CPU0_RC_DP"
				( objectStatus "@baseboard_fab2_lib.baseboard_fab2(sch_1):clk_322m_osc_cpu0_rc_dp" )
			)
			( signal "FM_CPU0_RC_ERROR_N"
				( objectStatus "@baseboard_fab2_lib.baseboard_fab2(sch_1):fm_cpu0_rc_error_n" )
			)
			( signal "H_CPU0_FIVR_FAULT_G"
				( objectStatus "@baseboard_fab2_lib.baseboard_fab2(sch_1):h_cpu0_fivr_fault_g" )
			)
			( signal "P1V8_MCP_CPU0"
				( attribute "VOLTAGE" "+1.8V"
					( Units "uVoltage" "V" 1.000000)
					( Status sAliasFlattened )
					( Origin gFrontEnd )
				)
				( objectStatus "@baseboard_fab2_lib.baseboard_fab2(sch_1):p1v8_mcp_cpu0" )
			)
			( signal "PD_CPU0_DMIMODE_OVERRIDE"
				( objectStatus "@baseboard_fab2_lib.baseboard_fab2(sch_1):pd_cpu0_dmimode_override" )
			)
			( signal "PD_CPU0_RSVD_TEST_1"
				( objectStatus "@baseboard_fab2_lib.baseboard_fab2(sch_1):pd_cpu0_rsvd_test_1" )
			)
			( signal "PD_CPU0_RSVD_TEST_2"
				( objectStatus "@baseboard_fab2_lib.baseboard_fab2(sch_1):pd_cpu0_rsvd_test_2" )
			)
			( signal "PVCCMCP_CPU0"
				( attribute "VOLTAGE" "1.2V"
					( Units "uVoltage" "V" 1.000000)
					( Status sAliasFlattened )
					( Origin gFrontEnd )
				)
				( objectStatus "@baseboard_fab2_lib.baseboard_fab2(sch_1):pvccmcp_cpu0" )
			)
			( signal "TP_CPU0_RSVD_194"
				( objectStatus "@baseboard_fab2_lib.baseboard_fab2(sch_1):tp_cpu0_rsvd_194" )
			)
			( signal "TP_CPU0_RSVD_198"
				( objectStatus "@baseboard_fab2_lib.baseboard_fab2(sch_1):tp_cpu0_rsvd_198" )
			)
			( signal "TP_CPU0_RSVD_199"
				( objectStatus "@baseboard_fab2_lib.baseboard_fab2(sch_1):tp_cpu0_rsvd_199" )
			)
			( signal "TP_CPU0_RSVD_204"
				( objectStatus "@baseboard_fab2_lib.baseboard_fab2(sch_1):tp_cpu0_rsvd_204" )
			)
			( signal "TP_CPU0_RSVD_205"
				( objectStatus "@baseboard_fab2_lib.baseboard_fab2(sch_1):tp_cpu0_rsvd_205" )
			)
			( signal "TP_CPU0_RSVD_208"
				( objectStatus "@baseboard_fab2_lib.baseboard_fab2(sch_1):tp_cpu0_rsvd_208" )
			)
			( signal "TP_CPU0_RSVD_210"
				( objectStatus "@baseboard_fab2_lib.baseboard_fab2(sch_1):tp_cpu0_rsvd_210" )
			)
			( signal "TP_CPU0_RSVD_211"
				( objectStatus "@baseboard_fab2_lib.baseboard_fab2(sch_1):tp_cpu0_rsvd_211" )
			)
			( signal "TP_CPU0_RSVD_212"
				( objectStatus "@baseboard_fab2_lib.baseboard_fab2(sch_1):tp_cpu0_rsvd_212" )
			)
			( signal "TP_CPU0_RSVD_214"
				( objectStatus "@baseboard_fab2_lib.baseboard_fab2(sch_1):tp_cpu0_rsvd_214" )
			)
			( signal "TP_CPU0_RSVD_216"
				( objectStatus "@baseboard_fab2_lib.baseboard_fab2(sch_1):tp_cpu0_rsvd_216" )
			)
			( signal "TP_CPU0_RSVD_217"
				( objectStatus "@baseboard_fab2_lib.baseboard_fab2(sch_1):tp_cpu0_rsvd_217" )
			)
			( signal "TP_CPU0_RSVD_218"
				( objectStatus "@baseboard_fab2_lib.baseboard_fab2(sch_1):tp_cpu0_rsvd_218" )
			)
			( signal "TP_CPU0_RSVD_219"
				( objectStatus "@baseboard_fab2_lib.baseboard_fab2(sch_1):tp_cpu0_rsvd_219" )
			)
			( signal "TP_CPU0_RSVD_222"
				( objectStatus "@baseboard_fab2_lib.baseboard_fab2(sch_1):tp_cpu0_rsvd_222" )
			)
			( signal "TP_CPU0_RSVD_223"
				( objectStatus "@baseboard_fab2_lib.baseboard_fab2(sch_1):tp_cpu0_rsvd_223" )
			)
			( signal "TP_CPU0_RSVD_224"
				( objectStatus "@baseboard_fab2_lib.baseboard_fab2(sch_1):tp_cpu0_rsvd_224" )
			)
			( signal "TP_CPU0_RSVD_225"
				( objectStatus "@baseboard_fab2_lib.baseboard_fab2(sch_1):tp_cpu0_rsvd_225" )
			)
			( signal "TP_CPU0_RSVD_226"
				( objectStatus "@baseboard_fab2_lib.baseboard_fab2(sch_1):tp_cpu0_rsvd_226" )
			)
			( signal "TP_CPU0_RSVD_227"
				( objectStatus "@baseboard_fab2_lib.baseboard_fab2(sch_1):tp_cpu0_rsvd_227" )
			)
			( signal "TP_CPU0_RSVD_228"
				( objectStatus "@baseboard_fab2_lib.baseboard_fab2(sch_1):tp_cpu0_rsvd_228" )
			)
			( signal "TP_CPU0_RSVD_229"
				( objectStatus "@baseboard_fab2_lib.baseboard_fab2(sch_1):tp_cpu0_rsvd_229" )
			)
			( signal "TP_CPU0_RSVD_230"
				( objectStatus "@baseboard_fab2_lib.baseboard_fab2(sch_1):tp_cpu0_rsvd_230" )
			)
			( signal "TP_CPU0_RSVD_231"
				( objectStatus "@baseboard_fab2_lib.baseboard_fab2(sch_1):tp_cpu0_rsvd_231" )
			)
			( signal "TP_CPU0_RSVD_232"
				( objectStatus "@baseboard_fab2_lib.baseboard_fab2(sch_1):tp_cpu0_rsvd_232" )
			)
			( signal "TP_CPU0_RSVD_233"
				( objectStatus "@baseboard_fab2_lib.baseboard_fab2(sch_1):tp_cpu0_rsvd_233" )
			)
			( signal "TP_CPU0_RSVD_234"
				( objectStatus "@baseboard_fab2_lib.baseboard_fab2(sch_1):tp_cpu0_rsvd_234" )
			)
			( signal "TP_CPU0_RSVD_235"
				( objectStatus "@baseboard_fab2_lib.baseboard_fab2(sch_1):tp_cpu0_rsvd_235" )
			)
			( signal "TP_CPU0_RSVD_236"
				( objectStatus "@baseboard_fab2_lib.baseboard_fab2(sch_1):tp_cpu0_rsvd_236" )
			)
			( signal "TP_CPU0_RSVD_237"
				( objectStatus "@baseboard_fab2_lib.baseboard_fab2(sch_1):tp_cpu0_rsvd_237" )
			)
			( signal "TP_CPU0_RSVD_238"
				( objectStatus "@baseboard_fab2_lib.baseboard_fab2(sch_1):tp_cpu0_rsvd_238" )
			)
			( signal "TP_CPU0_RSVD_239"
				( objectStatus "@baseboard_fab2_lib.baseboard_fab2(sch_1):tp_cpu0_rsvd_239" )
			)
			( signal "TP_CPU0_RSVD_240"
				( objectStatus "@baseboard_fab2_lib.baseboard_fab2(sch_1):tp_cpu0_rsvd_240" )
			)
			( signal "TP_CPU0_RSVD_241"
				( objectStatus "@baseboard_fab2_lib.baseboard_fab2(sch_1):tp_cpu0_rsvd_241" )
			)
			( signal "TP_CPU0_RSVD_242"
				( objectStatus "@baseboard_fab2_lib.baseboard_fab2(sch_1):tp_cpu0_rsvd_242" )
			)
			( signal "TP_CPU0_RSVD_243"
				( objectStatus "@baseboard_fab2_lib.baseboard_fab2(sch_1):tp_cpu0_rsvd_243" )
			)
			( signal "TP_CPU0_RSVD_244"
				( objectStatus "@baseboard_fab2_lib.baseboard_fab2(sch_1):tp_cpu0_rsvd_244" )
			)
			( signal "TP_CPU0_RSVD_245"
				( objectStatus "@baseboard_fab2_lib.baseboard_fab2(sch_1):tp_cpu0_rsvd_245" )
			)
			( signal "TP_CPU0_RSVD_246"
				( objectStatus "@baseboard_fab2_lib.baseboard_fab2(sch_1):tp_cpu0_rsvd_246" )
			)
			( signal "TP_CPU0_RSVD_247"
				( objectStatus "@baseboard_fab2_lib.baseboard_fab2(sch_1):tp_cpu0_rsvd_247" )
			)
			( signal "TP_CPU0_RSVD_248"
				( objectStatus "@baseboard_fab2_lib.baseboard_fab2(sch_1):tp_cpu0_rsvd_248" )
			)
			( signal "TP_CPU0_RSVD_249"
				( objectStatus "@baseboard_fab2_lib.baseboard_fab2(sch_1):tp_cpu0_rsvd_249" )
			)
			( signal "TP_CPU0_RSVD_250"
				( objectStatus "@baseboard_fab2_lib.baseboard_fab2(sch_1):tp_cpu0_rsvd_250" )
			)
			( signal "TP_CPU0_RSVD_251"
				( objectStatus "@baseboard_fab2_lib.baseboard_fab2(sch_1):tp_cpu0_rsvd_251" )
			)
			( signal "TP_CPU0_RSVD_252"
				( objectStatus "@baseboard_fab2_lib.baseboard_fab2(sch_1):tp_cpu0_rsvd_252" )
			)
			( signal "TP_CPU0_RSVD_253"
				( objectStatus "@baseboard_fab2_lib.baseboard_fab2(sch_1):tp_cpu0_rsvd_253" )
			)
			( signal "TP_CPU0_RSVD_254"
				( objectStatus "@baseboard_fab2_lib.baseboard_fab2(sch_1):tp_cpu0_rsvd_254" )
			)
			( signal "TP_CPU0_RSVD_256"
				( objectStatus "@baseboard_fab2_lib.baseboard_fab2(sch_1):tp_cpu0_rsvd_256" )
			)
			( signal "TP_CPU0_RSVD_258"
				( objectStatus "@baseboard_fab2_lib.baseboard_fab2(sch_1):tp_cpu0_rsvd_258" )
			)
			( signal "TP_CPU0_RSVD_259"
				( objectStatus "@baseboard_fab2_lib.baseboard_fab2(sch_1):tp_cpu0_rsvd_259" )
			)
			( signal "TP_CPU0_RSVD_260"
				( objectStatus "@baseboard_fab2_lib.baseboard_fab2(sch_1):tp_cpu0_rsvd_260" )
			)
			( signal "TP_CPU0_RSVD_261"
				( objectStatus "@baseboard_fab2_lib.baseboard_fab2(sch_1):tp_cpu0_rsvd_261" )
			)
			( signal "TP_CPU0_RSVD_262"
				( objectStatus "@baseboard_fab2_lib.baseboard_fab2(sch_1):tp_cpu0_rsvd_262" )
			)
			( signal "TP_CPU0_RSVD_263"
				( objectStatus "@baseboard_fab2_lib.baseboard_fab2(sch_1):tp_cpu0_rsvd_263" )
			)
			( signal "TP_CPU0_RSVD_264"
				( objectStatus "@baseboard_fab2_lib.baseboard_fab2(sch_1):tp_cpu0_rsvd_264" )
			)
			( signal "TP_CPU0_RSVD_265"
				( objectStatus "@baseboard_fab2_lib.baseboard_fab2(sch_1):tp_cpu0_rsvd_265" )
			)
			( signal "TP_CPU0_RSVD_266"
				( objectStatus "@baseboard_fab2_lib.baseboard_fab2(sch_1):tp_cpu0_rsvd_266" )
			)
			( signal "TP_CPU0_RSVD_267"
				( objectStatus "@baseboard_fab2_lib.baseboard_fab2(sch_1):tp_cpu0_rsvd_267" )
			)
			( signal "TP_CPU0_RSVD_268"
				( objectStatus "@baseboard_fab2_lib.baseboard_fab2(sch_1):tp_cpu0_rsvd_268" )
			)
			( signal "TP_CPU0_RSVD_269"
				( objectStatus "@baseboard_fab2_lib.baseboard_fab2(sch_1):tp_cpu0_rsvd_269" )
			)
			( signal "TP_CPU0_RSVD_270"
				( objectStatus "@baseboard_fab2_lib.baseboard_fab2(sch_1):tp_cpu0_rsvd_270" )
			)
			( signal "TP_CPU0_RSVD_271"
				( objectStatus "@baseboard_fab2_lib.baseboard_fab2(sch_1):tp_cpu0_rsvd_271" )
			)
			( signal "TP_CPU0_RSVD_272"
				( objectStatus "@baseboard_fab2_lib.baseboard_fab2(sch_1):tp_cpu0_rsvd_272" )
			)
			( signal "TP_CPU0_RSVD_273"
				( objectStatus "@baseboard_fab2_lib.baseboard_fab2(sch_1):tp_cpu0_rsvd_273" )
			)
			( signal "TP_CPU0_RSVD_274"
				( objectStatus "@baseboard_fab2_lib.baseboard_fab2(sch_1):tp_cpu0_rsvd_274" )
			)
			( signal "TP_CPU0_RSVD_275"
				( objectStatus "@baseboard_fab2_lib.baseboard_fab2(sch_1):tp_cpu0_rsvd_275" )
			)
			( signal "TP_CPU0_RSVD_276"
				( objectStatus "@baseboard_fab2_lib.baseboard_fab2(sch_1):tp_cpu0_rsvd_276" )
			)
			( signal "TP_CPU0_RSVD_277"
				( objectStatus "@baseboard_fab2_lib.baseboard_fab2(sch_1):tp_cpu0_rsvd_277" )
			)
			( signal "TP_CPU0_RSVD_278"
				( objectStatus "@baseboard_fab2_lib.baseboard_fab2(sch_1):tp_cpu0_rsvd_278" )
			)
			( signal "TP_CPU0_RSVD_279"
				( objectStatus "@baseboard_fab2_lib.baseboard_fab2(sch_1):tp_cpu0_rsvd_279" )
			)
			( signal "TP_CPU0_RSVD_280"
				( objectStatus "@baseboard_fab2_lib.baseboard_fab2(sch_1):tp_cpu0_rsvd_280" )
			)
			( signal "TP_CPU0_RSVD_281"
				( objectStatus "@baseboard_fab2_lib.baseboard_fab2(sch_1):tp_cpu0_rsvd_281" )
			)
			( signal "TP_CPU0_RSVD_282"
				( objectStatus "@baseboard_fab2_lib.baseboard_fab2(sch_1):tp_cpu0_rsvd_282" )
			)
			( signal "TP_CPU0_RSVD_283"
				( objectStatus "@baseboard_fab2_lib.baseboard_fab2(sch_1):tp_cpu0_rsvd_283" )
			)
			( signal "TP_CPU0_RSVD_284"
				( objectStatus "@baseboard_fab2_lib.baseboard_fab2(sch_1):tp_cpu0_rsvd_284" )
			)
			( signal "TP_CPU0_RSVD_285"
				( objectStatus "@baseboard_fab2_lib.baseboard_fab2(sch_1):tp_cpu0_rsvd_285" )
			)
			( signal "TP_CPU0_RSVD_286"
				( objectStatus "@baseboard_fab2_lib.baseboard_fab2(sch_1):tp_cpu0_rsvd_286" )
			)
			( signal "TP_CPU0_RSVD_287"
				( objectStatus "@baseboard_fab2_lib.baseboard_fab2(sch_1):tp_cpu0_rsvd_287" )
			)
			( signal "TP_CPU0_RSVD_288"
				( objectStatus "@baseboard_fab2_lib.baseboard_fab2(sch_1):tp_cpu0_rsvd_288" )
			)
			( signal "TP_CPU0_RSVD_289"
				( objectStatus "@baseboard_fab2_lib.baseboard_fab2(sch_1):tp_cpu0_rsvd_289" )
			)
			( signal "TP_CPU0_RSVD_290"
				( objectStatus "@baseboard_fab2_lib.baseboard_fab2(sch_1):tp_cpu0_rsvd_290" )
			)
			( signal "TP_CPU0_RSVD_291"
				( objectStatus "@baseboard_fab2_lib.baseboard_fab2(sch_1):tp_cpu0_rsvd_291" )
			)
			( signal "TP_CPU0_RSVD_292"
				( objectStatus "@baseboard_fab2_lib.baseboard_fab2(sch_1):tp_cpu0_rsvd_292" )
			)
			( signal "TP_CPU0_RSVD_293"
				( objectStatus "@baseboard_fab2_lib.baseboard_fab2(sch_1):tp_cpu0_rsvd_293" )
			)
			( signal "TP_CPU0_RSVD_298"
				( objectStatus "@baseboard_fab2_lib.baseboard_fab2(sch_1):tp_cpu0_rsvd_298" )
			)
			( signal "TP_CPU0_RSVD_299"
				( objectStatus "@baseboard_fab2_lib.baseboard_fab2(sch_1):tp_cpu0_rsvd_299" )
			)
			( signal "TP_CPU0_RSVD_300"
				( objectStatus "@baseboard_fab2_lib.baseboard_fab2(sch_1):tp_cpu0_rsvd_300" )
			)
			( signal "TP_CPU0_RSVD_303"
				( objectStatus "@baseboard_fab2_lib.baseboard_fab2(sch_1):tp_cpu0_rsvd_303" )
			)
			( signal "TP_CPU0_RSVD_304"
				( objectStatus "@baseboard_fab2_lib.baseboard_fab2(sch_1):tp_cpu0_rsvd_304" )
			)
			( signal "TP_CPU0_RSVD_TEST_11"
				( objectStatus "@baseboard_fab2_lib.baseboard_fab2(sch_1):tp_cpu0_rsvd_test_11" )
			)
			( signal "TP_CPU0_RSVD_TEST_3"
				( objectStatus "@baseboard_fab2_lib.baseboard_fab2(sch_1):tp_cpu0_rsvd_test_3" )
			)
			( signal "TP_CPU0_RSVD_TEST_4"
				( objectStatus "@baseboard_fab2_lib.baseboard_fab2(sch_1):tp_cpu0_rsvd_test_4" )
			)
			( signal "TP_CPU0_RSVD_TEST_5"
				( objectStatus "@baseboard_fab2_lib.baseboard_fab2(sch_1):tp_cpu0_rsvd_test_5" )
			)
			( signal "VSENSE_P1V8MCP_CPU0_SKT_VRTN"
				( objectStatus "@baseboard_fab2_lib.baseboard_fab2(sch_1):vsense_p1v8mcp_cpu0_skt_vrtn" )
			)
			( signal "VSENSE_P1V8MCP_CPU0_SKT_VSEN"
				( objectStatus "@baseboard_fab2_lib.baseboard_fab2(sch_1):vsense_p1v8mcp_cpu0_skt_vsen" )
			)
			( signal "XDP_CPU_PWR_DEBUG_N"
				( objectStatus "@baseboard_fab2_lib.baseboard_fab2(sch_1):xdp_cpu_pwr_debug_n" )
			)
			( signal "XDP_PRESENT_N"
				( objectStatus "@baseboard_fab2_lib.baseboard_fab2(sch_1):xdp_present_n" )
			)
			( signal "M_A_ACT_N"
				( objectStatus "@baseboard_fab2_lib.baseboard_fab2(sch_1):m_a_act_n" )
			)
			( signal "M_A_ALERT_N"
				( objectStatus "@baseboard_fab2_lib.baseboard_fab2(sch_1):m_a_alert_n" )
			)
			( signal "M_A_BA<0>"
				( objectStatus "@baseboard_fab2_lib.baseboard_fab2(sch_1):m_a_ba(0)" )
			)
			( signal "M_A_BA<1>"
				( objectStatus "@baseboard_fab2_lib.baseboard_fab2(sch_1):m_a_ba(1)" )
			)
			( signal "M_A_BG<0>"
				( objectStatus "@baseboard_fab2_lib.baseboard_fab2(sch_1):m_a_bg(0)" )
			)
			( signal "M_A_BG<1>"
				( objectStatus "@baseboard_fab2_lib.baseboard_fab2(sch_1):m_a_bg(1)" )
			)
			( signal "M_A_C<2>"
				( objectStatus "@baseboard_fab2_lib.baseboard_fab2(sch_1):m_a_c(2)" )
			)
			( signal "M_A_CKE<0>"
				( objectStatus "@baseboard_fab2_lib.baseboard_fab2(sch_1):m_a_cke(0)" )
			)
			( signal "M_A_CKE<1>"
				( objectStatus "@baseboard_fab2_lib.baseboard_fab2(sch_1):m_a_cke(1)" )
			)
			( signal "M_A_CKE<2>"
				( objectStatus "@baseboard_fab2_lib.baseboard_fab2(sch_1):m_a_cke(2)" )
			)
			( signal "M_A_CKE<3>"
				( objectStatus "@baseboard_fab2_lib.baseboard_fab2(sch_1):m_a_cke(3)" )
			)
			( signal "M_A_CLK_DN<0>"
				( objectStatus "@baseboard_fab2_lib.baseboard_fab2(sch_1):m_a_clk_dn(0)" )
			)
			( signal "M_A_CLK_DN<1>"
				( objectStatus "@baseboard_fab2_lib.baseboard_fab2(sch_1):m_a_clk_dn(1)" )
			)
			( signal "M_A_CLK_DN<2>"
				( objectStatus "@baseboard_fab2_lib.baseboard_fab2(sch_1):m_a_clk_dn(2)" )
			)
			( signal "M_A_CLK_DN<3>"
				( objectStatus "@baseboard_fab2_lib.baseboard_fab2(sch_1):m_a_clk_dn(3)" )
			)
			( signal "M_A_CLK_DP<0>"
				( objectStatus "@baseboard_fab2_lib.baseboard_fab2(sch_1):m_a_clk_dp(0)" )
			)
			( signal "M_A_CLK_DP<1>"
				( objectStatus "@baseboard_fab2_lib.baseboard_fab2(sch_1):m_a_clk_dp(1)" )
			)
			( signal "M_A_CLK_DP<2>"
				( objectStatus "@baseboard_fab2_lib.baseboard_fab2(sch_1):m_a_clk_dp(2)" )
			)
			( signal "M_A_CLK_DP<3>"
				( objectStatus "@baseboard_fab2_lib.baseboard_fab2(sch_1):m_a_clk_dp(3)" )
			)
			( signal "M_A_CS_N<0>"
				( objectStatus "@baseboard_fab2_lib.baseboard_fab2(sch_1):m_a_cs_n(0)" )
			)
			( signal "M_A_CS_N<1>"
				( objectStatus "@baseboard_fab2_lib.baseboard_fab2(sch_1):m_a_cs_n(1)" )
			)
			( signal "M_A_CS_N<2>"
				( objectStatus "@baseboard_fab2_lib.baseboard_fab2(sch_1):m_a_cs_n(2)" )
			)
			( signal "M_A_CS_N<3>"
				( objectStatus "@baseboard_fab2_lib.baseboard_fab2(sch_1):m_a_cs_n(3)" )
			)
			( signal "M_A_CS_N<4>"
				( objectStatus "@baseboard_fab2_lib.baseboard_fab2(sch_1):m_a_cs_n(4)" )
			)
			( signal "M_A_CS_N<5>"
				( objectStatus "@baseboard_fab2_lib.baseboard_fab2(sch_1):m_a_cs_n(5)" )
			)
			( signal "M_A_CS_N<6>"
				( objectStatus "@baseboard_fab2_lib.baseboard_fab2(sch_1):m_a_cs_n(6)" )
			)
			( signal "M_A_CS_N<7>"
				( objectStatus "@baseboard_fab2_lib.baseboard_fab2(sch_1):m_a_cs_n(7)" )
			)
			( signal "M_A_DQ<0>"
				( objectStatus "@baseboard_fab2_lib.baseboard_fab2(sch_1):m_a_dq(0)" )
			)
			( signal "M_A_DQ<1>"
				( objectStatus "@baseboard_fab2_lib.baseboard_fab2(sch_1):m_a_dq(1)" )
			)
			( signal "M_A_DQ<2>"
				( objectStatus "@baseboard_fab2_lib.baseboard_fab2(sch_1):m_a_dq(2)" )
			)
			( signal "M_A_DQ<3>"
				( objectStatus "@baseboard_fab2_lib.baseboard_fab2(sch_1):m_a_dq(3)" )
			)
			( signal "M_A_DQ<4>"
				( objectStatus "@baseboard_fab2_lib.baseboard_fab2(sch_1):m_a_dq(4)" )
			)
			( signal "M_A_DQ<5>"
				( objectStatus "@baseboard_fab2_lib.baseboard_fab2(sch_1):m_a_dq(5)" )
			)
			( signal "M_A_DQ<6>"
				( objectStatus "@baseboard_fab2_lib.baseboard_fab2(sch_1):m_a_dq(6)" )
			)
			( signal "M_A_DQ<7>"
				( objectStatus "@baseboard_fab2_lib.baseboard_fab2(sch_1):m_a_dq(7)" )
			)
			( signal "M_A_DQ<8>"
				( objectStatus "@baseboard_fab2_lib.baseboard_fab2(sch_1):m_a_dq(8)" )
			)
			( signal "M_A_DQ<9>"
				( objectStatus "@baseboard_fab2_lib.baseboard_fab2(sch_1):m_a_dq(9)" )
			)
			( signal "M_A_DQ<10>"
				( objectStatus "@baseboard_fab2_lib.baseboard_fab2(sch_1):m_a_dq(10)" )
			)
			( signal "M_A_DQ<11>"
				( objectStatus "@baseboard_fab2_lib.baseboard_fab2(sch_1):m_a_dq(11)" )
			)
			( signal "M_A_DQ<12>"
				( objectStatus "@baseboard_fab2_lib.baseboard_fab2(sch_1):m_a_dq(12)" )
			)
			( signal "M_A_DQ<13>"
				( objectStatus "@baseboard_fab2_lib.baseboard_fab2(sch_1):m_a_dq(13)" )
			)
			( signal "M_A_DQ<14>"
				( objectStatus "@baseboard_fab2_lib.baseboard_fab2(sch_1):m_a_dq(14)" )
			)
			( signal "M_A_DQ<15>"
				( objectStatus "@baseboard_fab2_lib.baseboard_fab2(sch_1):m_a_dq(15)" )
			)
			( signal "M_A_DQ<16>"
				( objectStatus "@baseboard_fab2_lib.baseboard_fab2(sch_1):m_a_dq(16)" )
			)
			( signal "M_A_DQ<17>"
				( objectStatus "@baseboard_fab2_lib.baseboard_fab2(sch_1):m_a_dq(17)" )
			)
			( signal "M_A_DQ<18>"
				( objectStatus "@baseboard_fab2_lib.baseboard_fab2(sch_1):m_a_dq(18)" )
			)
			( signal "M_A_DQ<19>"
				( objectStatus "@baseboard_fab2_lib.baseboard_fab2(sch_1):m_a_dq(19)" )
			)
			( signal "M_A_DQ<20>"
				( objectStatus "@baseboard_fab2_lib.baseboard_fab2(sch_1):m_a_dq(20)" )
			)
			( signal "M_A_DQ<21>"
				( objectStatus "@baseboard_fab2_lib.baseboard_fab2(sch_1):m_a_dq(21)" )
			)
			( signal "M_A_DQ<22>"
				( objectStatus "@baseboard_fab2_lib.baseboard_fab2(sch_1):m_a_dq(22)" )
			)
			( signal "M_A_DQ<23>"
				( objectStatus "@baseboard_fab2_lib.baseboard_fab2(sch_1):m_a_dq(23)" )
			)
			( signal "M_A_DQ<24>"
				( objectStatus "@baseboard_fab2_lib.baseboard_fab2(sch_1):m_a_dq(24)" )
			)
			( signal "M_A_DQ<25>"
				( objectStatus "@baseboard_fab2_lib.baseboard_fab2(sch_1):m_a_dq(25)" )
			)
			( signal "M_A_DQ<26>"
				( objectStatus "@baseboard_fab2_lib.baseboard_fab2(sch_1):m_a_dq(26)" )
			)
			( signal "M_A_DQ<27>"
				( objectStatus "@baseboard_fab2_lib.baseboard_fab2(sch_1):m_a_dq(27)" )
			)
			( signal "M_A_DQ<28>"
				( objectStatus "@baseboard_fab2_lib.baseboard_fab2(sch_1):m_a_dq(28)" )
			)
			( signal "M_A_DQ<29>"
				( objectStatus "@baseboard_fab2_lib.baseboard_fab2(sch_1):m_a_dq(29)" )
			)
			( signal "M_A_DQ<30>"
				( objectStatus "@baseboard_fab2_lib.baseboard_fab2(sch_1):m_a_dq(30)" )
			)
			( signal "M_A_DQ<31>"
				( objectStatus "@baseboard_fab2_lib.baseboard_fab2(sch_1):m_a_dq(31)" )
			)
			( signal "M_A_DQ<32>"
				( objectStatus "@baseboard_fab2_lib.baseboard_fab2(sch_1):m_a_dq(32)" )
			)
			( signal "M_A_DQ<33>"
				( objectStatus "@baseboard_fab2_lib.baseboard_fab2(sch_1):m_a_dq(33)" )
			)
			( signal "M_A_DQ<34>"
				( objectStatus "@baseboard_fab2_lib.baseboard_fab2(sch_1):m_a_dq(34)" )
			)
			( signal "M_A_DQ<35>"
				( objectStatus "@baseboard_fab2_lib.baseboard_fab2(sch_1):m_a_dq(35)" )
			)
			( signal "M_A_DQ<36>"
				( objectStatus "@baseboard_fab2_lib.baseboard_fab2(sch_1):m_a_dq(36)" )
			)
			( signal "M_A_DQ<37>"
				( objectStatus "@baseboard_fab2_lib.baseboard_fab2(sch_1):m_a_dq(37)" )
			)
			( signal "M_A_DQ<38>"
				( objectStatus "@baseboard_fab2_lib.baseboard_fab2(sch_1):m_a_dq(38)" )
			)
			( signal "M_A_DQ<39>"
				( objectStatus "@baseboard_fab2_lib.baseboard_fab2(sch_1):m_a_dq(39)" )
			)
			( signal "M_A_DQ<40>"
				( objectStatus "@baseboard_fab2_lib.baseboard_fab2(sch_1):m_a_dq(40)" )
			)
			( signal "M_A_DQ<41>"
				( objectStatus "@baseboard_fab2_lib.baseboard_fab2(sch_1):m_a_dq(41)" )
			)
			( signal "M_A_DQ<42>"
				( objectStatus "@baseboard_fab2_lib.baseboard_fab2(sch_1):m_a_dq(42)" )
			)
			( signal "M_A_DQ<43>"
				( objectStatus "@baseboard_fab2_lib.baseboard_fab2(sch_1):m_a_dq(43)" )
			)
			( signal "M_A_DQ<44>"
				( objectStatus "@baseboard_fab2_lib.baseboard_fab2(sch_1):m_a_dq(44)" )
			)
			( signal "M_A_DQ<45>"
				( objectStatus "@baseboard_fab2_lib.baseboard_fab2(sch_1):m_a_dq(45)" )
			)
			( signal "M_A_DQ<46>"
				( objectStatus "@baseboard_fab2_lib.baseboard_fab2(sch_1):m_a_dq(46)" )
			)
			( signal "M_A_DQ<47>"
				( objectStatus "@baseboard_fab2_lib.baseboard_fab2(sch_1):m_a_dq(47)" )
			)
			( signal "M_A_DQ<48>"
				( objectStatus "@baseboard_fab2_lib.baseboard_fab2(sch_1):m_a_dq(48)" )
			)
			( signal "M_A_DQ<49>"
				( objectStatus "@baseboard_fab2_lib.baseboard_fab2(sch_1):m_a_dq(49)" )
			)
			( signal "M_A_DQ<50>"
				( objectStatus "@baseboard_fab2_lib.baseboard_fab2(sch_1):m_a_dq(50)" )
			)
			( signal "M_A_DQ<51>"
				( objectStatus "@baseboard_fab2_lib.baseboard_fab2(sch_1):m_a_dq(51)" )
			)
			( signal "M_A_DQ<52>"
				( objectStatus "@baseboard_fab2_lib.baseboard_fab2(sch_1):m_a_dq(52)" )
			)
			( signal "M_A_DQ<53>"
				( objectStatus "@baseboard_fab2_lib.baseboard_fab2(sch_1):m_a_dq(53)" )
			)
			( signal "M_A_DQ<54>"
				( objectStatus "@baseboard_fab2_lib.baseboard_fab2(sch_1):m_a_dq(54)" )
			)
			( signal "M_A_DQ<55>"
				( objectStatus "@baseboard_fab2_lib.baseboard_fab2(sch_1):m_a_dq(55)" )
			)
			( signal "M_A_DQ<56>"
				( objectStatus "@baseboard_fab2_lib.baseboard_fab2(sch_1):m_a_dq(56)" )
			)
			( signal "M_A_DQ<57>"
				( objectStatus "@baseboard_fab2_lib.baseboard_fab2(sch_1):m_a_dq(57)" )
			)
			( signal "M_A_DQ<58>"
				( objectStatus "@baseboard_fab2_lib.baseboard_fab2(sch_1):m_a_dq(58)" )
			)
			( signal "M_A_DQ<59>"
				( objectStatus "@baseboard_fab2_lib.baseboard_fab2(sch_1):m_a_dq(59)" )
			)
			( signal "M_A_DQ<60>"
				( objectStatus "@baseboard_fab2_lib.baseboard_fab2(sch_1):m_a_dq(60)" )
			)
			( signal "M_A_DQ<61>"
				( objectStatus "@baseboard_fab2_lib.baseboard_fab2(sch_1):m_a_dq(61)" )
			)
			( signal "M_A_DQ<62>"
				( objectStatus "@baseboard_fab2_lib.baseboard_fab2(sch_1):m_a_dq(62)" )
			)
			( signal "M_A_DQ<63>"
				( objectStatus "@baseboard_fab2_lib.baseboard_fab2(sch_1):m_a_dq(63)" )
			)
			( signal "M_A_DQS_DN<0>"
				( objectStatus "@baseboard_fab2_lib.baseboard_fab2(sch_1):m_a_dqs_dn(0)" )
			)
			( signal "M_A_DQS_DN<1>"
				( objectStatus "@baseboard_fab2_lib.baseboard_fab2(sch_1):m_a_dqs_dn(1)" )
			)
			( signal "M_A_DQS_DN<2>"
				( objectStatus "@baseboard_fab2_lib.baseboard_fab2(sch_1):m_a_dqs_dn(2)" )
			)
			( signal "M_A_DQS_DN<3>"
				( objectStatus "@baseboard_fab2_lib.baseboard_fab2(sch_1):m_a_dqs_dn(3)" )
			)
			( signal "M_A_DQS_DN<4>"
				( objectStatus "@baseboard_fab2_lib.baseboard_fab2(sch_1):m_a_dqs_dn(4)" )
			)
			( signal "M_A_DQS_DN<5>"
				( objectStatus "@baseboard_fab2_lib.baseboard_fab2(sch_1):m_a_dqs_dn(5)" )
			)
			( signal "M_A_DQS_DN<6>"
				( objectStatus "@baseboard_fab2_lib.baseboard_fab2(sch_1):m_a_dqs_dn(6)" )
			)
			( signal "M_A_DQS_DN<7>"
				( objectStatus "@baseboard_fab2_lib.baseboard_fab2(sch_1):m_a_dqs_dn(7)" )
			)
			( signal "M_A_DQS_DN<8>"
				( objectStatus "@baseboard_fab2_lib.baseboard_fab2(sch_1):m_a_dqs_dn(8)" )
			)
			( signal "M_A_DQS_DN<9>"
				( objectStatus "@baseboard_fab2_lib.baseboard_fab2(sch_1):m_a_dqs_dn(9)" )
			)
			( signal "M_A_DQS_DN<10>"
				( objectStatus "@baseboard_fab2_lib.baseboard_fab2(sch_1):m_a_dqs_dn(10)" )
			)
			( signal "M_A_DQS_DN<11>"
				( objectStatus "@baseboard_fab2_lib.baseboard_fab2(sch_1):m_a_dqs_dn(11)" )
			)
			( signal "M_A_DQS_DN<12>"
				( objectStatus "@baseboard_fab2_lib.baseboard_fab2(sch_1):m_a_dqs_dn(12)" )
			)
			( signal "M_A_DQS_DN<13>"
				( objectStatus "@baseboard_fab2_lib.baseboard_fab2(sch_1):m_a_dqs_dn(13)" )
			)
			( signal "M_A_DQS_DN<14>"
				( objectStatus "@baseboard_fab2_lib.baseboard_fab2(sch_1):m_a_dqs_dn(14)" )
			)
			( signal "M_A_DQS_DN<15>"
				( objectStatus "@baseboard_fab2_lib.baseboard_fab2(sch_1):m_a_dqs_dn(15)" )
			)
			( signal "M_A_DQS_DN<16>"
				( objectStatus "@baseboard_fab2_lib.baseboard_fab2(sch_1):m_a_dqs_dn(16)" )
			)
			( signal "M_A_DQS_DN<17>"
				( objectStatus "@baseboard_fab2_lib.baseboard_fab2(sch_1):m_a_dqs_dn(17)" )
			)
			( signal "M_A_DQS_DP<0>"
				( objectStatus "@baseboard_fab2_lib.baseboard_fab2(sch_1):m_a_dqs_dp(0)" )
			)
			( signal "M_A_DQS_DP<1>"
				( objectStatus "@baseboard_fab2_lib.baseboard_fab2(sch_1):m_a_dqs_dp(1)" )
			)
			( signal "M_A_DQS_DP<2>"
				( objectStatus "@baseboard_fab2_lib.baseboard_fab2(sch_1):m_a_dqs_dp(2)" )
			)
			( signal "M_A_DQS_DP<3>"
				( objectStatus "@baseboard_fab2_lib.baseboard_fab2(sch_1):m_a_dqs_dp(3)" )
			)
			( signal "M_A_DQS_DP<4>"
				( objectStatus "@baseboard_fab2_lib.baseboard_fab2(sch_1):m_a_dqs_dp(4)" )
			)
			( signal "M_A_DQS_DP<5>"
				( objectStatus "@baseboard_fab2_lib.baseboard_fab2(sch_1):m_a_dqs_dp(5)" )
			)
			( signal "M_A_DQS_DP<6>"
				( objectStatus "@baseboard_fab2_lib.baseboard_fab2(sch_1):m_a_dqs_dp(6)" )
			)
			( signal "M_A_DQS_DP<7>"
				( objectStatus "@baseboard_fab2_lib.baseboard_fab2(sch_1):m_a_dqs_dp(7)" )
			)
			( signal "M_A_DQS_DP<8>"
				( objectStatus "@baseboard_fab2_lib.baseboard_fab2(sch_1):m_a_dqs_dp(8)" )
			)
			( signal "M_A_DQS_DP<9>"
				( objectStatus "@baseboard_fab2_lib.baseboard_fab2(sch_1):m_a_dqs_dp(9)" )
			)
			( signal "M_A_DQS_DP<10>"
				( objectStatus "@baseboard_fab2_lib.baseboard_fab2(sch_1):m_a_dqs_dp(10)" )
			)
			( signal "M_A_DQS_DP<11>"
				( objectStatus "@baseboard_fab2_lib.baseboard_fab2(sch_1):m_a_dqs_dp(11)" )
			)
			( signal "M_A_DQS_DP<12>"
				( objectStatus "@baseboard_fab2_lib.baseboard_fab2(sch_1):m_a_dqs_dp(12)" )
			)
			( signal "M_A_DQS_DP<13>"
				( objectStatus "@baseboard_fab2_lib.baseboard_fab2(sch_1):m_a_dqs_dp(13)" )
			)
			( signal "M_A_DQS_DP<14>"
				( objectStatus "@baseboard_fab2_lib.baseboard_fab2(sch_1):m_a_dqs_dp(14)" )
			)
			( signal "M_A_DQS_DP<15>"
				( objectStatus "@baseboard_fab2_lib.baseboard_fab2(sch_1):m_a_dqs_dp(15)" )
			)
			( signal "M_A_DQS_DP<16>"
				( objectStatus "@baseboard_fab2_lib.baseboard_fab2(sch_1):m_a_dqs_dp(16)" )
			)
			( signal "M_A_DQS_DP<17>"
				( objectStatus "@baseboard_fab2_lib.baseboard_fab2(sch_1):m_a_dqs_dp(17)" )
			)
			( signal "M_A_ECC<0>"
				( objectStatus "@baseboard_fab2_lib.baseboard_fab2(sch_1):m_a_ecc(0)" )
			)
			( signal "M_A_ECC<1>"
				( objectStatus "@baseboard_fab2_lib.baseboard_fab2(sch_1):m_a_ecc(1)" )
			)
			( signal "M_A_ECC<2>"
				( objectStatus "@baseboard_fab2_lib.baseboard_fab2(sch_1):m_a_ecc(2)" )
			)
			( signal "M_A_ECC<3>"
				( objectStatus "@baseboard_fab2_lib.baseboard_fab2(sch_1):m_a_ecc(3)" )
			)
			( signal "M_A_ECC<4>"
				( objectStatus "@baseboard_fab2_lib.baseboard_fab2(sch_1):m_a_ecc(4)" )
			)
			( signal "M_A_ECC<5>"
				( objectStatus "@baseboard_fab2_lib.baseboard_fab2(sch_1):m_a_ecc(5)" )
			)
			( signal "M_A_ECC<6>"
				( objectStatus "@baseboard_fab2_lib.baseboard_fab2(sch_1):m_a_ecc(6)" )
			)
			( signal "M_A_ECC<7>"
				( objectStatus "@baseboard_fab2_lib.baseboard_fab2(sch_1):m_a_ecc(7)" )
			)
			( signal "M_A_MA<0>"
				( objectStatus "@baseboard_fab2_lib.baseboard_fab2(sch_1):m_a_ma(0)" )
			)
			( signal "M_A_MA<1>"
				( objectStatus "@baseboard_fab2_lib.baseboard_fab2(sch_1):m_a_ma(1)" )
			)
			( signal "M_A_MA<2>"
				( objectStatus "@baseboard_fab2_lib.baseboard_fab2(sch_1):m_a_ma(2)" )
			)
			( signal "M_A_MA<3>"
				( objectStatus "@baseboard_fab2_lib.baseboard_fab2(sch_1):m_a_ma(3)" )
			)
			( signal "M_A_MA<4>"
				( objectStatus "@baseboard_fab2_lib.baseboard_fab2(sch_1):m_a_ma(4)" )
			)
			( signal "M_A_MA<5>"
				( objectStatus "@baseboard_fab2_lib.baseboard_fab2(sch_1):m_a_ma(5)" )
			)
			( signal "M_A_MA<6>"
				( objectStatus "@baseboard_fab2_lib.baseboard_fab2(sch_1):m_a_ma(6)" )
			)
			( signal "M_A_MA<7>"
				( objectStatus "@baseboard_fab2_lib.baseboard_fab2(sch_1):m_a_ma(7)" )
			)
			( signal "M_A_MA<8>"
				( objectStatus "@baseboard_fab2_lib.baseboard_fab2(sch_1):m_a_ma(8)" )
			)
			( signal "M_A_MA<9>"
				( objectStatus "@baseboard_fab2_lib.baseboard_fab2(sch_1):m_a_ma(9)" )
			)
			( signal "M_A_MA<10>"
				( objectStatus "@baseboard_fab2_lib.baseboard_fab2(sch_1):m_a_ma(10)" )
			)
			( signal "M_A_MA<11>"
				( objectStatus "@baseboard_fab2_lib.baseboard_fab2(sch_1):m_a_ma(11)" )
			)
			( signal "M_A_MA<12>"
				( objectStatus "@baseboard_fab2_lib.baseboard_fab2(sch_1):m_a_ma(12)" )
			)
			( signal "M_A_MA<13>"
				( objectStatus "@baseboard_fab2_lib.baseboard_fab2(sch_1):m_a_ma(13)" )
			)
			( signal "M_A_MA<14>"
				( objectStatus "@baseboard_fab2_lib.baseboard_fab2(sch_1):m_a_ma(14)" )
			)
			( signal "M_A_MA<15>"
				( objectStatus "@baseboard_fab2_lib.baseboard_fab2(sch_1):m_a_ma(15)" )
			)
			( signal "M_A_MA<16>"
				( objectStatus "@baseboard_fab2_lib.baseboard_fab2(sch_1):m_a_ma(16)" )
			)
			( signal "M_A_MA<17>"
				( objectStatus "@baseboard_fab2_lib.baseboard_fab2(sch_1):m_a_ma(17)" )
			)
			( signal "M_A_ODT<0>"
				( objectStatus "@baseboard_fab2_lib.baseboard_fab2(sch_1):m_a_odt(0)" )
			)
			( signal "M_A_ODT<1>"
				( objectStatus "@baseboard_fab2_lib.baseboard_fab2(sch_1):m_a_odt(1)" )
			)
			( signal "M_A_ODT<2>"
				( objectStatus "@baseboard_fab2_lib.baseboard_fab2(sch_1):m_a_odt(2)" )
			)
			( signal "M_A_ODT<3>"
				( objectStatus "@baseboard_fab2_lib.baseboard_fab2(sch_1):m_a_odt(3)" )
			)
			( signal "M_A_PAR"
				( objectStatus "@baseboard_fab2_lib.baseboard_fab2(sch_1):m_a_par" )
			)
			( signal "M_B_ACT_N"
				( objectStatus "@baseboard_fab2_lib.baseboard_fab2(sch_1):m_b_act_n" )
			)
			( signal "M_B_ALERT_N"
				( objectStatus "@baseboard_fab2_lib.baseboard_fab2(sch_1):m_b_alert_n" )
			)
			( signal "M_B_BA<0>"
				( objectStatus "@baseboard_fab2_lib.baseboard_fab2(sch_1):m_b_ba(0)" )
			)
			( signal "M_B_BA<1>"
				( objectStatus "@baseboard_fab2_lib.baseboard_fab2(sch_1):m_b_ba(1)" )
			)
			( signal "M_B_BG<0>"
				( objectStatus "@baseboard_fab2_lib.baseboard_fab2(sch_1):m_b_bg(0)" )
			)
			( signal "M_B_BG<1>"
				( objectStatus "@baseboard_fab2_lib.baseboard_fab2(sch_1):m_b_bg(1)" )
			)
			( signal "M_B_C<2>"
				( objectStatus "@baseboard_fab2_lib.baseboard_fab2(sch_1):m_b_c(2)" )
			)
			( signal "M_B_CKE<0>"
				( objectStatus "@baseboard_fab2_lib.baseboard_fab2(sch_1):m_b_cke(0)" )
			)
			( signal "M_B_CKE<1>"
				( objectStatus "@baseboard_fab2_lib.baseboard_fab2(sch_1):m_b_cke(1)" )
			)
			( signal "M_B_CKE<2>"
				( objectStatus "@baseboard_fab2_lib.baseboard_fab2(sch_1):m_b_cke(2)" )
			)
			( signal "M_B_CKE<3>"
				( objectStatus "@baseboard_fab2_lib.baseboard_fab2(sch_1):m_b_cke(3)" )
			)
			( signal "M_B_CLK_DN<0>"
				( objectStatus "@baseboard_fab2_lib.baseboard_fab2(sch_1):m_b_clk_dn(0)" )
			)
			( signal "M_B_CLK_DN<1>"
				( objectStatus "@baseboard_fab2_lib.baseboard_fab2(sch_1):m_b_clk_dn(1)" )
			)
			( signal "M_B_CLK_DN<2>"
				( objectStatus "@baseboard_fab2_lib.baseboard_fab2(sch_1):m_b_clk_dn(2)" )
			)
			( signal "M_B_CLK_DN<3>"
				( objectStatus "@baseboard_fab2_lib.baseboard_fab2(sch_1):m_b_clk_dn(3)" )
			)
			( signal "M_B_CLK_DP<0>"
				( objectStatus "@baseboard_fab2_lib.baseboard_fab2(sch_1):m_b_clk_dp(0)" )
			)
			( signal "M_B_CLK_DP<1>"
				( objectStatus "@baseboard_fab2_lib.baseboard_fab2(sch_1):m_b_clk_dp(1)" )
			)
			( signal "M_B_CLK_DP<2>"
				( objectStatus "@baseboard_fab2_lib.baseboard_fab2(sch_1):m_b_clk_dp(2)" )
			)
			( signal "M_B_CLK_DP<3>"
				( objectStatus "@baseboard_fab2_lib.baseboard_fab2(sch_1):m_b_clk_dp(3)" )
			)
			( signal "M_B_CS_N<0>"
				( objectStatus "@baseboard_fab2_lib.baseboard_fab2(sch_1):m_b_cs_n(0)" )
			)
			( signal "M_B_CS_N<1>"
				( objectStatus "@baseboard_fab2_lib.baseboard_fab2(sch_1):m_b_cs_n(1)" )
			)
			( signal "M_B_CS_N<2>"
				( objectStatus "@baseboard_fab2_lib.baseboard_fab2(sch_1):m_b_cs_n(2)" )
			)
			( signal "M_B_CS_N<3>"
				( objectStatus "@baseboard_fab2_lib.baseboard_fab2(sch_1):m_b_cs_n(3)" )
			)
			( signal "M_B_CS_N<4>"
				( objectStatus "@baseboard_fab2_lib.baseboard_fab2(sch_1):m_b_cs_n(4)" )
			)
			( signal "M_B_CS_N<5>"
				( objectStatus "@baseboard_fab2_lib.baseboard_fab2(sch_1):m_b_cs_n(5)" )
			)
			( signal "M_B_CS_N<6>"
				( objectStatus "@baseboard_fab2_lib.baseboard_fab2(sch_1):m_b_cs_n(6)" )
			)
			( signal "M_B_CS_N<7>"
				( objectStatus "@baseboard_fab2_lib.baseboard_fab2(sch_1):m_b_cs_n(7)" )
			)
			( signal "M_B_DQ<0>"
				( objectStatus "@baseboard_fab2_lib.baseboard_fab2(sch_1):m_b_dq(0)" )
			)
			( signal "M_B_DQ<1>"
				( objectStatus "@baseboard_fab2_lib.baseboard_fab2(sch_1):m_b_dq(1)" )
			)
			( signal "M_B_DQ<2>"
				( objectStatus "@baseboard_fab2_lib.baseboard_fab2(sch_1):m_b_dq(2)" )
			)
			( signal "M_B_DQ<3>"
				( objectStatus "@baseboard_fab2_lib.baseboard_fab2(sch_1):m_b_dq(3)" )
			)
			( signal "M_B_DQ<4>"
				( objectStatus "@baseboard_fab2_lib.baseboard_fab2(sch_1):m_b_dq(4)" )
			)
			( signal "M_B_DQ<5>"
				( objectStatus "@baseboard_fab2_lib.baseboard_fab2(sch_1):m_b_dq(5)" )
			)
			( signal "M_B_DQ<6>"
				( objectStatus "@baseboard_fab2_lib.baseboard_fab2(sch_1):m_b_dq(6)" )
			)
			( signal "M_B_DQ<7>"
				( objectStatus "@baseboard_fab2_lib.baseboard_fab2(sch_1):m_b_dq(7)" )
			)
			( signal "M_B_DQ<8>"
				( objectStatus "@baseboard_fab2_lib.baseboard_fab2(sch_1):m_b_dq(8)" )
			)
			( signal "M_B_DQ<9>"
				( objectStatus "@baseboard_fab2_lib.baseboard_fab2(sch_1):m_b_dq(9)" )
			)
			( signal "M_B_DQ<10>"
				( objectStatus "@baseboard_fab2_lib.baseboard_fab2(sch_1):m_b_dq(10)" )
			)
			( signal "M_B_DQ<11>"
				( objectStatus "@baseboard_fab2_lib.baseboard_fab2(sch_1):m_b_dq(11)" )
			)
			( signal "M_B_DQ<12>"
				( objectStatus "@baseboard_fab2_lib.baseboard_fab2(sch_1):m_b_dq(12)" )
			)
			( signal "M_B_DQ<13>"
				( objectStatus "@baseboard_fab2_lib.baseboard_fab2(sch_1):m_b_dq(13)" )
			)
			( signal "M_B_DQ<14>"
				( objectStatus "@baseboard_fab2_lib.baseboard_fab2(sch_1):m_b_dq(14)" )
			)
			( signal "M_B_DQ<15>"
				( objectStatus "@baseboard_fab2_lib.baseboard_fab2(sch_1):m_b_dq(15)" )
			)
			( signal "M_B_DQ<16>"
				( objectStatus "@baseboard_fab2_lib.baseboard_fab2(sch_1):m_b_dq(16)" )
			)
			( signal "M_B_DQ<17>"
				( objectStatus "@baseboard_fab2_lib.baseboard_fab2(sch_1):m_b_dq(17)" )
			)
			( signal "M_B_DQ<18>"
				( objectStatus "@baseboard_fab2_lib.baseboard_fab2(sch_1):m_b_dq(18)" )
			)
			( signal "M_B_DQ<19>"
				( objectStatus "@baseboard_fab2_lib.baseboard_fab2(sch_1):m_b_dq(19)" )
			)
			( signal "M_B_DQ<20>"
				( objectStatus "@baseboard_fab2_lib.baseboard_fab2(sch_1):m_b_dq(20)" )
			)
			( signal "M_B_DQ<21>"
				( objectStatus "@baseboard_fab2_lib.baseboard_fab2(sch_1):m_b_dq(21)" )
			)
			( signal "M_B_DQ<22>"
				( objectStatus "@baseboard_fab2_lib.baseboard_fab2(sch_1):m_b_dq(22)" )
			)
			( signal "M_B_DQ<23>"
				( objectStatus "@baseboard_fab2_lib.baseboard_fab2(sch_1):m_b_dq(23)" )
			)
			( signal "M_B_DQ<24>"
				( objectStatus "@baseboard_fab2_lib.baseboard_fab2(sch_1):m_b_dq(24)" )
			)
			( signal "M_B_DQ<25>"
				( objectStatus "@baseboard_fab2_lib.baseboard_fab2(sch_1):m_b_dq(25)" )
			)
			( signal "M_B_DQ<26>"
				( objectStatus "@baseboard_fab2_lib.baseboard_fab2(sch_1):m_b_dq(26)" )
			)
			( signal "M_B_DQ<27>"
				( objectStatus "@baseboard_fab2_lib.baseboard_fab2(sch_1):m_b_dq(27)" )
			)
			( signal "M_B_DQ<28>"
				( objectStatus "@baseboard_fab2_lib.baseboard_fab2(sch_1):m_b_dq(28)" )
			)
			( signal "M_B_DQ<29>"
				( objectStatus "@baseboard_fab2_lib.baseboard_fab2(sch_1):m_b_dq(29)" )
			)
			( signal "M_B_DQ<30>"
				( objectStatus "@baseboard_fab2_lib.baseboard_fab2(sch_1):m_b_dq(30)" )
			)
			( signal "M_B_DQ<31>"
				( objectStatus "@baseboard_fab2_lib.baseboard_fab2(sch_1):m_b_dq(31)" )
			)
			( signal "M_B_DQ<32>"
				( objectStatus "@baseboard_fab2_lib.baseboard_fab2(sch_1):m_b_dq(32)" )
			)
			( signal "M_B_DQ<33>"
				( objectStatus "@baseboard_fab2_lib.baseboard_fab2(sch_1):m_b_dq(33)" )
			)
			( signal "M_B_DQ<34>"
				( objectStatus "@baseboard_fab2_lib.baseboard_fab2(sch_1):m_b_dq(34)" )
			)
			( signal "M_B_DQ<35>"
				( objectStatus "@baseboard_fab2_lib.baseboard_fab2(sch_1):m_b_dq(35)" )
			)
			( signal "M_B_DQ<36>"
				( objectStatus "@baseboard_fab2_lib.baseboard_fab2(sch_1):m_b_dq(36)" )
			)
			( signal "M_B_DQ<37>"
				( objectStatus "@baseboard_fab2_lib.baseboard_fab2(sch_1):m_b_dq(37)" )
			)
			( signal "M_B_DQ<38>"
				( objectStatus "@baseboard_fab2_lib.baseboard_fab2(sch_1):m_b_dq(38)" )
			)
			( signal "M_B_DQ<39>"
				( objectStatus "@baseboard_fab2_lib.baseboard_fab2(sch_1):m_b_dq(39)" )
			)
			( signal "M_B_DQ<40>"
				( objectStatus "@baseboard_fab2_lib.baseboard_fab2(sch_1):m_b_dq(40)" )
			)
			( signal "M_B_DQ<41>"
				( objectStatus "@baseboard_fab2_lib.baseboard_fab2(sch_1):m_b_dq(41)" )
			)
			( signal "M_B_DQ<42>"
				( objectStatus "@baseboard_fab2_lib.baseboard_fab2(sch_1):m_b_dq(42)" )
			)
			( signal "M_B_DQ<43>"
				( objectStatus "@baseboard_fab2_lib.baseboard_fab2(sch_1):m_b_dq(43)" )
			)
			( signal "M_B_DQ<44>"
				( objectStatus "@baseboard_fab2_lib.baseboard_fab2(sch_1):m_b_dq(44)" )
			)
			( signal "M_B_DQ<45>"
				( objectStatus "@baseboard_fab2_lib.baseboard_fab2(sch_1):m_b_dq(45)" )
			)
			( signal "M_B_DQ<46>"
				( objectStatus "@baseboard_fab2_lib.baseboard_fab2(sch_1):m_b_dq(46)" )
			)
			( signal "M_B_DQ<47>"
				( objectStatus "@baseboard_fab2_lib.baseboard_fab2(sch_1):m_b_dq(47)" )
			)
			( signal "M_B_DQ<48>"
				( objectStatus "@baseboard_fab2_lib.baseboard_fab2(sch_1):m_b_dq(48)" )
			)
			( signal "M_B_DQ<49>"
				( objectStatus "@baseboard_fab2_lib.baseboard_fab2(sch_1):m_b_dq(49)" )
			)
			( signal "M_B_DQ<50>"
				( objectStatus "@baseboard_fab2_lib.baseboard_fab2(sch_1):m_b_dq(50)" )
			)
			( signal "M_B_DQ<51>"
				( objectStatus "@baseboard_fab2_lib.baseboard_fab2(sch_1):m_b_dq(51)" )
			)
			( signal "M_B_DQ<52>"
				( objectStatus "@baseboard_fab2_lib.baseboard_fab2(sch_1):m_b_dq(52)" )
			)
			( signal "M_B_DQ<53>"
				( objectStatus "@baseboard_fab2_lib.baseboard_fab2(sch_1):m_b_dq(53)" )
			)
			( signal "M_B_DQ<54>"
				( objectStatus "@baseboard_fab2_lib.baseboard_fab2(sch_1):m_b_dq(54)" )
			)
			( signal "M_B_DQ<55>"
				( objectStatus "@baseboard_fab2_lib.baseboard_fab2(sch_1):m_b_dq(55)" )
			)
			( signal "M_B_DQ<56>"
				( objectStatus "@baseboard_fab2_lib.baseboard_fab2(sch_1):m_b_dq(56)" )
			)
			( signal "M_B_DQ<57>"
				( objectStatus "@baseboard_fab2_lib.baseboard_fab2(sch_1):m_b_dq(57)" )
			)
			( signal "M_B_DQ<58>"
				( objectStatus "@baseboard_fab2_lib.baseboard_fab2(sch_1):m_b_dq(58)" )
			)
			( signal "M_B_DQ<59>"
				( objectStatus "@baseboard_fab2_lib.baseboard_fab2(sch_1):m_b_dq(59)" )
			)
			( signal "M_B_DQ<60>"
				( objectStatus "@baseboard_fab2_lib.baseboard_fab2(sch_1):m_b_dq(60)" )
			)
			( signal "M_B_DQ<61>"
				( objectStatus "@baseboard_fab2_lib.baseboard_fab2(sch_1):m_b_dq(61)" )
			)
			( signal "M_B_DQ<62>"
				( objectStatus "@baseboard_fab2_lib.baseboard_fab2(sch_1):m_b_dq(62)" )
			)
			( signal "M_B_DQ<63>"
				( objectStatus "@baseboard_fab2_lib.baseboard_fab2(sch_1):m_b_dq(63)" )
			)
			( signal "M_B_DQS_DN<0>"
				( objectStatus "@baseboard_fab2_lib.baseboard_fab2(sch_1):m_b_dqs_dn(0)" )
			)
			( signal "M_B_DQS_DN<1>"
				( objectStatus "@baseboard_fab2_lib.baseboard_fab2(sch_1):m_b_dqs_dn(1)" )
			)
			( signal "M_B_DQS_DN<2>"
				( objectStatus "@baseboard_fab2_lib.baseboard_fab2(sch_1):m_b_dqs_dn(2)" )
			)
			( signal "M_B_DQS_DN<3>"
				( objectStatus "@baseboard_fab2_lib.baseboard_fab2(sch_1):m_b_dqs_dn(3)" )
			)
			( signal "M_B_DQS_DN<4>"
				( objectStatus "@baseboard_fab2_lib.baseboard_fab2(sch_1):m_b_dqs_dn(4)" )
			)
			( signal "M_B_DQS_DN<5>"
				( objectStatus "@baseboard_fab2_lib.baseboard_fab2(sch_1):m_b_dqs_dn(5)" )
			)
			( signal "M_B_DQS_DN<6>"
				( objectStatus "@baseboard_fab2_lib.baseboard_fab2(sch_1):m_b_dqs_dn(6)" )
			)
			( signal "M_B_DQS_DN<7>"
				( objectStatus "@baseboard_fab2_lib.baseboard_fab2(sch_1):m_b_dqs_dn(7)" )
			)
			( signal "M_B_DQS_DN<8>"
				( objectStatus "@baseboard_fab2_lib.baseboard_fab2(sch_1):m_b_dqs_dn(8)" )
			)
			( signal "M_B_DQS_DN<9>"
				( objectStatus "@baseboard_fab2_lib.baseboard_fab2(sch_1):m_b_dqs_dn(9)" )
			)
			( signal "M_B_DQS_DN<10>"
				( objectStatus "@baseboard_fab2_lib.baseboard_fab2(sch_1):m_b_dqs_dn(10)" )
			)
			( signal "M_B_DQS_DN<11>"
				( objectStatus "@baseboard_fab2_lib.baseboard_fab2(sch_1):m_b_dqs_dn(11)" )
			)
			( signal "M_B_DQS_DN<12>"
				( objectStatus "@baseboard_fab2_lib.baseboard_fab2(sch_1):m_b_dqs_dn(12)" )
			)
			( signal "M_B_DQS_DN<13>"
				( objectStatus "@baseboard_fab2_lib.baseboard_fab2(sch_1):m_b_dqs_dn(13)" )
			)
			( signal "M_B_DQS_DN<14>"
				( objectStatus "@baseboard_fab2_lib.baseboard_fab2(sch_1):m_b_dqs_dn(14)" )
			)
			( signal "M_B_DQS_DN<15>"
				( objectStatus "@baseboard_fab2_lib.baseboard_fab2(sch_1):m_b_dqs_dn(15)" )
			)
			( signal "M_B_DQS_DN<16>"
				( objectStatus "@baseboard_fab2_lib.baseboard_fab2(sch_1):m_b_dqs_dn(16)" )
			)
			( signal "M_B_DQS_DN<17>"
				( objectStatus "@baseboard_fab2_lib.baseboard_fab2(sch_1):m_b_dqs_dn(17)" )
			)
			( signal "M_B_DQS_DP<0>"
				( objectStatus "@baseboard_fab2_lib.baseboard_fab2(sch_1):m_b_dqs_dp(0)" )
			)
			( signal "M_B_DQS_DP<1>"
				( objectStatus "@baseboard_fab2_lib.baseboard_fab2(sch_1):m_b_dqs_dp(1)" )
			)
			( signal "M_B_DQS_DP<2>"
				( objectStatus "@baseboard_fab2_lib.baseboard_fab2(sch_1):m_b_dqs_dp(2)" )
			)
			( signal "M_B_DQS_DP<3>"
				( objectStatus "@baseboard_fab2_lib.baseboard_fab2(sch_1):m_b_dqs_dp(3)" )
			)
			( signal "M_B_DQS_DP<4>"
				( objectStatus "@baseboard_fab2_lib.baseboard_fab2(sch_1):m_b_dqs_dp(4)" )
			)
			( signal "M_B_DQS_DP<5>"
				( objectStatus "@baseboard_fab2_lib.baseboard_fab2(sch_1):m_b_dqs_dp(5)" )
			)
			( signal "M_B_DQS_DP<6>"
				( objectStatus "@baseboard_fab2_lib.baseboard_fab2(sch_1):m_b_dqs_dp(6)" )
			)
			( signal "M_B_DQS_DP<7>"
				( objectStatus "@baseboard_fab2_lib.baseboard_fab2(sch_1):m_b_dqs_dp(7)" )
			)
			( signal "M_B_DQS_DP<8>"
				( objectStatus "@baseboard_fab2_lib.baseboard_fab2(sch_1):m_b_dqs_dp(8)" )
			)
			( signal "M_B_DQS_DP<9>"
				( objectStatus "@baseboard_fab2_lib.baseboard_fab2(sch_1):m_b_dqs_dp(9)" )
			)
			( signal "M_B_DQS_DP<10>"
				( objectStatus "@baseboard_fab2_lib.baseboard_fab2(sch_1):m_b_dqs_dp(10)" )
			)
			( signal "M_B_DQS_DP<11>"
				( objectStatus "@baseboard_fab2_lib.baseboard_fab2(sch_1):m_b_dqs_dp(11)" )
			)
			( signal "M_B_DQS_DP<12>"
				( objectStatus "@baseboard_fab2_lib.baseboard_fab2(sch_1):m_b_dqs_dp(12)" )
			)
			( signal "M_B_DQS_DP<13>"
				( objectStatus "@baseboard_fab2_lib.baseboard_fab2(sch_1):m_b_dqs_dp(13)" )
			)
			( signal "M_B_DQS_DP<14>"
				( objectStatus "@baseboard_fab2_lib.baseboard_fab2(sch_1):m_b_dqs_dp(14)" )
			)
			( signal "M_B_DQS_DP<15>"
				( objectStatus "@baseboard_fab2_lib.baseboard_fab2(sch_1):m_b_dqs_dp(15)" )
			)
			( signal "M_B_DQS_DP<16>"
				( objectStatus "@baseboard_fab2_lib.baseboard_fab2(sch_1):m_b_dqs_dp(16)" )
			)
			( signal "M_B_DQS_DP<17>"
				( objectStatus "@baseboard_fab2_lib.baseboard_fab2(sch_1):m_b_dqs_dp(17)" )
			)
			( signal "M_B_ECC<0>"
				( objectStatus "@baseboard_fab2_lib.baseboard_fab2(sch_1):m_b_ecc(0)" )
			)
			( signal "M_B_ECC<1>"
				( objectStatus "@baseboard_fab2_lib.baseboard_fab2(sch_1):m_b_ecc(1)" )
			)
			( signal "M_B_ECC<2>"
				( objectStatus "@baseboard_fab2_lib.baseboard_fab2(sch_1):m_b_ecc(2)" )
			)
			( signal "M_B_ECC<3>"
				( objectStatus "@baseboard_fab2_lib.baseboard_fab2(sch_1):m_b_ecc(3)" )
			)
			( signal "M_B_ECC<4>"
				( objectStatus "@baseboard_fab2_lib.baseboard_fab2(sch_1):m_b_ecc(4)" )
			)
			( signal "M_B_ECC<5>"
				( objectStatus "@baseboard_fab2_lib.baseboard_fab2(sch_1):m_b_ecc(5)" )
			)
			( signal "M_B_ECC<6>"
				( objectStatus "@baseboard_fab2_lib.baseboard_fab2(sch_1):m_b_ecc(6)" )
			)
			( signal "M_B_ECC<7>"
				( objectStatus "@baseboard_fab2_lib.baseboard_fab2(sch_1):m_b_ecc(7)" )
			)
			( signal "M_B_MA<0>"
				( objectStatus "@baseboard_fab2_lib.baseboard_fab2(sch_1):m_b_ma(0)" )
			)
			( signal "M_B_MA<1>"
				( objectStatus "@baseboard_fab2_lib.baseboard_fab2(sch_1):m_b_ma(1)" )
			)
			( signal "M_B_MA<2>"
				( objectStatus "@baseboard_fab2_lib.baseboard_fab2(sch_1):m_b_ma(2)" )
			)
			( signal "M_B_MA<3>"
				( objectStatus "@baseboard_fab2_lib.baseboard_fab2(sch_1):m_b_ma(3)" )
			)
			( signal "M_B_MA<4>"
				( objectStatus "@baseboard_fab2_lib.baseboard_fab2(sch_1):m_b_ma(4)" )
			)
			( signal "M_B_MA<5>"
				( objectStatus "@baseboard_fab2_lib.baseboard_fab2(sch_1):m_b_ma(5)" )
			)
			( signal "M_B_MA<6>"
				( objectStatus "@baseboard_fab2_lib.baseboard_fab2(sch_1):m_b_ma(6)" )
			)
			( signal "M_B_MA<7>"
				( objectStatus "@baseboard_fab2_lib.baseboard_fab2(sch_1):m_b_ma(7)" )
			)
			( signal "M_B_MA<8>"
				( objectStatus "@baseboard_fab2_lib.baseboard_fab2(sch_1):m_b_ma(8)" )
			)
			( signal "M_B_MA<9>"
				( objectStatus "@baseboard_fab2_lib.baseboard_fab2(sch_1):m_b_ma(9)" )
			)
			( signal "M_B_MA<10>"
				( objectStatus "@baseboard_fab2_lib.baseboard_fab2(sch_1):m_b_ma(10)" )
			)
			( signal "M_B_MA<11>"
				( objectStatus "@baseboard_fab2_lib.baseboard_fab2(sch_1):m_b_ma(11)" )
			)
			( signal "M_B_MA<12>"
				( objectStatus "@baseboard_fab2_lib.baseboard_fab2(sch_1):m_b_ma(12)" )
			)
			( signal "M_B_MA<13>"
				( objectStatus "@baseboard_fab2_lib.baseboard_fab2(sch_1):m_b_ma(13)" )
			)
			( signal "M_B_MA<14>"
				( objectStatus "@baseboard_fab2_lib.baseboard_fab2(sch_1):m_b_ma(14)" )
			)
			( signal "M_B_MA<15>"
				( objectStatus "@baseboard_fab2_lib.baseboard_fab2(sch_1):m_b_ma(15)" )
			)
			( signal "M_B_MA<16>"
				( objectStatus "@baseboard_fab2_lib.baseboard_fab2(sch_1):m_b_ma(16)" )
			)
			( signal "M_B_MA<17>"
				( objectStatus "@baseboard_fab2_lib.baseboard_fab2(sch_1):m_b_ma(17)" )
			)
			( signal "M_B_ODT<0>"
				( objectStatus "@baseboard_fab2_lib.baseboard_fab2(sch_1):m_b_odt(0)" )
			)
			( signal "M_B_ODT<1>"
				( objectStatus "@baseboard_fab2_lib.baseboard_fab2(sch_1):m_b_odt(1)" )
			)
			( signal "M_B_ODT<2>"
				( objectStatus "@baseboard_fab2_lib.baseboard_fab2(sch_1):m_b_odt(2)" )
			)
			( signal "M_B_ODT<3>"
				( objectStatus "@baseboard_fab2_lib.baseboard_fab2(sch_1):m_b_odt(3)" )
			)
			( signal "M_B_PAR"
				( objectStatus "@baseboard_fab2_lib.baseboard_fab2(sch_1):m_b_par" )
			)
			( signal "M_C_ACT_N"
				( objectStatus "@baseboard_fab2_lib.baseboard_fab2(sch_1):m_c_act_n" )
			)
			( signal "M_C_ALERT_N"
				( objectStatus "@baseboard_fab2_lib.baseboard_fab2(sch_1):m_c_alert_n" )
			)
			( signal "M_C_BA<0>"
				( objectStatus "@baseboard_fab2_lib.baseboard_fab2(sch_1):m_c_ba(0)" )
			)
			( signal "M_C_BA<1>"
				( objectStatus "@baseboard_fab2_lib.baseboard_fab2(sch_1):m_c_ba(1)" )
			)
			( signal "M_C_BG<0>"
				( objectStatus "@baseboard_fab2_lib.baseboard_fab2(sch_1):m_c_bg(0)" )
			)
			( signal "M_C_BG<1>"
				( objectStatus "@baseboard_fab2_lib.baseboard_fab2(sch_1):m_c_bg(1)" )
			)
			( signal "M_C_C<2>"
				( objectStatus "@baseboard_fab2_lib.baseboard_fab2(sch_1):m_c_c(2)" )
			)
			( signal "M_C_CKE<0>"
				( objectStatus "@baseboard_fab2_lib.baseboard_fab2(sch_1):m_c_cke(0)" )
			)
			( signal "M_C_CKE<1>"
				( objectStatus "@baseboard_fab2_lib.baseboard_fab2(sch_1):m_c_cke(1)" )
			)
			( signal "M_C_CKE<2>"
				( objectStatus "@baseboard_fab2_lib.baseboard_fab2(sch_1):m_c_cke(2)" )
			)
			( signal "M_C_CKE<3>"
				( objectStatus "@baseboard_fab2_lib.baseboard_fab2(sch_1):m_c_cke(3)" )
			)
			( signal "M_C_CLK_DN<0>"
				( objectStatus "@baseboard_fab2_lib.baseboard_fab2(sch_1):m_c_clk_dn(0)" )
			)
			( signal "M_C_CLK_DN<1>"
				( objectStatus "@baseboard_fab2_lib.baseboard_fab2(sch_1):m_c_clk_dn(1)" )
			)
			( signal "M_C_CLK_DN<2>"
				( objectStatus "@baseboard_fab2_lib.baseboard_fab2(sch_1):m_c_clk_dn(2)" )
			)
			( signal "M_C_CLK_DN<3>"
				( objectStatus "@baseboard_fab2_lib.baseboard_fab2(sch_1):m_c_clk_dn(3)" )
			)
			( signal "M_C_CLK_DP<0>"
				( objectStatus "@baseboard_fab2_lib.baseboard_fab2(sch_1):m_c_clk_dp(0)" )
			)
			( signal "M_C_CLK_DP<1>"
				( objectStatus "@baseboard_fab2_lib.baseboard_fab2(sch_1):m_c_clk_dp(1)" )
			)
			( signal "M_C_CLK_DP<2>"
				( objectStatus "@baseboard_fab2_lib.baseboard_fab2(sch_1):m_c_clk_dp(2)" )
			)
			( signal "M_C_CLK_DP<3>"
				( objectStatus "@baseboard_fab2_lib.baseboard_fab2(sch_1):m_c_clk_dp(3)" )
			)
			( signal "M_C_CS_N<0>"
				( objectStatus "@baseboard_fab2_lib.baseboard_fab2(sch_1):m_c_cs_n(0)" )
			)
			( signal "M_C_CS_N<1>"
				( objectStatus "@baseboard_fab2_lib.baseboard_fab2(sch_1):m_c_cs_n(1)" )
			)
			( signal "M_C_CS_N<2>"
				( objectStatus "@baseboard_fab2_lib.baseboard_fab2(sch_1):m_c_cs_n(2)" )
			)
			( signal "M_C_CS_N<3>"
				( objectStatus "@baseboard_fab2_lib.baseboard_fab2(sch_1):m_c_cs_n(3)" )
			)
			( signal "M_C_CS_N<4>"
				( objectStatus "@baseboard_fab2_lib.baseboard_fab2(sch_1):m_c_cs_n(4)" )
			)
			( signal "M_C_CS_N<5>"
				( objectStatus "@baseboard_fab2_lib.baseboard_fab2(sch_1):m_c_cs_n(5)" )
			)
			( signal "M_C_CS_N<6>"
				( objectStatus "@baseboard_fab2_lib.baseboard_fab2(sch_1):m_c_cs_n(6)" )
			)
			( signal "M_C_CS_N<7>"
				( objectStatus "@baseboard_fab2_lib.baseboard_fab2(sch_1):m_c_cs_n(7)" )
			)
			( signal "M_C_DQ<0>"
				( objectStatus "@baseboard_fab2_lib.baseboard_fab2(sch_1):m_c_dq(0)" )
			)
			( signal "M_C_DQ<1>"
				( objectStatus "@baseboard_fab2_lib.baseboard_fab2(sch_1):m_c_dq(1)" )
			)
			( signal "M_C_DQ<2>"
				( objectStatus "@baseboard_fab2_lib.baseboard_fab2(sch_1):m_c_dq(2)" )
			)
			( signal "M_C_DQ<3>"
				( objectStatus "@baseboard_fab2_lib.baseboard_fab2(sch_1):m_c_dq(3)" )
			)
			( signal "M_C_DQ<4>"
				( objectStatus "@baseboard_fab2_lib.baseboard_fab2(sch_1):m_c_dq(4)" )
			)
			( signal "M_C_DQ<5>"
				( objectStatus "@baseboard_fab2_lib.baseboard_fab2(sch_1):m_c_dq(5)" )
			)
			( signal "M_C_DQ<6>"
				( objectStatus "@baseboard_fab2_lib.baseboard_fab2(sch_1):m_c_dq(6)" )
			)
			( signal "M_C_DQ<7>"
				( objectStatus "@baseboard_fab2_lib.baseboard_fab2(sch_1):m_c_dq(7)" )
			)
			( signal "M_C_DQ<8>"
				( objectStatus "@baseboard_fab2_lib.baseboard_fab2(sch_1):m_c_dq(8)" )
			)
			( signal "M_C_DQ<9>"
				( objectStatus "@baseboard_fab2_lib.baseboard_fab2(sch_1):m_c_dq(9)" )
			)
			( signal "M_C_DQ<10>"
				( objectStatus "@baseboard_fab2_lib.baseboard_fab2(sch_1):m_c_dq(10)" )
			)
			( signal "M_C_DQ<11>"
				( objectStatus "@baseboard_fab2_lib.baseboard_fab2(sch_1):m_c_dq(11)" )
			)
			( signal "M_C_DQ<12>"
				( objectStatus "@baseboard_fab2_lib.baseboard_fab2(sch_1):m_c_dq(12)" )
			)
			( signal "M_C_DQ<13>"
				( objectStatus "@baseboard_fab2_lib.baseboard_fab2(sch_1):m_c_dq(13)" )
			)
			( signal "M_C_DQ<14>"
				( objectStatus "@baseboard_fab2_lib.baseboard_fab2(sch_1):m_c_dq(14)" )
			)
			( signal "M_C_DQ<15>"
				( objectStatus "@baseboard_fab2_lib.baseboard_fab2(sch_1):m_c_dq(15)" )
			)
			( signal "M_C_DQ<16>"
				( objectStatus "@baseboard_fab2_lib.baseboard_fab2(sch_1):m_c_dq(16)" )
			)
			( signal "M_C_DQ<17>"
				( objectStatus "@baseboard_fab2_lib.baseboard_fab2(sch_1):m_c_dq(17)" )
			)
			( signal "M_C_DQ<18>"
				( objectStatus "@baseboard_fab2_lib.baseboard_fab2(sch_1):m_c_dq(18)" )
			)
			( signal "M_C_DQ<19>"
				( objectStatus "@baseboard_fab2_lib.baseboard_fab2(sch_1):m_c_dq(19)" )
			)
			( signal "M_C_DQ<20>"
				( objectStatus "@baseboard_fab2_lib.baseboard_fab2(sch_1):m_c_dq(20)" )
			)
			( signal "M_C_DQ<21>"
				( objectStatus "@baseboard_fab2_lib.baseboard_fab2(sch_1):m_c_dq(21)" )
			)
			( signal "M_C_DQ<22>"
				( objectStatus "@baseboard_fab2_lib.baseboard_fab2(sch_1):m_c_dq(22)" )
			)
			( signal "M_C_DQ<23>"
				( objectStatus "@baseboard_fab2_lib.baseboard_fab2(sch_1):m_c_dq(23)" )
			)
			( signal "M_C_DQ<24>"
				( objectStatus "@baseboard_fab2_lib.baseboard_fab2(sch_1):m_c_dq(24)" )
			)
			( signal "M_C_DQ<25>"
				( objectStatus "@baseboard_fab2_lib.baseboard_fab2(sch_1):m_c_dq(25)" )
			)
			( signal "M_C_DQ<26>"
				( objectStatus "@baseboard_fab2_lib.baseboard_fab2(sch_1):m_c_dq(26)" )
			)
			( signal "M_C_DQ<27>"
				( objectStatus "@baseboard_fab2_lib.baseboard_fab2(sch_1):m_c_dq(27)" )
			)
			( signal "M_C_DQ<28>"
				( objectStatus "@baseboard_fab2_lib.baseboard_fab2(sch_1):m_c_dq(28)" )
			)
			( signal "M_C_DQ<29>"
				( objectStatus "@baseboard_fab2_lib.baseboard_fab2(sch_1):m_c_dq(29)" )
			)
			( signal "M_C_DQ<30>"
				( objectStatus "@baseboard_fab2_lib.baseboard_fab2(sch_1):m_c_dq(30)" )
			)
			( signal "M_C_DQ<31>"
				( objectStatus "@baseboard_fab2_lib.baseboard_fab2(sch_1):m_c_dq(31)" )
			)
			( signal "M_C_DQ<32>"
				( objectStatus "@baseboard_fab2_lib.baseboard_fab2(sch_1):m_c_dq(32)" )
			)
			( signal "M_C_DQ<33>"
				( objectStatus "@baseboard_fab2_lib.baseboard_fab2(sch_1):m_c_dq(33)" )
			)
			( signal "M_C_DQ<34>"
				( objectStatus "@baseboard_fab2_lib.baseboard_fab2(sch_1):m_c_dq(34)" )
			)
			( signal "M_C_DQ<35>"
				( objectStatus "@baseboard_fab2_lib.baseboard_fab2(sch_1):m_c_dq(35)" )
			)
			( signal "M_C_DQ<36>"
				( objectStatus "@baseboard_fab2_lib.baseboard_fab2(sch_1):m_c_dq(36)" )
			)
			( signal "M_C_DQ<37>"
				( objectStatus "@baseboard_fab2_lib.baseboard_fab2(sch_1):m_c_dq(37)" )
			)
			( signal "M_C_DQ<38>"
				( objectStatus "@baseboard_fab2_lib.baseboard_fab2(sch_1):m_c_dq(38)" )
			)
			( signal "M_C_DQ<39>"
				( objectStatus "@baseboard_fab2_lib.baseboard_fab2(sch_1):m_c_dq(39)" )
			)
			( signal "M_C_DQ<40>"
				( objectStatus "@baseboard_fab2_lib.baseboard_fab2(sch_1):m_c_dq(40)" )
			)
			( signal "M_C_DQ<41>"
				( objectStatus "@baseboard_fab2_lib.baseboard_fab2(sch_1):m_c_dq(41)" )
			)
			( signal "M_C_DQ<42>"
				( objectStatus "@baseboard_fab2_lib.baseboard_fab2(sch_1):m_c_dq(42)" )
			)
			( signal "M_C_DQ<43>"
				( objectStatus "@baseboard_fab2_lib.baseboard_fab2(sch_1):m_c_dq(43)" )
			)
			( signal "M_C_DQ<44>"
				( objectStatus "@baseboard_fab2_lib.baseboard_fab2(sch_1):m_c_dq(44)" )
			)
			( signal "M_C_DQ<45>"
				( objectStatus "@baseboard_fab2_lib.baseboard_fab2(sch_1):m_c_dq(45)" )
			)
			( signal "M_C_DQ<46>"
				( objectStatus "@baseboard_fab2_lib.baseboard_fab2(sch_1):m_c_dq(46)" )
			)
			( signal "M_C_DQ<47>"
				( objectStatus "@baseboard_fab2_lib.baseboard_fab2(sch_1):m_c_dq(47)" )
			)
			( signal "M_C_DQ<48>"
				( objectStatus "@baseboard_fab2_lib.baseboard_fab2(sch_1):m_c_dq(48)" )
			)
			( signal "M_C_DQ<49>"
				( objectStatus "@baseboard_fab2_lib.baseboard_fab2(sch_1):m_c_dq(49)" )
			)
			( signal "M_C_DQ<50>"
				( objectStatus "@baseboard_fab2_lib.baseboard_fab2(sch_1):m_c_dq(50)" )
			)
			( signal "M_C_DQ<51>"
				( objectStatus "@baseboard_fab2_lib.baseboard_fab2(sch_1):m_c_dq(51)" )
			)
			( signal "M_C_DQ<52>"
				( objectStatus "@baseboard_fab2_lib.baseboard_fab2(sch_1):m_c_dq(52)" )
			)
			( signal "M_C_DQ<53>"
				( objectStatus "@baseboard_fab2_lib.baseboard_fab2(sch_1):m_c_dq(53)" )
			)
			( signal "M_C_DQ<54>"
				( objectStatus "@baseboard_fab2_lib.baseboard_fab2(sch_1):m_c_dq(54)" )
			)
			( signal "M_C_DQ<55>"
				( objectStatus "@baseboard_fab2_lib.baseboard_fab2(sch_1):m_c_dq(55)" )
			)
			( signal "M_C_DQ<56>"
				( objectStatus "@baseboard_fab2_lib.baseboard_fab2(sch_1):m_c_dq(56)" )
			)
			( signal "M_C_DQ<57>"
				( objectStatus "@baseboard_fab2_lib.baseboard_fab2(sch_1):m_c_dq(57)" )
			)
			( signal "M_C_DQ<58>"
				( objectStatus "@baseboard_fab2_lib.baseboard_fab2(sch_1):m_c_dq(58)" )
			)
			( signal "M_C_DQ<59>"
				( objectStatus "@baseboard_fab2_lib.baseboard_fab2(sch_1):m_c_dq(59)" )
			)
			( signal "M_C_DQ<60>"
				( objectStatus "@baseboard_fab2_lib.baseboard_fab2(sch_1):m_c_dq(60)" )
			)
			( signal "M_C_DQ<61>"
				( objectStatus "@baseboard_fab2_lib.baseboard_fab2(sch_1):m_c_dq(61)" )
			)
			( signal "M_C_DQ<62>"
				( objectStatus "@baseboard_fab2_lib.baseboard_fab2(sch_1):m_c_dq(62)" )
			)
			( signal "M_C_DQ<63>"
				( objectStatus "@baseboard_fab2_lib.baseboard_fab2(sch_1):m_c_dq(63)" )
			)
			( signal "M_C_DQS_DN<0>"
				( objectStatus "@baseboard_fab2_lib.baseboard_fab2(sch_1):m_c_dqs_dn(0)" )
			)
			( signal "M_C_DQS_DN<1>"
				( objectStatus "@baseboard_fab2_lib.baseboard_fab2(sch_1):m_c_dqs_dn(1)" )
			)
			( signal "M_C_DQS_DN<2>"
				( objectStatus "@baseboard_fab2_lib.baseboard_fab2(sch_1):m_c_dqs_dn(2)" )
			)
			( signal "M_C_DQS_DN<3>"
				( objectStatus "@baseboard_fab2_lib.baseboard_fab2(sch_1):m_c_dqs_dn(3)" )
			)
			( signal "M_C_DQS_DN<4>"
				( objectStatus "@baseboard_fab2_lib.baseboard_fab2(sch_1):m_c_dqs_dn(4)" )
			)
			( signal "M_C_DQS_DN<5>"
				( objectStatus "@baseboard_fab2_lib.baseboard_fab2(sch_1):m_c_dqs_dn(5)" )
			)
			( signal "M_C_DQS_DN<6>"
				( objectStatus "@baseboard_fab2_lib.baseboard_fab2(sch_1):m_c_dqs_dn(6)" )
			)
			( signal "M_C_DQS_DN<7>"
				( objectStatus "@baseboard_fab2_lib.baseboard_fab2(sch_1):m_c_dqs_dn(7)" )
			)
			( signal "M_C_DQS_DN<8>"
				( objectStatus "@baseboard_fab2_lib.baseboard_fab2(sch_1):m_c_dqs_dn(8)" )
			)
			( signal "M_C_DQS_DN<9>"
				( objectStatus "@baseboard_fab2_lib.baseboard_fab2(sch_1):m_c_dqs_dn(9)" )
			)
			( signal "M_C_DQS_DN<10>"
				( objectStatus "@baseboard_fab2_lib.baseboard_fab2(sch_1):m_c_dqs_dn(10)" )
			)
			( signal "M_C_DQS_DN<11>"
				( objectStatus "@baseboard_fab2_lib.baseboard_fab2(sch_1):m_c_dqs_dn(11)" )
			)
			( signal "M_C_DQS_DN<12>"
				( objectStatus "@baseboard_fab2_lib.baseboard_fab2(sch_1):m_c_dqs_dn(12)" )
			)
			( signal "M_C_DQS_DN<13>"
				( objectStatus "@baseboard_fab2_lib.baseboard_fab2(sch_1):m_c_dqs_dn(13)" )
			)
			( signal "M_C_DQS_DN<14>"
				( objectStatus "@baseboard_fab2_lib.baseboard_fab2(sch_1):m_c_dqs_dn(14)" )
			)
			( signal "M_C_DQS_DN<15>"
				( objectStatus "@baseboard_fab2_lib.baseboard_fab2(sch_1):m_c_dqs_dn(15)" )
			)
			( signal "M_C_DQS_DN<16>"
				( objectStatus "@baseboard_fab2_lib.baseboard_fab2(sch_1):m_c_dqs_dn(16)" )
			)
			( signal "M_C_DQS_DN<17>"
				( objectStatus "@baseboard_fab2_lib.baseboard_fab2(sch_1):m_c_dqs_dn(17)" )
			)
			( signal "M_C_DQS_DP<0>"
				( objectStatus "@baseboard_fab2_lib.baseboard_fab2(sch_1):m_c_dqs_dp(0)" )
			)
			( signal "M_C_DQS_DP<1>"
				( objectStatus "@baseboard_fab2_lib.baseboard_fab2(sch_1):m_c_dqs_dp(1)" )
			)
			( signal "M_C_DQS_DP<2>"
				( objectStatus "@baseboard_fab2_lib.baseboard_fab2(sch_1):m_c_dqs_dp(2)" )
			)
			( signal "M_C_DQS_DP<3>"
				( objectStatus "@baseboard_fab2_lib.baseboard_fab2(sch_1):m_c_dqs_dp(3)" )
			)
			( signal "M_C_DQS_DP<4>"
				( objectStatus "@baseboard_fab2_lib.baseboard_fab2(sch_1):m_c_dqs_dp(4)" )
			)
			( signal "M_C_DQS_DP<5>"
				( objectStatus "@baseboard_fab2_lib.baseboard_fab2(sch_1):m_c_dqs_dp(5)" )
			)
			( signal "M_C_DQS_DP<6>"
				( objectStatus "@baseboard_fab2_lib.baseboard_fab2(sch_1):m_c_dqs_dp(6)" )
			)
			( signal "M_C_DQS_DP<7>"
				( objectStatus "@baseboard_fab2_lib.baseboard_fab2(sch_1):m_c_dqs_dp(7)" )
			)
			( signal "M_C_DQS_DP<8>"
				( objectStatus "@baseboard_fab2_lib.baseboard_fab2(sch_1):m_c_dqs_dp(8)" )
			)
			( signal "M_C_DQS_DP<9>"
				( objectStatus "@baseboard_fab2_lib.baseboard_fab2(sch_1):m_c_dqs_dp(9)" )
			)
			( signal "M_C_DQS_DP<10>"
				( objectStatus "@baseboard_fab2_lib.baseboard_fab2(sch_1):m_c_dqs_dp(10)" )
			)
			( signal "M_C_DQS_DP<11>"
				( objectStatus "@baseboard_fab2_lib.baseboard_fab2(sch_1):m_c_dqs_dp(11)" )
			)
			( signal "M_C_DQS_DP<12>"
				( objectStatus "@baseboard_fab2_lib.baseboard_fab2(sch_1):m_c_dqs_dp(12)" )
			)
			( signal "M_C_DQS_DP<13>"
				( objectStatus "@baseboard_fab2_lib.baseboard_fab2(sch_1):m_c_dqs_dp(13)" )
			)
			( signal "M_C_DQS_DP<14>"
				( objectStatus "@baseboard_fab2_lib.baseboard_fab2(sch_1):m_c_dqs_dp(14)" )
			)
			( signal "M_C_DQS_DP<15>"
				( objectStatus "@baseboard_fab2_lib.baseboard_fab2(sch_1):m_c_dqs_dp(15)" )
			)
			( signal "M_C_DQS_DP<16>"
				( objectStatus "@baseboard_fab2_lib.baseboard_fab2(sch_1):m_c_dqs_dp(16)" )
			)
			( signal "M_C_DQS_DP<17>"
				( objectStatus "@baseboard_fab2_lib.baseboard_fab2(sch_1):m_c_dqs_dp(17)" )
			)
			( signal "M_C_ECC<0>"
				( objectStatus "@baseboard_fab2_lib.baseboard_fab2(sch_1):m_c_ecc(0)" )
			)
			( signal "M_C_ECC<1>"
				( objectStatus "@baseboard_fab2_lib.baseboard_fab2(sch_1):m_c_ecc(1)" )
			)
			( signal "M_C_ECC<2>"
				( objectStatus "@baseboard_fab2_lib.baseboard_fab2(sch_1):m_c_ecc(2)" )
			)
			( signal "M_C_ECC<3>"
				( objectStatus "@baseboard_fab2_lib.baseboard_fab2(sch_1):m_c_ecc(3)" )
			)
			( signal "M_C_ECC<4>"
				( objectStatus "@baseboard_fab2_lib.baseboard_fab2(sch_1):m_c_ecc(4)" )
			)
			( signal "M_C_ECC<5>"
				( objectStatus "@baseboard_fab2_lib.baseboard_fab2(sch_1):m_c_ecc(5)" )
			)
			( signal "M_C_ECC<6>"
				( objectStatus "@baseboard_fab2_lib.baseboard_fab2(sch_1):m_c_ecc(6)" )
			)
			( signal "M_C_ECC<7>"
				( objectStatus "@baseboard_fab2_lib.baseboard_fab2(sch_1):m_c_ecc(7)" )
			)
			( signal "M_C_MA<0>"
				( objectStatus "@baseboard_fab2_lib.baseboard_fab2(sch_1):m_c_ma(0)" )
			)
			( signal "M_C_MA<1>"
				( objectStatus "@baseboard_fab2_lib.baseboard_fab2(sch_1):m_c_ma(1)" )
			)
			( signal "M_C_MA<2>"
				( objectStatus "@baseboard_fab2_lib.baseboard_fab2(sch_1):m_c_ma(2)" )
			)
			( signal "M_C_MA<3>"
				( objectStatus "@baseboard_fab2_lib.baseboard_fab2(sch_1):m_c_ma(3)" )
			)
			( signal "M_C_MA<4>"
				( objectStatus "@baseboard_fab2_lib.baseboard_fab2(sch_1):m_c_ma(4)" )
			)
			( signal "M_C_MA<5>"
				( objectStatus "@baseboard_fab2_lib.baseboard_fab2(sch_1):m_c_ma(5)" )
			)
			( signal "M_C_MA<6>"
				( objectStatus "@baseboard_fab2_lib.baseboard_fab2(sch_1):m_c_ma(6)" )
			)
			( signal "M_C_MA<7>"
				( objectStatus "@baseboard_fab2_lib.baseboard_fab2(sch_1):m_c_ma(7)" )
			)
			( signal "M_C_MA<8>"
				( objectStatus "@baseboard_fab2_lib.baseboard_fab2(sch_1):m_c_ma(8)" )
			)
			( signal "M_C_MA<9>"
				( objectStatus "@baseboard_fab2_lib.baseboard_fab2(sch_1):m_c_ma(9)" )
			)
			( signal "M_C_MA<10>"
				( objectStatus "@baseboard_fab2_lib.baseboard_fab2(sch_1):m_c_ma(10)" )
			)
			( signal "M_C_MA<11>"
				( objectStatus "@baseboard_fab2_lib.baseboard_fab2(sch_1):m_c_ma(11)" )
			)
			( signal "M_C_MA<12>"
				( objectStatus "@baseboard_fab2_lib.baseboard_fab2(sch_1):m_c_ma(12)" )
			)
			( signal "M_C_MA<13>"
				( objectStatus "@baseboard_fab2_lib.baseboard_fab2(sch_1):m_c_ma(13)" )
			)
			( signal "M_C_MA<14>"
				( objectStatus "@baseboard_fab2_lib.baseboard_fab2(sch_1):m_c_ma(14)" )
			)
			( signal "M_C_MA<15>"
				( objectStatus "@baseboard_fab2_lib.baseboard_fab2(sch_1):m_c_ma(15)" )
			)
			( signal "M_C_MA<16>"
				( objectStatus "@baseboard_fab2_lib.baseboard_fab2(sch_1):m_c_ma(16)" )
			)
			( signal "M_C_MA<17>"
				( objectStatus "@baseboard_fab2_lib.baseboard_fab2(sch_1):m_c_ma(17)" )
			)
			( signal "M_C_ODT<0>"
				( objectStatus "@baseboard_fab2_lib.baseboard_fab2(sch_1):m_c_odt(0)" )
			)
			( signal "M_C_ODT<1>"
				( objectStatus "@baseboard_fab2_lib.baseboard_fab2(sch_1):m_c_odt(1)" )
			)
			( signal "M_C_ODT<2>"
				( objectStatus "@baseboard_fab2_lib.baseboard_fab2(sch_1):m_c_odt(2)" )
			)
			( signal "M_C_ODT<3>"
				( objectStatus "@baseboard_fab2_lib.baseboard_fab2(sch_1):m_c_odt(3)" )
			)
			( signal "M_C_PAR"
				( objectStatus "@baseboard_fab2_lib.baseboard_fab2(sch_1):m_c_par" )
			)
			( signal "M_D_ACT_N"
				( objectStatus "@baseboard_fab2_lib.baseboard_fab2(sch_1):m_d_act_n" )
			)
			( signal "M_D_ALERT_N"
				( objectStatus "@baseboard_fab2_lib.baseboard_fab2(sch_1):m_d_alert_n" )
			)
			( signal "M_D_BA<0>"
				( objectStatus "@baseboard_fab2_lib.baseboard_fab2(sch_1):m_d_ba(0)" )
			)
			( signal "M_D_BA<1>"
				( objectStatus "@baseboard_fab2_lib.baseboard_fab2(sch_1):m_d_ba(1)" )
			)
			( signal "M_D_BG<0>"
				( objectStatus "@baseboard_fab2_lib.baseboard_fab2(sch_1):m_d_bg(0)" )
			)
			( signal "M_D_BG<1>"
				( objectStatus "@baseboard_fab2_lib.baseboard_fab2(sch_1):m_d_bg(1)" )
			)
			( signal "M_D_C<2>"
				( objectStatus "@baseboard_fab2_lib.baseboard_fab2(sch_1):m_d_c(2)" )
			)
			( signal "M_D_CKE<0>"
				( objectStatus "@baseboard_fab2_lib.baseboard_fab2(sch_1):m_d_cke(0)" )
			)
			( signal "M_D_CKE<1>"
				( objectStatus "@baseboard_fab2_lib.baseboard_fab2(sch_1):m_d_cke(1)" )
			)
			( signal "M_D_CKE<2>"
				( objectStatus "@baseboard_fab2_lib.baseboard_fab2(sch_1):m_d_cke(2)" )
			)
			( signal "M_D_CKE<3>"
				( objectStatus "@baseboard_fab2_lib.baseboard_fab2(sch_1):m_d_cke(3)" )
			)
			( signal "M_D_CLK_DN<0>"
				( objectStatus "@baseboard_fab2_lib.baseboard_fab2(sch_1):m_d_clk_dn(0)" )
			)
			( signal "M_D_CLK_DN<1>"
				( objectStatus "@baseboard_fab2_lib.baseboard_fab2(sch_1):m_d_clk_dn(1)" )
			)
			( signal "M_D_CLK_DN<2>"
				( objectStatus "@baseboard_fab2_lib.baseboard_fab2(sch_1):m_d_clk_dn(2)" )
			)
			( signal "M_D_CLK_DN<3>"
				( objectStatus "@baseboard_fab2_lib.baseboard_fab2(sch_1):m_d_clk_dn(3)" )
			)
			( signal "M_D_CLK_DP<0>"
				( objectStatus "@baseboard_fab2_lib.baseboard_fab2(sch_1):m_d_clk_dp(0)" )
			)
			( signal "M_D_CLK_DP<1>"
				( objectStatus "@baseboard_fab2_lib.baseboard_fab2(sch_1):m_d_clk_dp(1)" )
			)
			( signal "M_D_CLK_DP<2>"
				( objectStatus "@baseboard_fab2_lib.baseboard_fab2(sch_1):m_d_clk_dp(2)" )
			)
			( signal "M_D_CLK_DP<3>"
				( objectStatus "@baseboard_fab2_lib.baseboard_fab2(sch_1):m_d_clk_dp(3)" )
			)
			( signal "M_D_CS_N<0>"
				( objectStatus "@baseboard_fab2_lib.baseboard_fab2(sch_1):m_d_cs_n(0)" )
			)
			( signal "M_D_CS_N<1>"
				( objectStatus "@baseboard_fab2_lib.baseboard_fab2(sch_1):m_d_cs_n(1)" )
			)
			( signal "M_D_CS_N<2>"
				( objectStatus "@baseboard_fab2_lib.baseboard_fab2(sch_1):m_d_cs_n(2)" )
			)
			( signal "M_D_CS_N<3>"
				( objectStatus "@baseboard_fab2_lib.baseboard_fab2(sch_1):m_d_cs_n(3)" )
			)
			( signal "M_D_CS_N<4>"
				( objectStatus "@baseboard_fab2_lib.baseboard_fab2(sch_1):m_d_cs_n(4)" )
			)
			( signal "M_D_CS_N<5>"
				( objectStatus "@baseboard_fab2_lib.baseboard_fab2(sch_1):m_d_cs_n(5)" )
			)
			( signal "M_D_CS_N<6>"
				( objectStatus "@baseboard_fab2_lib.baseboard_fab2(sch_1):m_d_cs_n(6)" )
			)
			( signal "M_D_CS_N<7>"
				( objectStatus "@baseboard_fab2_lib.baseboard_fab2(sch_1):m_d_cs_n(7)" )
			)
			( signal "M_D_DQ<0>"
				( objectStatus "@baseboard_fab2_lib.baseboard_fab2(sch_1):m_d_dq(0)" )
			)
			( signal "M_D_DQ<1>"
				( objectStatus "@baseboard_fab2_lib.baseboard_fab2(sch_1):m_d_dq(1)" )
			)
			( signal "M_D_DQ<2>"
				( objectStatus "@baseboard_fab2_lib.baseboard_fab2(sch_1):m_d_dq(2)" )
			)
			( signal "M_D_DQ<3>"
				( objectStatus "@baseboard_fab2_lib.baseboard_fab2(sch_1):m_d_dq(3)" )
			)
			( signal "M_D_DQ<4>"
				( objectStatus "@baseboard_fab2_lib.baseboard_fab2(sch_1):m_d_dq(4)" )
			)
			( signal "M_D_DQ<5>"
				( objectStatus "@baseboard_fab2_lib.baseboard_fab2(sch_1):m_d_dq(5)" )
			)
			( signal "M_D_DQ<6>"
				( objectStatus "@baseboard_fab2_lib.baseboard_fab2(sch_1):m_d_dq(6)" )
			)
			( signal "M_D_DQ<7>"
				( objectStatus "@baseboard_fab2_lib.baseboard_fab2(sch_1):m_d_dq(7)" )
			)
			( signal "M_D_DQ<8>"
				( objectStatus "@baseboard_fab2_lib.baseboard_fab2(sch_1):m_d_dq(8)" )
			)
			( signal "M_D_DQ<9>"
				( objectStatus "@baseboard_fab2_lib.baseboard_fab2(sch_1):m_d_dq(9)" )
			)
			( signal "M_D_DQ<10>"
				( objectStatus "@baseboard_fab2_lib.baseboard_fab2(sch_1):m_d_dq(10)" )
			)
			( signal "M_D_DQ<11>"
				( objectStatus "@baseboard_fab2_lib.baseboard_fab2(sch_1):m_d_dq(11)" )
			)
			( signal "M_D_DQ<12>"
				( objectStatus "@baseboard_fab2_lib.baseboard_fab2(sch_1):m_d_dq(12)" )
			)
			( signal "M_D_DQ<13>"
				( objectStatus "@baseboard_fab2_lib.baseboard_fab2(sch_1):m_d_dq(13)" )
			)
			( signal "M_D_DQ<14>"
				( objectStatus "@baseboard_fab2_lib.baseboard_fab2(sch_1):m_d_dq(14)" )
			)
			( signal "M_D_DQ<15>"
				( objectStatus "@baseboard_fab2_lib.baseboard_fab2(sch_1):m_d_dq(15)" )
			)
			( signal "M_D_DQ<16>"
				( objectStatus "@baseboard_fab2_lib.baseboard_fab2(sch_1):m_d_dq(16)" )
			)
			( signal "M_D_DQ<17>"
				( objectStatus "@baseboard_fab2_lib.baseboard_fab2(sch_1):m_d_dq(17)" )
			)
			( signal "M_D_DQ<18>"
				( objectStatus "@baseboard_fab2_lib.baseboard_fab2(sch_1):m_d_dq(18)" )
			)
			( signal "M_D_DQ<19>"
				( objectStatus "@baseboard_fab2_lib.baseboard_fab2(sch_1):m_d_dq(19)" )
			)
			( signal "M_D_DQ<20>"
				( objectStatus "@baseboard_fab2_lib.baseboard_fab2(sch_1):m_d_dq(20)" )
			)
			( signal "M_D_DQ<21>"
				( objectStatus "@baseboard_fab2_lib.baseboard_fab2(sch_1):m_d_dq(21)" )
			)
			( signal "M_D_DQ<22>"
				( objectStatus "@baseboard_fab2_lib.baseboard_fab2(sch_1):m_d_dq(22)" )
			)
			( signal "M_D_DQ<23>"
				( objectStatus "@baseboard_fab2_lib.baseboard_fab2(sch_1):m_d_dq(23)" )
			)
			( signal "M_D_DQ<24>"
				( objectStatus "@baseboard_fab2_lib.baseboard_fab2(sch_1):m_d_dq(24)" )
			)
			( signal "M_D_DQ<25>"
				( objectStatus "@baseboard_fab2_lib.baseboard_fab2(sch_1):m_d_dq(25)" )
			)
			( signal "M_D_DQ<26>"
				( objectStatus "@baseboard_fab2_lib.baseboard_fab2(sch_1):m_d_dq(26)" )
			)
			( signal "M_D_DQ<27>"
				( objectStatus "@baseboard_fab2_lib.baseboard_fab2(sch_1):m_d_dq(27)" )
			)
			( signal "M_D_DQ<28>"
				( objectStatus "@baseboard_fab2_lib.baseboard_fab2(sch_1):m_d_dq(28)" )
			)
			( signal "M_D_DQ<29>"
				( objectStatus "@baseboard_fab2_lib.baseboard_fab2(sch_1):m_d_dq(29)" )
			)
			( signal "M_D_DQ<30>"
				( objectStatus "@baseboard_fab2_lib.baseboard_fab2(sch_1):m_d_dq(30)" )
			)
			( signal "M_D_DQ<31>"
				( objectStatus "@baseboard_fab2_lib.baseboard_fab2(sch_1):m_d_dq(31)" )
			)
			( signal "M_D_DQ<32>"
				( objectStatus "@baseboard_fab2_lib.baseboard_fab2(sch_1):m_d_dq(32)" )
			)
			( signal "M_D_DQ<33>"
				( objectStatus "@baseboard_fab2_lib.baseboard_fab2(sch_1):m_d_dq(33)" )
			)
			( signal "M_D_DQ<34>"
				( objectStatus "@baseboard_fab2_lib.baseboard_fab2(sch_1):m_d_dq(34)" )
			)
			( signal "M_D_DQ<35>"
				( objectStatus "@baseboard_fab2_lib.baseboard_fab2(sch_1):m_d_dq(35)" )
			)
			( signal "M_D_DQ<36>"
				( objectStatus "@baseboard_fab2_lib.baseboard_fab2(sch_1):m_d_dq(36)" )
			)
			( signal "M_D_DQ<37>"
				( objectStatus "@baseboard_fab2_lib.baseboard_fab2(sch_1):m_d_dq(37)" )
			)
			( signal "M_D_DQ<38>"
				( objectStatus "@baseboard_fab2_lib.baseboard_fab2(sch_1):m_d_dq(38)" )
			)
			( signal "M_D_DQ<39>"
				( objectStatus "@baseboard_fab2_lib.baseboard_fab2(sch_1):m_d_dq(39)" )
			)
			( signal "M_D_DQ<40>"
				( objectStatus "@baseboard_fab2_lib.baseboard_fab2(sch_1):m_d_dq(40)" )
			)
			( signal "M_D_DQ<41>"
				( objectStatus "@baseboard_fab2_lib.baseboard_fab2(sch_1):m_d_dq(41)" )
			)
			( signal "M_D_DQ<42>"
				( objectStatus "@baseboard_fab2_lib.baseboard_fab2(sch_1):m_d_dq(42)" )
			)
			( signal "M_D_DQ<43>"
				( objectStatus "@baseboard_fab2_lib.baseboard_fab2(sch_1):m_d_dq(43)" )
			)
			( signal "M_D_DQ<44>"
				( objectStatus "@baseboard_fab2_lib.baseboard_fab2(sch_1):m_d_dq(44)" )
			)
			( signal "M_D_DQ<45>"
				( objectStatus "@baseboard_fab2_lib.baseboard_fab2(sch_1):m_d_dq(45)" )
			)
			( signal "M_D_DQ<46>"
				( objectStatus "@baseboard_fab2_lib.baseboard_fab2(sch_1):m_d_dq(46)" )
			)
			( signal "M_D_DQ<47>"
				( objectStatus "@baseboard_fab2_lib.baseboard_fab2(sch_1):m_d_dq(47)" )
			)
			( signal "M_D_DQ<48>"
				( objectStatus "@baseboard_fab2_lib.baseboard_fab2(sch_1):m_d_dq(48)" )
			)
			( signal "M_D_DQ<49>"
				( objectStatus "@baseboard_fab2_lib.baseboard_fab2(sch_1):m_d_dq(49)" )
			)
			( signal "M_D_DQ<50>"
				( objectStatus "@baseboard_fab2_lib.baseboard_fab2(sch_1):m_d_dq(50)" )
			)
			( signal "M_D_DQ<51>"
				( objectStatus "@baseboard_fab2_lib.baseboard_fab2(sch_1):m_d_dq(51)" )
			)
			( signal "M_D_DQ<52>"
				( objectStatus "@baseboard_fab2_lib.baseboard_fab2(sch_1):m_d_dq(52)" )
			)
			( signal "M_D_DQ<53>"
				( objectStatus "@baseboard_fab2_lib.baseboard_fab2(sch_1):m_d_dq(53)" )
			)
			( signal "M_D_DQ<54>"
				( objectStatus "@baseboard_fab2_lib.baseboard_fab2(sch_1):m_d_dq(54)" )
			)
			( signal "M_D_DQ<55>"
				( objectStatus "@baseboard_fab2_lib.baseboard_fab2(sch_1):m_d_dq(55)" )
			)
			( signal "M_D_DQ<56>"
				( objectStatus "@baseboard_fab2_lib.baseboard_fab2(sch_1):m_d_dq(56)" )
			)
			( signal "M_D_DQ<57>"
				( objectStatus "@baseboard_fab2_lib.baseboard_fab2(sch_1):m_d_dq(57)" )
			)
			( signal "M_D_DQ<58>"
				( objectStatus "@baseboard_fab2_lib.baseboard_fab2(sch_1):m_d_dq(58)" )
			)
			( signal "M_D_DQ<59>"
				( objectStatus "@baseboard_fab2_lib.baseboard_fab2(sch_1):m_d_dq(59)" )
			)
			( signal "M_D_DQ<60>"
				( objectStatus "@baseboard_fab2_lib.baseboard_fab2(sch_1):m_d_dq(60)" )
			)
			( signal "M_D_DQ<61>"
				( objectStatus "@baseboard_fab2_lib.baseboard_fab2(sch_1):m_d_dq(61)" )
			)
			( signal "M_D_DQ<62>"
				( objectStatus "@baseboard_fab2_lib.baseboard_fab2(sch_1):m_d_dq(62)" )
			)
			( signal "M_D_DQ<63>"
				( objectStatus "@baseboard_fab2_lib.baseboard_fab2(sch_1):m_d_dq(63)" )
			)
			( signal "M_D_DQS_DN<0>"
				( objectStatus "@baseboard_fab2_lib.baseboard_fab2(sch_1):m_d_dqs_dn(0)" )
			)
			( signal "M_D_DQS_DN<1>"
				( objectStatus "@baseboard_fab2_lib.baseboard_fab2(sch_1):m_d_dqs_dn(1)" )
			)
			( signal "M_D_DQS_DN<2>"
				( objectStatus "@baseboard_fab2_lib.baseboard_fab2(sch_1):m_d_dqs_dn(2)" )
			)
			( signal "M_D_DQS_DN<3>"
				( objectStatus "@baseboard_fab2_lib.baseboard_fab2(sch_1):m_d_dqs_dn(3)" )
			)
			( signal "M_D_DQS_DN<4>"
				( objectStatus "@baseboard_fab2_lib.baseboard_fab2(sch_1):m_d_dqs_dn(4)" )
			)
			( signal "M_D_DQS_DN<5>"
				( objectStatus "@baseboard_fab2_lib.baseboard_fab2(sch_1):m_d_dqs_dn(5)" )
			)
			( signal "M_D_DQS_DN<6>"
				( objectStatus "@baseboard_fab2_lib.baseboard_fab2(sch_1):m_d_dqs_dn(6)" )
			)
			( signal "M_D_DQS_DN<7>"
				( objectStatus "@baseboard_fab2_lib.baseboard_fab2(sch_1):m_d_dqs_dn(7)" )
			)
			( signal "M_D_DQS_DN<8>"
				( objectStatus "@baseboard_fab2_lib.baseboard_fab2(sch_1):m_d_dqs_dn(8)" )
			)
			( signal "M_D_DQS_DN<9>"
				( objectStatus "@baseboard_fab2_lib.baseboard_fab2(sch_1):m_d_dqs_dn(9)" )
			)
			( signal "M_D_DQS_DN<10>"
				( objectStatus "@baseboard_fab2_lib.baseboard_fab2(sch_1):m_d_dqs_dn(10)" )
			)
			( signal "M_D_DQS_DN<11>"
				( objectStatus "@baseboard_fab2_lib.baseboard_fab2(sch_1):m_d_dqs_dn(11)" )
			)
			( signal "M_D_DQS_DN<12>"
				( objectStatus "@baseboard_fab2_lib.baseboard_fab2(sch_1):m_d_dqs_dn(12)" )
			)
			( signal "M_D_DQS_DN<13>"
				( objectStatus "@baseboard_fab2_lib.baseboard_fab2(sch_1):m_d_dqs_dn(13)" )
			)
			( signal "M_D_DQS_DN<14>"
				( objectStatus "@baseboard_fab2_lib.baseboard_fab2(sch_1):m_d_dqs_dn(14)" )
			)
			( signal "M_D_DQS_DN<15>"
				( objectStatus "@baseboard_fab2_lib.baseboard_fab2(sch_1):m_d_dqs_dn(15)" )
			)
			( signal "M_D_DQS_DN<16>"
				( objectStatus "@baseboard_fab2_lib.baseboard_fab2(sch_1):m_d_dqs_dn(16)" )
			)
			( signal "M_D_DQS_DN<17>"
				( objectStatus "@baseboard_fab2_lib.baseboard_fab2(sch_1):m_d_dqs_dn(17)" )
			)
			( signal "M_D_DQS_DP<0>"
				( objectStatus "@baseboard_fab2_lib.baseboard_fab2(sch_1):m_d_dqs_dp(0)" )
			)
			( signal "M_D_DQS_DP<1>"
				( objectStatus "@baseboard_fab2_lib.baseboard_fab2(sch_1):m_d_dqs_dp(1)" )
			)
			( signal "M_D_DQS_DP<2>"
				( objectStatus "@baseboard_fab2_lib.baseboard_fab2(sch_1):m_d_dqs_dp(2)" )
			)
			( signal "M_D_DQS_DP<3>"
				( objectStatus "@baseboard_fab2_lib.baseboard_fab2(sch_1):m_d_dqs_dp(3)" )
			)
			( signal "M_D_DQS_DP<4>"
				( objectStatus "@baseboard_fab2_lib.baseboard_fab2(sch_1):m_d_dqs_dp(4)" )
			)
			( signal "M_D_DQS_DP<5>"
				( objectStatus "@baseboard_fab2_lib.baseboard_fab2(sch_1):m_d_dqs_dp(5)" )
			)
			( signal "M_D_DQS_DP<6>"
				( objectStatus "@baseboard_fab2_lib.baseboard_fab2(sch_1):m_d_dqs_dp(6)" )
			)
			( signal "M_D_DQS_DP<7>"
				( objectStatus "@baseboard_fab2_lib.baseboard_fab2(sch_1):m_d_dqs_dp(7)" )
			)
			( signal "M_D_DQS_DP<8>"
				( objectStatus "@baseboard_fab2_lib.baseboard_fab2(sch_1):m_d_dqs_dp(8)" )
			)
			( signal "M_D_DQS_DP<9>"
				( objectStatus "@baseboard_fab2_lib.baseboard_fab2(sch_1):m_d_dqs_dp(9)" )
			)
			( signal "M_D_DQS_DP<10>"
				( objectStatus "@baseboard_fab2_lib.baseboard_fab2(sch_1):m_d_dqs_dp(10)" )
			)
			( signal "M_D_DQS_DP<11>"
				( objectStatus "@baseboard_fab2_lib.baseboard_fab2(sch_1):m_d_dqs_dp(11)" )
			)
			( signal "M_D_DQS_DP<12>"
				( objectStatus "@baseboard_fab2_lib.baseboard_fab2(sch_1):m_d_dqs_dp(12)" )
			)
			( signal "M_D_DQS_DP<13>"
				( objectStatus "@baseboard_fab2_lib.baseboard_fab2(sch_1):m_d_dqs_dp(13)" )
			)
			( signal "M_D_DQS_DP<14>"
				( objectStatus "@baseboard_fab2_lib.baseboard_fab2(sch_1):m_d_dqs_dp(14)" )
			)
			( signal "M_D_DQS_DP<15>"
				( objectStatus "@baseboard_fab2_lib.baseboard_fab2(sch_1):m_d_dqs_dp(15)" )
			)
			( signal "M_D_DQS_DP<16>"
				( objectStatus "@baseboard_fab2_lib.baseboard_fab2(sch_1):m_d_dqs_dp(16)" )
			)
			( signal "M_D_DQS_DP<17>"
				( objectStatus "@baseboard_fab2_lib.baseboard_fab2(sch_1):m_d_dqs_dp(17)" )
			)
			( signal "M_D_ECC<0>"
				( objectStatus "@baseboard_fab2_lib.baseboard_fab2(sch_1):m_d_ecc(0)" )
			)
			( signal "M_D_ECC<1>"
				( objectStatus "@baseboard_fab2_lib.baseboard_fab2(sch_1):m_d_ecc(1)" )
			)
			( signal "M_D_ECC<2>"
				( objectStatus "@baseboard_fab2_lib.baseboard_fab2(sch_1):m_d_ecc(2)" )
			)
			( signal "M_D_ECC<3>"
				( objectStatus "@baseboard_fab2_lib.baseboard_fab2(sch_1):m_d_ecc(3)" )
			)
			( signal "M_D_ECC<4>"
				( objectStatus "@baseboard_fab2_lib.baseboard_fab2(sch_1):m_d_ecc(4)" )
			)
			( signal "M_D_ECC<5>"
				( objectStatus "@baseboard_fab2_lib.baseboard_fab2(sch_1):m_d_ecc(5)" )
			)
			( signal "M_D_ECC<6>"
				( objectStatus "@baseboard_fab2_lib.baseboard_fab2(sch_1):m_d_ecc(6)" )
			)
			( signal "M_D_ECC<7>"
				( objectStatus "@baseboard_fab2_lib.baseboard_fab2(sch_1):m_d_ecc(7)" )
			)
			( signal "M_D_MA<0>"
				( objectStatus "@baseboard_fab2_lib.baseboard_fab2(sch_1):m_d_ma(0)" )
			)
			( signal "M_D_MA<1>"
				( objectStatus "@baseboard_fab2_lib.baseboard_fab2(sch_1):m_d_ma(1)" )
			)
			( signal "M_D_MA<2>"
				( objectStatus "@baseboard_fab2_lib.baseboard_fab2(sch_1):m_d_ma(2)" )
			)
			( signal "M_D_MA<3>"
				( objectStatus "@baseboard_fab2_lib.baseboard_fab2(sch_1):m_d_ma(3)" )
			)
			( signal "M_D_MA<4>"
				( objectStatus "@baseboard_fab2_lib.baseboard_fab2(sch_1):m_d_ma(4)" )
			)
			( signal "M_D_MA<5>"
				( objectStatus "@baseboard_fab2_lib.baseboard_fab2(sch_1):m_d_ma(5)" )
			)
			( signal "M_D_MA<6>"
				( objectStatus "@baseboard_fab2_lib.baseboard_fab2(sch_1):m_d_ma(6)" )
			)
			( signal "M_D_MA<7>"
				( objectStatus "@baseboard_fab2_lib.baseboard_fab2(sch_1):m_d_ma(7)" )
			)
			( signal "M_D_MA<8>"
				( objectStatus "@baseboard_fab2_lib.baseboard_fab2(sch_1):m_d_ma(8)" )
			)
			( signal "M_D_MA<9>"
				( objectStatus "@baseboard_fab2_lib.baseboard_fab2(sch_1):m_d_ma(9)" )
			)
			( signal "M_D_MA<10>"
				( objectStatus "@baseboard_fab2_lib.baseboard_fab2(sch_1):m_d_ma(10)" )
			)
			( signal "M_D_MA<11>"
				( objectStatus "@baseboard_fab2_lib.baseboard_fab2(sch_1):m_d_ma(11)" )
			)
			( signal "M_D_MA<12>"
				( objectStatus "@baseboard_fab2_lib.baseboard_fab2(sch_1):m_d_ma(12)" )
			)
			( signal "M_D_MA<13>"
				( objectStatus "@baseboard_fab2_lib.baseboard_fab2(sch_1):m_d_ma(13)" )
			)
			( signal "M_D_MA<14>"
				( objectStatus "@baseboard_fab2_lib.baseboard_fab2(sch_1):m_d_ma(14)" )
			)
			( signal "M_D_MA<15>"
				( objectStatus "@baseboard_fab2_lib.baseboard_fab2(sch_1):m_d_ma(15)" )
			)
			( signal "M_D_MA<16>"
				( objectStatus "@baseboard_fab2_lib.baseboard_fab2(sch_1):m_d_ma(16)" )
			)
			( signal "M_D_MA<17>"
				( objectStatus "@baseboard_fab2_lib.baseboard_fab2(sch_1):m_d_ma(17)" )
			)
			( signal "M_D_ODT<0>"
				( objectStatus "@baseboard_fab2_lib.baseboard_fab2(sch_1):m_d_odt(0)" )
			)
			( signal "M_D_ODT<1>"
				( objectStatus "@baseboard_fab2_lib.baseboard_fab2(sch_1):m_d_odt(1)" )
			)
			( signal "M_D_ODT<2>"
				( objectStatus "@baseboard_fab2_lib.baseboard_fab2(sch_1):m_d_odt(2)" )
			)
			( signal "M_D_ODT<3>"
				( objectStatus "@baseboard_fab2_lib.baseboard_fab2(sch_1):m_d_odt(3)" )
			)
			( signal "M_D_PAR"
				( objectStatus "@baseboard_fab2_lib.baseboard_fab2(sch_1):m_d_par" )
			)
			( signal "M_E_ACT_N"
				( objectStatus "@baseboard_fab2_lib.baseboard_fab2(sch_1):m_e_act_n" )
			)
			( signal "M_E_ALERT_N"
				( objectStatus "@baseboard_fab2_lib.baseboard_fab2(sch_1):m_e_alert_n" )
			)
			( signal "M_E_BA<0>"
				( objectStatus "@baseboard_fab2_lib.baseboard_fab2(sch_1):m_e_ba(0)" )
			)
			( signal "M_E_BA<1>"
				( objectStatus "@baseboard_fab2_lib.baseboard_fab2(sch_1):m_e_ba(1)" )
			)
			( signal "M_E_BG<0>"
				( objectStatus "@baseboard_fab2_lib.baseboard_fab2(sch_1):m_e_bg(0)" )
			)
			( signal "M_E_BG<1>"
				( objectStatus "@baseboard_fab2_lib.baseboard_fab2(sch_1):m_e_bg(1)" )
			)
			( signal "M_E_C<2>"
				( objectStatus "@baseboard_fab2_lib.baseboard_fab2(sch_1):m_e_c(2)" )
			)
			( signal "M_E_CKE<0>"
				( objectStatus "@baseboard_fab2_lib.baseboard_fab2(sch_1):m_e_cke(0)" )
			)
			( signal "M_E_CKE<1>"
				( objectStatus "@baseboard_fab2_lib.baseboard_fab2(sch_1):m_e_cke(1)" )
			)
			( signal "M_E_CKE<2>"
				( objectStatus "@baseboard_fab2_lib.baseboard_fab2(sch_1):m_e_cke(2)" )
			)
			( signal "M_E_CKE<3>"
				( objectStatus "@baseboard_fab2_lib.baseboard_fab2(sch_1):m_e_cke(3)" )
			)
			( signal "M_E_CLK_DN<0>"
				( objectStatus "@baseboard_fab2_lib.baseboard_fab2(sch_1):m_e_clk_dn(0)" )
			)
			( signal "M_E_CLK_DN<1>"
				( objectStatus "@baseboard_fab2_lib.baseboard_fab2(sch_1):m_e_clk_dn(1)" )
			)
			( signal "M_E_CLK_DN<2>"
				( objectStatus "@baseboard_fab2_lib.baseboard_fab2(sch_1):m_e_clk_dn(2)" )
			)
			( signal "M_E_CLK_DN<3>"
				( objectStatus "@baseboard_fab2_lib.baseboard_fab2(sch_1):m_e_clk_dn(3)" )
			)
			( signal "M_E_CLK_DP<0>"
				( objectStatus "@baseboard_fab2_lib.baseboard_fab2(sch_1):m_e_clk_dp(0)" )
			)
			( signal "M_E_CLK_DP<1>"
				( objectStatus "@baseboard_fab2_lib.baseboard_fab2(sch_1):m_e_clk_dp(1)" )
			)
			( signal "M_E_CLK_DP<2>"
				( objectStatus "@baseboard_fab2_lib.baseboard_fab2(sch_1):m_e_clk_dp(2)" )
			)
			( signal "M_E_CLK_DP<3>"
				( objectStatus "@baseboard_fab2_lib.baseboard_fab2(sch_1):m_e_clk_dp(3)" )
			)
			( signal "M_E_CS_N<0>"
				( objectStatus "@baseboard_fab2_lib.baseboard_fab2(sch_1):m_e_cs_n(0)" )
			)
			( signal "M_E_CS_N<1>"
				( objectStatus "@baseboard_fab2_lib.baseboard_fab2(sch_1):m_e_cs_n(1)" )
			)
			( signal "M_E_CS_N<2>"
				( objectStatus "@baseboard_fab2_lib.baseboard_fab2(sch_1):m_e_cs_n(2)" )
			)
			( signal "M_E_CS_N<3>"
				( objectStatus "@baseboard_fab2_lib.baseboard_fab2(sch_1):m_e_cs_n(3)" )
			)
			( signal "M_E_CS_N<4>"
				( objectStatus "@baseboard_fab2_lib.baseboard_fab2(sch_1):m_e_cs_n(4)" )
			)
			( signal "M_E_CS_N<5>"
				( objectStatus "@baseboard_fab2_lib.baseboard_fab2(sch_1):m_e_cs_n(5)" )
			)
			( signal "M_E_CS_N<6>"
				( objectStatus "@baseboard_fab2_lib.baseboard_fab2(sch_1):m_e_cs_n(6)" )
			)
			( signal "M_E_CS_N<7>"
				( objectStatus "@baseboard_fab2_lib.baseboard_fab2(sch_1):m_e_cs_n(7)" )
			)
			( signal "M_E_DQ<0>"
				( objectStatus "@baseboard_fab2_lib.baseboard_fab2(sch_1):m_e_dq(0)" )
			)
			( signal "M_E_DQ<1>"
				( objectStatus "@baseboard_fab2_lib.baseboard_fab2(sch_1):m_e_dq(1)" )
			)
			( signal "M_E_DQ<2>"
				( objectStatus "@baseboard_fab2_lib.baseboard_fab2(sch_1):m_e_dq(2)" )
			)
			( signal "M_E_DQ<3>"
				( objectStatus "@baseboard_fab2_lib.baseboard_fab2(sch_1):m_e_dq(3)" )
			)
			( signal "M_E_DQ<4>"
				( objectStatus "@baseboard_fab2_lib.baseboard_fab2(sch_1):m_e_dq(4)" )
			)
			( signal "M_E_DQ<5>"
				( objectStatus "@baseboard_fab2_lib.baseboard_fab2(sch_1):m_e_dq(5)" )
			)
			( signal "M_E_DQ<6>"
				( objectStatus "@baseboard_fab2_lib.baseboard_fab2(sch_1):m_e_dq(6)" )
			)
			( signal "M_E_DQ<7>"
				( objectStatus "@baseboard_fab2_lib.baseboard_fab2(sch_1):m_e_dq(7)" )
			)
			( signal "M_E_DQ<8>"
				( objectStatus "@baseboard_fab2_lib.baseboard_fab2(sch_1):m_e_dq(8)" )
			)
			( signal "M_E_DQ<9>"
				( objectStatus "@baseboard_fab2_lib.baseboard_fab2(sch_1):m_e_dq(9)" )
			)
			( signal "M_E_DQ<10>"
				( objectStatus "@baseboard_fab2_lib.baseboard_fab2(sch_1):m_e_dq(10)" )
			)
			( signal "M_E_DQ<11>"
				( objectStatus "@baseboard_fab2_lib.baseboard_fab2(sch_1):m_e_dq(11)" )
			)
			( signal "M_E_DQ<12>"
				( objectStatus "@baseboard_fab2_lib.baseboard_fab2(sch_1):m_e_dq(12)" )
			)
			( signal "M_E_DQ<13>"
				( objectStatus "@baseboard_fab2_lib.baseboard_fab2(sch_1):m_e_dq(13)" )
			)
			( signal "M_E_DQ<14>"
				( objectStatus "@baseboard_fab2_lib.baseboard_fab2(sch_1):m_e_dq(14)" )
			)
			( signal "M_E_DQ<15>"
				( objectStatus "@baseboard_fab2_lib.baseboard_fab2(sch_1):m_e_dq(15)" )
			)
			( signal "M_E_DQ<16>"
				( objectStatus "@baseboard_fab2_lib.baseboard_fab2(sch_1):m_e_dq(16)" )
			)
			( signal "M_E_DQ<17>"
				( objectStatus "@baseboard_fab2_lib.baseboard_fab2(sch_1):m_e_dq(17)" )
			)
			( signal "M_E_DQ<18>"
				( objectStatus "@baseboard_fab2_lib.baseboard_fab2(sch_1):m_e_dq(18)" )
			)
			( signal "M_E_DQ<19>"
				( objectStatus "@baseboard_fab2_lib.baseboard_fab2(sch_1):m_e_dq(19)" )
			)
			( signal "M_E_DQ<20>"
				( objectStatus "@baseboard_fab2_lib.baseboard_fab2(sch_1):m_e_dq(20)" )
			)
			( signal "M_E_DQ<21>"
				( objectStatus "@baseboard_fab2_lib.baseboard_fab2(sch_1):m_e_dq(21)" )
			)
			( signal "M_E_DQ<22>"
				( objectStatus "@baseboard_fab2_lib.baseboard_fab2(sch_1):m_e_dq(22)" )
			)
			( signal "M_E_DQ<23>"
				( objectStatus "@baseboard_fab2_lib.baseboard_fab2(sch_1):m_e_dq(23)" )
			)
			( signal "M_E_DQ<24>"
				( objectStatus "@baseboard_fab2_lib.baseboard_fab2(sch_1):m_e_dq(24)" )
			)
			( signal "M_E_DQ<25>"
				( objectStatus "@baseboard_fab2_lib.baseboard_fab2(sch_1):m_e_dq(25)" )
			)
			( signal "M_E_DQ<26>"
				( objectStatus "@baseboard_fab2_lib.baseboard_fab2(sch_1):m_e_dq(26)" )
			)
			( signal "M_E_DQ<27>"
				( objectStatus "@baseboard_fab2_lib.baseboard_fab2(sch_1):m_e_dq(27)" )
			)
			( signal "M_E_DQ<28>"
				( objectStatus "@baseboard_fab2_lib.baseboard_fab2(sch_1):m_e_dq(28)" )
			)
			( signal "M_E_DQ<29>"
				( objectStatus "@baseboard_fab2_lib.baseboard_fab2(sch_1):m_e_dq(29)" )
			)
			( signal "M_E_DQ<30>"
				( objectStatus "@baseboard_fab2_lib.baseboard_fab2(sch_1):m_e_dq(30)" )
			)
			( signal "M_E_DQ<31>"
				( objectStatus "@baseboard_fab2_lib.baseboard_fab2(sch_1):m_e_dq(31)" )
			)
			( signal "M_E_DQ<32>"
				( objectStatus "@baseboard_fab2_lib.baseboard_fab2(sch_1):m_e_dq(32)" )
			)
			( signal "M_E_DQ<33>"
				( objectStatus "@baseboard_fab2_lib.baseboard_fab2(sch_1):m_e_dq(33)" )
			)
			( signal "M_E_DQ<34>"
				( objectStatus "@baseboard_fab2_lib.baseboard_fab2(sch_1):m_e_dq(34)" )
			)
			( signal "M_E_DQ<35>"
				( objectStatus "@baseboard_fab2_lib.baseboard_fab2(sch_1):m_e_dq(35)" )
			)
			( signal "M_E_DQ<36>"
				( objectStatus "@baseboard_fab2_lib.baseboard_fab2(sch_1):m_e_dq(36)" )
			)
			( signal "M_E_DQ<37>"
				( objectStatus "@baseboard_fab2_lib.baseboard_fab2(sch_1):m_e_dq(37)" )
			)
			( signal "M_E_DQ<38>"
				( objectStatus "@baseboard_fab2_lib.baseboard_fab2(sch_1):m_e_dq(38)" )
			)
			( signal "M_E_DQ<39>"
				( objectStatus "@baseboard_fab2_lib.baseboard_fab2(sch_1):m_e_dq(39)" )
			)
			( signal "M_E_DQ<40>"
				( objectStatus "@baseboard_fab2_lib.baseboard_fab2(sch_1):m_e_dq(40)" )
			)
			( signal "M_E_DQ<41>"
				( objectStatus "@baseboard_fab2_lib.baseboard_fab2(sch_1):m_e_dq(41)" )
			)
			( signal "M_E_DQ<42>"
				( objectStatus "@baseboard_fab2_lib.baseboard_fab2(sch_1):m_e_dq(42)" )
			)
			( signal "M_E_DQ<43>"
				( objectStatus "@baseboard_fab2_lib.baseboard_fab2(sch_1):m_e_dq(43)" )
			)
			( signal "M_E_DQ<44>"
				( objectStatus "@baseboard_fab2_lib.baseboard_fab2(sch_1):m_e_dq(44)" )
			)
			( signal "M_E_DQ<45>"
				( objectStatus "@baseboard_fab2_lib.baseboard_fab2(sch_1):m_e_dq(45)" )
			)
			( signal "M_E_DQ<46>"
				( objectStatus "@baseboard_fab2_lib.baseboard_fab2(sch_1):m_e_dq(46)" )
			)
			( signal "M_E_DQ<47>"
				( objectStatus "@baseboard_fab2_lib.baseboard_fab2(sch_1):m_e_dq(47)" )
			)
			( signal "M_E_DQ<48>"
				( objectStatus "@baseboard_fab2_lib.baseboard_fab2(sch_1):m_e_dq(48)" )
			)
			( signal "M_E_DQ<49>"
				( objectStatus "@baseboard_fab2_lib.baseboard_fab2(sch_1):m_e_dq(49)" )
			)
			( signal "M_E_DQ<50>"
				( objectStatus "@baseboard_fab2_lib.baseboard_fab2(sch_1):m_e_dq(50)" )
			)
			( signal "M_E_DQ<51>"
				( objectStatus "@baseboard_fab2_lib.baseboard_fab2(sch_1):m_e_dq(51)" )
			)
			( signal "M_E_DQ<52>"
				( objectStatus "@baseboard_fab2_lib.baseboard_fab2(sch_1):m_e_dq(52)" )
			)
			( signal "M_E_DQ<53>"
				( objectStatus "@baseboard_fab2_lib.baseboard_fab2(sch_1):m_e_dq(53)" )
			)
			( signal "M_E_DQ<54>"
				( objectStatus "@baseboard_fab2_lib.baseboard_fab2(sch_1):m_e_dq(54)" )
			)
			( signal "M_E_DQ<55>"
				( objectStatus "@baseboard_fab2_lib.baseboard_fab2(sch_1):m_e_dq(55)" )
			)
			( signal "M_E_DQ<56>"
				( objectStatus "@baseboard_fab2_lib.baseboard_fab2(sch_1):m_e_dq(56)" )
			)
			( signal "M_E_DQ<57>"
				( objectStatus "@baseboard_fab2_lib.baseboard_fab2(sch_1):m_e_dq(57)" )
			)
			( signal "M_E_DQ<58>"
				( objectStatus "@baseboard_fab2_lib.baseboard_fab2(sch_1):m_e_dq(58)" )
			)
			( signal "M_E_DQ<59>"
				( objectStatus "@baseboard_fab2_lib.baseboard_fab2(sch_1):m_e_dq(59)" )
			)
			( signal "M_E_DQ<60>"
				( objectStatus "@baseboard_fab2_lib.baseboard_fab2(sch_1):m_e_dq(60)" )
			)
			( signal "M_E_DQ<61>"
				( objectStatus "@baseboard_fab2_lib.baseboard_fab2(sch_1):m_e_dq(61)" )
			)
			( signal "M_E_DQ<62>"
				( objectStatus "@baseboard_fab2_lib.baseboard_fab2(sch_1):m_e_dq(62)" )
			)
			( signal "M_E_DQ<63>"
				( objectStatus "@baseboard_fab2_lib.baseboard_fab2(sch_1):m_e_dq(63)" )
			)
			( signal "M_E_DQS_DN<0>"
				( objectStatus "@baseboard_fab2_lib.baseboard_fab2(sch_1):m_e_dqs_dn(0)" )
			)
			( signal "M_E_DQS_DN<1>"
				( objectStatus "@baseboard_fab2_lib.baseboard_fab2(sch_1):m_e_dqs_dn(1)" )
			)
			( signal "M_E_DQS_DN<2>"
				( objectStatus "@baseboard_fab2_lib.baseboard_fab2(sch_1):m_e_dqs_dn(2)" )
			)
			( signal "M_E_DQS_DN<3>"
				( objectStatus "@baseboard_fab2_lib.baseboard_fab2(sch_1):m_e_dqs_dn(3)" )
			)
			( signal "M_E_DQS_DN<4>"
				( objectStatus "@baseboard_fab2_lib.baseboard_fab2(sch_1):m_e_dqs_dn(4)" )
			)
			( signal "M_E_DQS_DN<5>"
				( objectStatus "@baseboard_fab2_lib.baseboard_fab2(sch_1):m_e_dqs_dn(5)" )
			)
			( signal "M_E_DQS_DN<6>"
				( objectStatus "@baseboard_fab2_lib.baseboard_fab2(sch_1):m_e_dqs_dn(6)" )
			)
			( signal "M_E_DQS_DN<7>"
				( objectStatus "@baseboard_fab2_lib.baseboard_fab2(sch_1):m_e_dqs_dn(7)" )
			)
			( signal "M_E_DQS_DN<8>"
				( objectStatus "@baseboard_fab2_lib.baseboard_fab2(sch_1):m_e_dqs_dn(8)" )
			)
			( signal "M_E_DQS_DN<9>"
				( objectStatus "@baseboard_fab2_lib.baseboard_fab2(sch_1):m_e_dqs_dn(9)" )
			)
			( signal "M_E_DQS_DN<10>"
				( objectStatus "@baseboard_fab2_lib.baseboard_fab2(sch_1):m_e_dqs_dn(10)" )
			)
			( signal "M_E_DQS_DN<11>"
				( objectStatus "@baseboard_fab2_lib.baseboard_fab2(sch_1):m_e_dqs_dn(11)" )
			)
			( signal "M_E_DQS_DN<12>"
				( objectStatus "@baseboard_fab2_lib.baseboard_fab2(sch_1):m_e_dqs_dn(12)" )
			)
			( signal "M_E_DQS_DN<13>"
				( objectStatus "@baseboard_fab2_lib.baseboard_fab2(sch_1):m_e_dqs_dn(13)" )
			)
			( signal "M_E_DQS_DN<14>"
				( objectStatus "@baseboard_fab2_lib.baseboard_fab2(sch_1):m_e_dqs_dn(14)" )
			)
			( signal "M_E_DQS_DN<15>"
				( objectStatus "@baseboard_fab2_lib.baseboard_fab2(sch_1):m_e_dqs_dn(15)" )
			)
			( signal "M_E_DQS_DN<16>"
				( objectStatus "@baseboard_fab2_lib.baseboard_fab2(sch_1):m_e_dqs_dn(16)" )
			)
			( signal "M_E_DQS_DN<17>"
				( objectStatus "@baseboard_fab2_lib.baseboard_fab2(sch_1):m_e_dqs_dn(17)" )
			)
			( signal "M_E_DQS_DP<0>"
				( objectStatus "@baseboard_fab2_lib.baseboard_fab2(sch_1):m_e_dqs_dp(0)" )
			)
			( signal "M_E_DQS_DP<1>"
				( objectStatus "@baseboard_fab2_lib.baseboard_fab2(sch_1):m_e_dqs_dp(1)" )
			)
			( signal "M_E_DQS_DP<2>"
				( objectStatus "@baseboard_fab2_lib.baseboard_fab2(sch_1):m_e_dqs_dp(2)" )
			)
			( signal "M_E_DQS_DP<3>"
				( objectStatus "@baseboard_fab2_lib.baseboard_fab2(sch_1):m_e_dqs_dp(3)" )
			)
			( signal "M_E_DQS_DP<4>"
				( objectStatus "@baseboard_fab2_lib.baseboard_fab2(sch_1):m_e_dqs_dp(4)" )
			)
			( signal "M_E_DQS_DP<5>"
				( objectStatus "@baseboard_fab2_lib.baseboard_fab2(sch_1):m_e_dqs_dp(5)" )
			)
			( signal "M_E_DQS_DP<6>"
				( objectStatus "@baseboard_fab2_lib.baseboard_fab2(sch_1):m_e_dqs_dp(6)" )
			)
			( signal "M_E_DQS_DP<7>"
				( objectStatus "@baseboard_fab2_lib.baseboard_fab2(sch_1):m_e_dqs_dp(7)" )
			)
			( signal "M_E_DQS_DP<8>"
				( objectStatus "@baseboard_fab2_lib.baseboard_fab2(sch_1):m_e_dqs_dp(8)" )
			)
			( signal "M_E_DQS_DP<9>"
				( objectStatus "@baseboard_fab2_lib.baseboard_fab2(sch_1):m_e_dqs_dp(9)" )
			)
			( signal "M_E_DQS_DP<10>"
				( objectStatus "@baseboard_fab2_lib.baseboard_fab2(sch_1):m_e_dqs_dp(10)" )
			)
			( signal "M_E_DQS_DP<11>"
				( objectStatus "@baseboard_fab2_lib.baseboard_fab2(sch_1):m_e_dqs_dp(11)" )
			)
			( signal "M_E_DQS_DP<12>"
				( objectStatus "@baseboard_fab2_lib.baseboard_fab2(sch_1):m_e_dqs_dp(12)" )
			)
			( signal "M_E_DQS_DP<13>"
				( objectStatus "@baseboard_fab2_lib.baseboard_fab2(sch_1):m_e_dqs_dp(13)" )
			)
			( signal "M_E_DQS_DP<14>"
				( objectStatus "@baseboard_fab2_lib.baseboard_fab2(sch_1):m_e_dqs_dp(14)" )
			)
			( signal "M_E_DQS_DP<15>"
				( objectStatus "@baseboard_fab2_lib.baseboard_fab2(sch_1):m_e_dqs_dp(15)" )
			)
			( signal "M_E_DQS_DP<16>"
				( objectStatus "@baseboard_fab2_lib.baseboard_fab2(sch_1):m_e_dqs_dp(16)" )
			)
			( signal "M_E_DQS_DP<17>"
				( objectStatus "@baseboard_fab2_lib.baseboard_fab2(sch_1):m_e_dqs_dp(17)" )
			)
			( signal "M_E_ECC<0>"
				( objectStatus "@baseboard_fab2_lib.baseboard_fab2(sch_1):m_e_ecc(0)" )
			)
			( signal "M_E_ECC<1>"
				( objectStatus "@baseboard_fab2_lib.baseboard_fab2(sch_1):m_e_ecc(1)" )
			)
			( signal "M_E_ECC<2>"
				( objectStatus "@baseboard_fab2_lib.baseboard_fab2(sch_1):m_e_ecc(2)" )
			)
			( signal "M_E_ECC<3>"
				( objectStatus "@baseboard_fab2_lib.baseboard_fab2(sch_1):m_e_ecc(3)" )
			)
			( signal "M_E_ECC<4>"
				( objectStatus "@baseboard_fab2_lib.baseboard_fab2(sch_1):m_e_ecc(4)" )
			)
			( signal "M_E_ECC<5>"
				( objectStatus "@baseboard_fab2_lib.baseboard_fab2(sch_1):m_e_ecc(5)" )
			)
			( signal "M_E_ECC<6>"
				( objectStatus "@baseboard_fab2_lib.baseboard_fab2(sch_1):m_e_ecc(6)" )
			)
			( signal "M_E_ECC<7>"
				( objectStatus "@baseboard_fab2_lib.baseboard_fab2(sch_1):m_e_ecc(7)" )
			)
			( signal "M_E_MA<0>"
				( objectStatus "@baseboard_fab2_lib.baseboard_fab2(sch_1):m_e_ma(0)" )
			)
			( signal "M_E_MA<1>"
				( objectStatus "@baseboard_fab2_lib.baseboard_fab2(sch_1):m_e_ma(1)" )
			)
			( signal "M_E_MA<2>"
				( objectStatus "@baseboard_fab2_lib.baseboard_fab2(sch_1):m_e_ma(2)" )
			)
			( signal "M_E_MA<3>"
				( objectStatus "@baseboard_fab2_lib.baseboard_fab2(sch_1):m_e_ma(3)" )
			)
			( signal "M_E_MA<4>"
				( objectStatus "@baseboard_fab2_lib.baseboard_fab2(sch_1):m_e_ma(4)" )
			)
			( signal "M_E_MA<5>"
				( objectStatus "@baseboard_fab2_lib.baseboard_fab2(sch_1):m_e_ma(5)" )
			)
			( signal "M_E_MA<6>"
				( objectStatus "@baseboard_fab2_lib.baseboard_fab2(sch_1):m_e_ma(6)" )
			)
			( signal "M_E_MA<7>"
				( objectStatus "@baseboard_fab2_lib.baseboard_fab2(sch_1):m_e_ma(7)" )
			)
			( signal "M_E_MA<8>"
				( objectStatus "@baseboard_fab2_lib.baseboard_fab2(sch_1):m_e_ma(8)" )
			)
			( signal "M_E_MA<9>"
				( objectStatus "@baseboard_fab2_lib.baseboard_fab2(sch_1):m_e_ma(9)" )
			)
			( signal "M_E_MA<10>"
				( objectStatus "@baseboard_fab2_lib.baseboard_fab2(sch_1):m_e_ma(10)" )
			)
			( signal "M_E_MA<11>"
				( objectStatus "@baseboard_fab2_lib.baseboard_fab2(sch_1):m_e_ma(11)" )
			)
			( signal "M_E_MA<12>"
				( objectStatus "@baseboard_fab2_lib.baseboard_fab2(sch_1):m_e_ma(12)" )
			)
			( signal "M_E_MA<13>"
				( objectStatus "@baseboard_fab2_lib.baseboard_fab2(sch_1):m_e_ma(13)" )
			)
			( signal "M_E_MA<14>"
				( objectStatus "@baseboard_fab2_lib.baseboard_fab2(sch_1):m_e_ma(14)" )
			)
			( signal "M_E_MA<15>"
				( objectStatus "@baseboard_fab2_lib.baseboard_fab2(sch_1):m_e_ma(15)" )
			)
			( signal "M_E_MA<16>"
				( objectStatus "@baseboard_fab2_lib.baseboard_fab2(sch_1):m_e_ma(16)" )
			)
			( signal "M_E_MA<17>"
				( objectStatus "@baseboard_fab2_lib.baseboard_fab2(sch_1):m_e_ma(17)" )
			)
			( signal "M_E_ODT<0>"
				( objectStatus "@baseboard_fab2_lib.baseboard_fab2(sch_1):m_e_odt(0)" )
			)
			( signal "M_E_ODT<1>"
				( objectStatus "@baseboard_fab2_lib.baseboard_fab2(sch_1):m_e_odt(1)" )
			)
			( signal "M_E_ODT<2>"
				( objectStatus "@baseboard_fab2_lib.baseboard_fab2(sch_1):m_e_odt(2)" )
			)
			( signal "M_E_ODT<3>"
				( objectStatus "@baseboard_fab2_lib.baseboard_fab2(sch_1):m_e_odt(3)" )
			)
			( signal "M_E_PAR"
				( objectStatus "@baseboard_fab2_lib.baseboard_fab2(sch_1):m_e_par" )
			)
			( signal "M_F_ACT_N"
				( objectStatus "@baseboard_fab2_lib.baseboard_fab2(sch_1):m_f_act_n" )
			)
			( signal "M_F_ALERT_N"
				( objectStatus "@baseboard_fab2_lib.baseboard_fab2(sch_1):m_f_alert_n" )
			)
			( signal "M_F_BA<0>"
				( objectStatus "@baseboard_fab2_lib.baseboard_fab2(sch_1):m_f_ba(0)" )
			)
			( signal "M_F_BA<1>"
				( objectStatus "@baseboard_fab2_lib.baseboard_fab2(sch_1):m_f_ba(1)" )
			)
			( signal "M_F_BG<0>"
				( objectStatus "@baseboard_fab2_lib.baseboard_fab2(sch_1):m_f_bg(0)" )
			)
			( signal "M_F_BG<1>"
				( objectStatus "@baseboard_fab2_lib.baseboard_fab2(sch_1):m_f_bg(1)" )
			)
			( signal "M_F_C<2>"
				( objectStatus "@baseboard_fab2_lib.baseboard_fab2(sch_1):m_f_c(2)" )
			)
			( signal "M_F_CKE<0>"
				( objectStatus "@baseboard_fab2_lib.baseboard_fab2(sch_1):m_f_cke(0)" )
			)
			( signal "M_F_CKE<1>"
				( objectStatus "@baseboard_fab2_lib.baseboard_fab2(sch_1):m_f_cke(1)" )
			)
			( signal "M_F_CKE<2>"
				( objectStatus "@baseboard_fab2_lib.baseboard_fab2(sch_1):m_f_cke(2)" )
			)
			( signal "M_F_CKE<3>"
				( objectStatus "@baseboard_fab2_lib.baseboard_fab2(sch_1):m_f_cke(3)" )
			)
			( signal "M_F_CLK_DN<0>"
				( objectStatus "@baseboard_fab2_lib.baseboard_fab2(sch_1):m_f_clk_dn(0)" )
			)
			( signal "M_F_CLK_DN<1>"
				( objectStatus "@baseboard_fab2_lib.baseboard_fab2(sch_1):m_f_clk_dn(1)" )
			)
			( signal "M_F_CLK_DN<2>"
				( objectStatus "@baseboard_fab2_lib.baseboard_fab2(sch_1):m_f_clk_dn(2)" )
			)
			( signal "M_F_CLK_DN<3>"
				( objectStatus "@baseboard_fab2_lib.baseboard_fab2(sch_1):m_f_clk_dn(3)" )
			)
			( signal "M_F_CLK_DP<0>"
				( objectStatus "@baseboard_fab2_lib.baseboard_fab2(sch_1):m_f_clk_dp(0)" )
			)
			( signal "M_F_CLK_DP<1>"
				( objectStatus "@baseboard_fab2_lib.baseboard_fab2(sch_1):m_f_clk_dp(1)" )
			)
			( signal "M_F_CLK_DP<2>"
				( objectStatus "@baseboard_fab2_lib.baseboard_fab2(sch_1):m_f_clk_dp(2)" )
			)
			( signal "M_F_CLK_DP<3>"
				( objectStatus "@baseboard_fab2_lib.baseboard_fab2(sch_1):m_f_clk_dp(3)" )
			)
			( signal "M_F_CS_N<0>"
				( objectStatus "@baseboard_fab2_lib.baseboard_fab2(sch_1):m_f_cs_n(0)" )
			)
			( signal "M_F_CS_N<1>"
				( objectStatus "@baseboard_fab2_lib.baseboard_fab2(sch_1):m_f_cs_n(1)" )
			)
			( signal "M_F_CS_N<2>"
				( objectStatus "@baseboard_fab2_lib.baseboard_fab2(sch_1):m_f_cs_n(2)" )
			)
			( signal "M_F_CS_N<3>"
				( objectStatus "@baseboard_fab2_lib.baseboard_fab2(sch_1):m_f_cs_n(3)" )
			)
			( signal "M_F_CS_N<4>"
				( objectStatus "@baseboard_fab2_lib.baseboard_fab2(sch_1):m_f_cs_n(4)" )
			)
			( signal "M_F_CS_N<5>"
				( objectStatus "@baseboard_fab2_lib.baseboard_fab2(sch_1):m_f_cs_n(5)" )
			)
			( signal "M_F_CS_N<6>"
				( objectStatus "@baseboard_fab2_lib.baseboard_fab2(sch_1):m_f_cs_n(6)" )
			)
			( signal "M_F_CS_N<7>"
				( objectStatus "@baseboard_fab2_lib.baseboard_fab2(sch_1):m_f_cs_n(7)" )
			)
			( signal "M_F_DQ<0>"
				( objectStatus "@baseboard_fab2_lib.baseboard_fab2(sch_1):m_f_dq(0)" )
			)
			( signal "M_F_DQ<1>"
				( objectStatus "@baseboard_fab2_lib.baseboard_fab2(sch_1):m_f_dq(1)" )
			)
			( signal "M_F_DQ<2>"
				( objectStatus "@baseboard_fab2_lib.baseboard_fab2(sch_1):m_f_dq(2)" )
			)
			( signal "M_F_DQ<3>"
				( objectStatus "@baseboard_fab2_lib.baseboard_fab2(sch_1):m_f_dq(3)" )
			)
			( signal "M_F_DQ<4>"
				( objectStatus "@baseboard_fab2_lib.baseboard_fab2(sch_1):m_f_dq(4)" )
			)
			( signal "M_F_DQ<5>"
				( objectStatus "@baseboard_fab2_lib.baseboard_fab2(sch_1):m_f_dq(5)" )
			)
			( signal "M_F_DQ<6>"
				( objectStatus "@baseboard_fab2_lib.baseboard_fab2(sch_1):m_f_dq(6)" )
			)
			( signal "M_F_DQ<7>"
				( objectStatus "@baseboard_fab2_lib.baseboard_fab2(sch_1):m_f_dq(7)" )
			)
			( signal "M_F_DQ<8>"
				( objectStatus "@baseboard_fab2_lib.baseboard_fab2(sch_1):m_f_dq(8)" )
			)
			( signal "M_F_DQ<9>"
				( objectStatus "@baseboard_fab2_lib.baseboard_fab2(sch_1):m_f_dq(9)" )
			)
			( signal "M_F_DQ<10>"
				( objectStatus "@baseboard_fab2_lib.baseboard_fab2(sch_1):m_f_dq(10)" )
			)
			( signal "M_F_DQ<11>"
				( objectStatus "@baseboard_fab2_lib.baseboard_fab2(sch_1):m_f_dq(11)" )
			)
			( signal "M_F_DQ<12>"
				( objectStatus "@baseboard_fab2_lib.baseboard_fab2(sch_1):m_f_dq(12)" )
			)
			( signal "M_F_DQ<13>"
				( objectStatus "@baseboard_fab2_lib.baseboard_fab2(sch_1):m_f_dq(13)" )
			)
			( signal "M_F_DQ<14>"
				( objectStatus "@baseboard_fab2_lib.baseboard_fab2(sch_1):m_f_dq(14)" )
			)
			( signal "M_F_DQ<15>"
				( objectStatus "@baseboard_fab2_lib.baseboard_fab2(sch_1):m_f_dq(15)" )
			)
			( signal "M_F_DQ<16>"
				( objectStatus "@baseboard_fab2_lib.baseboard_fab2(sch_1):m_f_dq(16)" )
			)
			( signal "M_F_DQ<17>"
				( objectStatus "@baseboard_fab2_lib.baseboard_fab2(sch_1):m_f_dq(17)" )
			)
			( signal "M_F_DQ<18>"
				( objectStatus "@baseboard_fab2_lib.baseboard_fab2(sch_1):m_f_dq(18)" )
			)
			( signal "M_F_DQ<19>"
				( objectStatus "@baseboard_fab2_lib.baseboard_fab2(sch_1):m_f_dq(19)" )
			)
			( signal "M_F_DQ<20>"
				( objectStatus "@baseboard_fab2_lib.baseboard_fab2(sch_1):m_f_dq(20)" )
			)
			( signal "M_F_DQ<21>"
				( objectStatus "@baseboard_fab2_lib.baseboard_fab2(sch_1):m_f_dq(21)" )
			)
			( signal "M_F_DQ<22>"
				( objectStatus "@baseboard_fab2_lib.baseboard_fab2(sch_1):m_f_dq(22)" )
			)
			( signal "M_F_DQ<23>"
				( objectStatus "@baseboard_fab2_lib.baseboard_fab2(sch_1):m_f_dq(23)" )
			)
			( signal "M_F_DQ<24>"
				( objectStatus "@baseboard_fab2_lib.baseboard_fab2(sch_1):m_f_dq(24)" )
			)
			( signal "M_F_DQ<25>"
				( objectStatus "@baseboard_fab2_lib.baseboard_fab2(sch_1):m_f_dq(25)" )
			)
			( signal "M_F_DQ<26>"
				( objectStatus "@baseboard_fab2_lib.baseboard_fab2(sch_1):m_f_dq(26)" )
			)
			( signal "M_F_DQ<27>"
				( objectStatus "@baseboard_fab2_lib.baseboard_fab2(sch_1):m_f_dq(27)" )
			)
			( signal "M_F_DQ<28>"
				( objectStatus "@baseboard_fab2_lib.baseboard_fab2(sch_1):m_f_dq(28)" )
			)
			( signal "M_F_DQ<29>"
				( objectStatus "@baseboard_fab2_lib.baseboard_fab2(sch_1):m_f_dq(29)" )
			)
			( signal "M_F_DQ<30>"
				( objectStatus "@baseboard_fab2_lib.baseboard_fab2(sch_1):m_f_dq(30)" )
			)
			( signal "M_F_DQ<31>"
				( objectStatus "@baseboard_fab2_lib.baseboard_fab2(sch_1):m_f_dq(31)" )
			)
			( signal "M_F_DQ<32>"
				( objectStatus "@baseboard_fab2_lib.baseboard_fab2(sch_1):m_f_dq(32)" )
			)
			( signal "M_F_DQ<33>"
				( objectStatus "@baseboard_fab2_lib.baseboard_fab2(sch_1):m_f_dq(33)" )
			)
			( signal "M_F_DQ<34>"
				( objectStatus "@baseboard_fab2_lib.baseboard_fab2(sch_1):m_f_dq(34)" )
			)
			( signal "M_F_DQ<35>"
				( objectStatus "@baseboard_fab2_lib.baseboard_fab2(sch_1):m_f_dq(35)" )
			)
			( signal "M_F_DQ<36>"
				( objectStatus "@baseboard_fab2_lib.baseboard_fab2(sch_1):m_f_dq(36)" )
			)
			( signal "M_F_DQ<37>"
				( objectStatus "@baseboard_fab2_lib.baseboard_fab2(sch_1):m_f_dq(37)" )
			)
			( signal "M_F_DQ<38>"
				( objectStatus "@baseboard_fab2_lib.baseboard_fab2(sch_1):m_f_dq(38)" )
			)
			( signal "M_F_DQ<39>"
				( objectStatus "@baseboard_fab2_lib.baseboard_fab2(sch_1):m_f_dq(39)" )
			)
			( signal "M_F_DQ<40>"
				( objectStatus "@baseboard_fab2_lib.baseboard_fab2(sch_1):m_f_dq(40)" )
			)
			( signal "M_F_DQ<41>"
				( objectStatus "@baseboard_fab2_lib.baseboard_fab2(sch_1):m_f_dq(41)" )
			)
			( signal "M_F_DQ<42>"
				( objectStatus "@baseboard_fab2_lib.baseboard_fab2(sch_1):m_f_dq(42)" )
			)
			( signal "M_F_DQ<43>"
				( objectStatus "@baseboard_fab2_lib.baseboard_fab2(sch_1):m_f_dq(43)" )
			)
			( signal "M_F_DQ<44>"
				( objectStatus "@baseboard_fab2_lib.baseboard_fab2(sch_1):m_f_dq(44)" )
			)
			( signal "M_F_DQ<45>"
				( objectStatus "@baseboard_fab2_lib.baseboard_fab2(sch_1):m_f_dq(45)" )
			)
			( signal "M_F_DQ<46>"
				( objectStatus "@baseboard_fab2_lib.baseboard_fab2(sch_1):m_f_dq(46)" )
			)
			( signal "M_F_DQ<47>"
				( objectStatus "@baseboard_fab2_lib.baseboard_fab2(sch_1):m_f_dq(47)" )
			)
			( signal "M_F_DQ<48>"
				( objectStatus "@baseboard_fab2_lib.baseboard_fab2(sch_1):m_f_dq(48)" )
			)
			( signal "M_F_DQ<49>"
				( objectStatus "@baseboard_fab2_lib.baseboard_fab2(sch_1):m_f_dq(49)" )
			)
			( signal "M_F_DQ<50>"
				( objectStatus "@baseboard_fab2_lib.baseboard_fab2(sch_1):m_f_dq(50)" )
			)
			( signal "M_F_DQ<51>"
				( objectStatus "@baseboard_fab2_lib.baseboard_fab2(sch_1):m_f_dq(51)" )
			)
			( signal "M_F_DQ<52>"
				( objectStatus "@baseboard_fab2_lib.baseboard_fab2(sch_1):m_f_dq(52)" )
			)
			( signal "M_F_DQ<53>"
				( objectStatus "@baseboard_fab2_lib.baseboard_fab2(sch_1):m_f_dq(53)" )
			)
			( signal "M_F_DQ<54>"
				( objectStatus "@baseboard_fab2_lib.baseboard_fab2(sch_1):m_f_dq(54)" )
			)
			( signal "M_F_DQ<55>"
				( objectStatus "@baseboard_fab2_lib.baseboard_fab2(sch_1):m_f_dq(55)" )
			)
			( signal "M_F_DQ<56>"
				( objectStatus "@baseboard_fab2_lib.baseboard_fab2(sch_1):m_f_dq(56)" )
			)
			( signal "M_F_DQ<57>"
				( objectStatus "@baseboard_fab2_lib.baseboard_fab2(sch_1):m_f_dq(57)" )
			)
			( signal "M_F_DQ<58>"
				( objectStatus "@baseboard_fab2_lib.baseboard_fab2(sch_1):m_f_dq(58)" )
			)
			( signal "M_F_DQ<59>"
				( objectStatus "@baseboard_fab2_lib.baseboard_fab2(sch_1):m_f_dq(59)" )
			)
			( signal "M_F_DQ<60>"
				( objectStatus "@baseboard_fab2_lib.baseboard_fab2(sch_1):m_f_dq(60)" )
			)
			( signal "M_F_DQ<61>"
				( objectStatus "@baseboard_fab2_lib.baseboard_fab2(sch_1):m_f_dq(61)" )
			)
			( signal "M_F_DQ<62>"
				( objectStatus "@baseboard_fab2_lib.baseboard_fab2(sch_1):m_f_dq(62)" )
			)
			( signal "M_F_DQ<63>"
				( objectStatus "@baseboard_fab2_lib.baseboard_fab2(sch_1):m_f_dq(63)" )
			)
			( signal "M_F_DQS_DN<0>"
				( objectStatus "@baseboard_fab2_lib.baseboard_fab2(sch_1):m_f_dqs_dn(0)" )
			)
			( signal "M_F_DQS_DN<1>"
				( objectStatus "@baseboard_fab2_lib.baseboard_fab2(sch_1):m_f_dqs_dn(1)" )
			)
			( signal "M_F_DQS_DN<2>"
				( objectStatus "@baseboard_fab2_lib.baseboard_fab2(sch_1):m_f_dqs_dn(2)" )
			)
			( signal "M_F_DQS_DN<3>"
				( objectStatus "@baseboard_fab2_lib.baseboard_fab2(sch_1):m_f_dqs_dn(3)" )
			)
			( signal "M_F_DQS_DN<4>"
				( objectStatus "@baseboard_fab2_lib.baseboard_fab2(sch_1):m_f_dqs_dn(4)" )
			)
			( signal "M_F_DQS_DN<5>"
				( objectStatus "@baseboard_fab2_lib.baseboard_fab2(sch_1):m_f_dqs_dn(5)" )
			)
			( signal "M_F_DQS_DN<6>"
				( objectStatus "@baseboard_fab2_lib.baseboard_fab2(sch_1):m_f_dqs_dn(6)" )
			)
			( signal "M_F_DQS_DN<7>"
				( objectStatus "@baseboard_fab2_lib.baseboard_fab2(sch_1):m_f_dqs_dn(7)" )
			)
			( signal "M_F_DQS_DN<8>"
				( objectStatus "@baseboard_fab2_lib.baseboard_fab2(sch_1):m_f_dqs_dn(8)" )
			)
			( signal "M_F_DQS_DN<9>"
				( objectStatus "@baseboard_fab2_lib.baseboard_fab2(sch_1):m_f_dqs_dn(9)" )
			)
			( signal "M_F_DQS_DN<10>"
				( objectStatus "@baseboard_fab2_lib.baseboard_fab2(sch_1):m_f_dqs_dn(10)" )
			)
			( signal "M_F_DQS_DN<11>"
				( objectStatus "@baseboard_fab2_lib.baseboard_fab2(sch_1):m_f_dqs_dn(11)" )
			)
			( signal "M_F_DQS_DN<12>"
				( objectStatus "@baseboard_fab2_lib.baseboard_fab2(sch_1):m_f_dqs_dn(12)" )
			)
			( signal "M_F_DQS_DN<13>"
				( objectStatus "@baseboard_fab2_lib.baseboard_fab2(sch_1):m_f_dqs_dn(13)" )
			)
			( signal "M_F_DQS_DN<14>"
				( objectStatus "@baseboard_fab2_lib.baseboard_fab2(sch_1):m_f_dqs_dn(14)" )
			)
			( signal "M_F_DQS_DN<15>"
				( objectStatus "@baseboard_fab2_lib.baseboard_fab2(sch_1):m_f_dqs_dn(15)" )
			)
			( signal "M_F_DQS_DN<16>"
				( objectStatus "@baseboard_fab2_lib.baseboard_fab2(sch_1):m_f_dqs_dn(16)" )
			)
			( signal "M_F_DQS_DN<17>"
				( objectStatus "@baseboard_fab2_lib.baseboard_fab2(sch_1):m_f_dqs_dn(17)" )
			)
			( signal "M_F_DQS_DP<0>"
				( objectStatus "@baseboard_fab2_lib.baseboard_fab2(sch_1):m_f_dqs_dp(0)" )
			)
			( signal "M_F_DQS_DP<1>"
				( objectStatus "@baseboard_fab2_lib.baseboard_fab2(sch_1):m_f_dqs_dp(1)" )
			)
			( signal "M_F_DQS_DP<2>"
				( objectStatus "@baseboard_fab2_lib.baseboard_fab2(sch_1):m_f_dqs_dp(2)" )
			)
			( signal "M_F_DQS_DP<3>"
				( objectStatus "@baseboard_fab2_lib.baseboard_fab2(sch_1):m_f_dqs_dp(3)" )
			)
			( signal "M_F_DQS_DP<4>"
				( objectStatus "@baseboard_fab2_lib.baseboard_fab2(sch_1):m_f_dqs_dp(4)" )
			)
			( signal "M_F_DQS_DP<5>"
				( objectStatus "@baseboard_fab2_lib.baseboard_fab2(sch_1):m_f_dqs_dp(5)" )
			)
			( signal "M_F_DQS_DP<6>"
				( objectStatus "@baseboard_fab2_lib.baseboard_fab2(sch_1):m_f_dqs_dp(6)" )
			)
			( signal "M_F_DQS_DP<7>"
				( objectStatus "@baseboard_fab2_lib.baseboard_fab2(sch_1):m_f_dqs_dp(7)" )
			)
			( signal "M_F_DQS_DP<8>"
				( objectStatus "@baseboard_fab2_lib.baseboard_fab2(sch_1):m_f_dqs_dp(8)" )
			)
			( signal "M_F_DQS_DP<9>"
				( objectStatus "@baseboard_fab2_lib.baseboard_fab2(sch_1):m_f_dqs_dp(9)" )
			)
			( signal "M_F_DQS_DP<10>"
				( objectStatus "@baseboard_fab2_lib.baseboard_fab2(sch_1):m_f_dqs_dp(10)" )
			)
			( signal "M_F_DQS_DP<11>"
				( objectStatus "@baseboard_fab2_lib.baseboard_fab2(sch_1):m_f_dqs_dp(11)" )
			)
			( signal "M_F_DQS_DP<12>"
				( objectStatus "@baseboard_fab2_lib.baseboard_fab2(sch_1):m_f_dqs_dp(12)" )
			)
			( signal "M_F_DQS_DP<13>"
				( objectStatus "@baseboard_fab2_lib.baseboard_fab2(sch_1):m_f_dqs_dp(13)" )
			)
			( signal "M_F_DQS_DP<14>"
				( objectStatus "@baseboard_fab2_lib.baseboard_fab2(sch_1):m_f_dqs_dp(14)" )
			)
			( signal "M_F_DQS_DP<15>"
				( objectStatus "@baseboard_fab2_lib.baseboard_fab2(sch_1):m_f_dqs_dp(15)" )
			)
			( signal "M_F_DQS_DP<16>"
				( objectStatus "@baseboard_fab2_lib.baseboard_fab2(sch_1):m_f_dqs_dp(16)" )
			)
			( signal "M_F_DQS_DP<17>"
				( objectStatus "@baseboard_fab2_lib.baseboard_fab2(sch_1):m_f_dqs_dp(17)" )
			)
			( signal "M_F_ECC<0>"
				( objectStatus "@baseboard_fab2_lib.baseboard_fab2(sch_1):m_f_ecc(0)" )
			)
			( signal "M_F_ECC<1>"
				( objectStatus "@baseboard_fab2_lib.baseboard_fab2(sch_1):m_f_ecc(1)" )
			)
			( signal "M_F_ECC<2>"
				( objectStatus "@baseboard_fab2_lib.baseboard_fab2(sch_1):m_f_ecc(2)" )
			)
			( signal "M_F_ECC<3>"
				( objectStatus "@baseboard_fab2_lib.baseboard_fab2(sch_1):m_f_ecc(3)" )
			)
			( signal "M_F_ECC<4>"
				( objectStatus "@baseboard_fab2_lib.baseboard_fab2(sch_1):m_f_ecc(4)" )
			)
			( signal "M_F_ECC<5>"
				( objectStatus "@baseboard_fab2_lib.baseboard_fab2(sch_1):m_f_ecc(5)" )
			)
			( signal "M_F_ECC<6>"
				( objectStatus "@baseboard_fab2_lib.baseboard_fab2(sch_1):m_f_ecc(6)" )
			)
			( signal "M_F_ECC<7>"
				( objectStatus "@baseboard_fab2_lib.baseboard_fab2(sch_1):m_f_ecc(7)" )
			)
			( signal "M_F_MA<0>"
				( objectStatus "@baseboard_fab2_lib.baseboard_fab2(sch_1):m_f_ma(0)" )
			)
			( signal "M_F_MA<1>"
				( objectStatus "@baseboard_fab2_lib.baseboard_fab2(sch_1):m_f_ma(1)" )
			)
			( signal "M_F_MA<2>"
				( objectStatus "@baseboard_fab2_lib.baseboard_fab2(sch_1):m_f_ma(2)" )
			)
			( signal "M_F_MA<3>"
				( objectStatus "@baseboard_fab2_lib.baseboard_fab2(sch_1):m_f_ma(3)" )
			)
			( signal "M_F_MA<4>"
				( objectStatus "@baseboard_fab2_lib.baseboard_fab2(sch_1):m_f_ma(4)" )
			)
			( signal "M_F_MA<5>"
				( objectStatus "@baseboard_fab2_lib.baseboard_fab2(sch_1):m_f_ma(5)" )
			)
			( signal "M_F_MA<6>"
				( objectStatus "@baseboard_fab2_lib.baseboard_fab2(sch_1):m_f_ma(6)" )
			)
			( signal "M_F_MA<7>"
				( objectStatus "@baseboard_fab2_lib.baseboard_fab2(sch_1):m_f_ma(7)" )
			)
			( signal "M_F_MA<8>"
				( objectStatus "@baseboard_fab2_lib.baseboard_fab2(sch_1):m_f_ma(8)" )
			)
			( signal "M_F_MA<9>"
				( objectStatus "@baseboard_fab2_lib.baseboard_fab2(sch_1):m_f_ma(9)" )
			)
			( signal "M_F_MA<10>"
				( objectStatus "@baseboard_fab2_lib.baseboard_fab2(sch_1):m_f_ma(10)" )
			)
			( signal "M_F_MA<11>"
				( objectStatus "@baseboard_fab2_lib.baseboard_fab2(sch_1):m_f_ma(11)" )
			)
			( signal "M_F_MA<12>"
				( objectStatus "@baseboard_fab2_lib.baseboard_fab2(sch_1):m_f_ma(12)" )
			)
			( signal "M_F_MA<13>"
				( objectStatus "@baseboard_fab2_lib.baseboard_fab2(sch_1):m_f_ma(13)" )
			)
			( signal "M_F_MA<14>"
				( objectStatus "@baseboard_fab2_lib.baseboard_fab2(sch_1):m_f_ma(14)" )
			)
			( signal "M_F_MA<15>"
				( objectStatus "@baseboard_fab2_lib.baseboard_fab2(sch_1):m_f_ma(15)" )
			)
			( signal "M_F_MA<16>"
				( objectStatus "@baseboard_fab2_lib.baseboard_fab2(sch_1):m_f_ma(16)" )
			)
			( signal "M_F_MA<17>"
				( objectStatus "@baseboard_fab2_lib.baseboard_fab2(sch_1):m_f_ma(17)" )
			)
			( signal "M_F_ODT<0>"
				( objectStatus "@baseboard_fab2_lib.baseboard_fab2(sch_1):m_f_odt(0)" )
			)
			( signal "M_F_ODT<1>"
				( objectStatus "@baseboard_fab2_lib.baseboard_fab2(sch_1):m_f_odt(1)" )
			)
			( signal "M_F_ODT<2>"
				( objectStatus "@baseboard_fab2_lib.baseboard_fab2(sch_1):m_f_odt(2)" )
			)
			( signal "M_F_ODT<3>"
				( objectStatus "@baseboard_fab2_lib.baseboard_fab2(sch_1):m_f_odt(3)" )
			)
			( signal "M_F_PAR"
				( objectStatus "@baseboard_fab2_lib.baseboard_fab2(sch_1):m_f_par" )
			)
			( signal "CLK_100M_CPU0_PE_REFCLK_DN"
				( objectStatus "@baseboard_fab2_lib.baseboard_fab2(sch_1):clk_100m_cpu0_pe_refclk_dn" )
			)
			( signal "CLK_100M_CPU0_PE_REFCLK_DP"
				( objectStatus "@baseboard_fab2_lib.baseboard_fab2(sch_1):clk_100m_cpu0_pe_refclk_dp" )
			)
			( signal "CLK_156M_OSC_CPU0_HFI_DN"
				( objectStatus "@baseboard_fab2_lib.baseboard_fab2(sch_1):clk_156m_osc_cpu0_hfi_dn" )
			)
			( signal "CLK_156M_OSC_CPU0_HFI_DP"
				( objectStatus "@baseboard_fab2_lib.baseboard_fab2(sch_1):clk_156m_osc_cpu0_hfi_dp" )
			)
			( signal "DMI_CPU0_PCH_RX_C_DN<0>"
				( objectStatus "@baseboard_fab2_lib.baseboard_fab2(sch_1):dmi_cpu0_pch_rx_c_dn(0)" )
			)
			( signal "DMI_CPU0_PCH_RX_C_DN<1>"
				( objectStatus "@baseboard_fab2_lib.baseboard_fab2(sch_1):dmi_cpu0_pch_rx_c_dn(1)" )
			)
			( signal "DMI_CPU0_PCH_RX_C_DN<2>"
				( objectStatus "@baseboard_fab2_lib.baseboard_fab2(sch_1):dmi_cpu0_pch_rx_c_dn(2)" )
			)
			( signal "DMI_CPU0_PCH_RX_C_DN<3>"
				( objectStatus "@baseboard_fab2_lib.baseboard_fab2(sch_1):dmi_cpu0_pch_rx_c_dn(3)" )
			)
			( signal "DMI_CPU0_PCH_RX_C_DP<0>"
				( objectStatus "@baseboard_fab2_lib.baseboard_fab2(sch_1):dmi_cpu0_pch_rx_c_dp(0)" )
			)
			( signal "DMI_CPU0_PCH_RX_C_DP<1>"
				( objectStatus "@baseboard_fab2_lib.baseboard_fab2(sch_1):dmi_cpu0_pch_rx_c_dp(1)" )
			)
			( signal "DMI_CPU0_PCH_RX_C_DP<2>"
				( objectStatus "@baseboard_fab2_lib.baseboard_fab2(sch_1):dmi_cpu0_pch_rx_c_dp(2)" )
			)
			( signal "DMI_CPU0_PCH_RX_C_DP<3>"
				( objectStatus "@baseboard_fab2_lib.baseboard_fab2(sch_1):dmi_cpu0_pch_rx_c_dp(3)" )
			)
			( signal "DMI_CPU0_PCH_TX_DN<0>"
				( objectStatus "@baseboard_fab2_lib.baseboard_fab2(sch_1):dmi_cpu0_pch_tx_dn(0)" )
			)
			( signal "DMI_CPU0_PCH_TX_DN<1>"
				( objectStatus "@baseboard_fab2_lib.baseboard_fab2(sch_1):dmi_cpu0_pch_tx_dn(1)" )
			)
			( signal "DMI_CPU0_PCH_TX_DN<2>"
				( objectStatus "@baseboard_fab2_lib.baseboard_fab2(sch_1):dmi_cpu0_pch_tx_dn(2)" )
			)
			( signal "DMI_CPU0_PCH_TX_DN<3>"
				( objectStatus "@baseboard_fab2_lib.baseboard_fab2(sch_1):dmi_cpu0_pch_tx_dn(3)" )
			)
			( signal "DMI_CPU0_PCH_TX_DP<0>"
				( objectStatus "@baseboard_fab2_lib.baseboard_fab2(sch_1):dmi_cpu0_pch_tx_dp(0)" )
			)
			( signal "DMI_CPU0_PCH_TX_DP<1>"
				( objectStatus "@baseboard_fab2_lib.baseboard_fab2(sch_1):dmi_cpu0_pch_tx_dp(1)" )
			)
			( signal "DMI_CPU0_PCH_TX_DP<2>"
				( objectStatus "@baseboard_fab2_lib.baseboard_fab2(sch_1):dmi_cpu0_pch_tx_dp(2)" )
			)
			( signal "DMI_CPU0_PCH_TX_DP<3>"
				( objectStatus "@baseboard_fab2_lib.baseboard_fab2(sch_1):dmi_cpu0_pch_tx_dp(3)" )
			)
			( signal "FM_MODPRST_HFI0_CPU0_LVT2_N"
				( objectStatus "@baseboard_fab2_lib.baseboard_fab2(sch_1):fm_modprst_hfi0_cpu0_lvt2_n" )
			)
			( signal "FM_MODPRST_HFI1_CPU0_LVT2_N"
				( objectStatus "@baseboard_fab2_lib.baseboard_fab2(sch_1):fm_modprst_hfi1_cpu0_lvt2_n" )
			)
			( signal "IRQ_HFI0_CPU0_LVT2_N"
				( objectStatus "@baseboard_fab2_lib.baseboard_fab2(sch_1):irq_hfi0_cpu0_lvt2_n" )
			)
			( signal "IRQ_HFI1_CPU0_LVT2_N"
				( objectStatus "@baseboard_fab2_lib.baseboard_fab2(sch_1):irq_hfi1_cpu0_lvt2_n" )
			)
			( signal "JTAG_MCP_CPU0_TDI"
				( objectStatus "@baseboard_fab2_lib.baseboard_fab2(sch_1):jtag_mcp_cpu0_tdi" )
			)
			( signal "JTAG_MCP_CPU0_TDO"
				( objectStatus "@baseboard_fab2_lib.baseboard_fab2(sch_1):jtag_mcp_cpu0_tdo" )
			)
			( signal "JTAG_MCP_TCK"
				( objectStatus "@baseboard_fab2_lib.baseboard_fab2(sch_1):jtag_mcp_tck" )
			)
			( signal "JTAG_MCP_TMS"
				( objectStatus "@baseboard_fab2_lib.baseboard_fab2(sch_1):jtag_mcp_tms" )
			)
			( signal "JTAG_MCP_TRST_N"
				( objectStatus "@baseboard_fab2_lib.baseboard_fab2(sch_1):jtag_mcp_trst_n" )
			)
			( signal "LED_HFI0_CPU0_N"
				( objectStatus "@baseboard_fab2_lib.baseboard_fab2(sch_1):led_hfi0_cpu0_n" )
			)
			( signal "LED_HFI1_CPU0_N"
				( objectStatus "@baseboard_fab2_lib.baseboard_fab2(sch_1):led_hfi1_cpu0_n" )
			)
			( signal "RST_CD_CPU0_POR_N"
				( objectStatus "@baseboard_fab2_lib.baseboard_fab2(sch_1):rst_cd_cpu0_por_n" )
			)
			( signal "RST_HFI0_CPU0_LVT2_N"
				( objectStatus "@baseboard_fab2_lib.baseboard_fab2(sch_1):rst_hfi0_cpu0_lvt2_n" )
			)
			( signal "RST_HFI1_CPU0_LVT2_N"
				( objectStatus "@baseboard_fab2_lib.baseboard_fab2(sch_1):rst_hfi1_cpu0_lvt2_n" )
			)
			( signal "SMB_HFI0_CPU0_LVC2_SCL"
				( objectStatus "@baseboard_fab2_lib.baseboard_fab2(sch_1):smb_hfi0_cpu0_lvc2_scl" )
			)
			( signal "SMB_HFI0_CPU0_LVC2_SDA"
				( objectStatus "@baseboard_fab2_lib.baseboard_fab2(sch_1):smb_hfi0_cpu0_lvc2_sda" )
			)
			( signal "SMB_HFI1_CPU0_LVC2_SCL"
				( objectStatus "@baseboard_fab2_lib.baseboard_fab2(sch_1):smb_hfi1_cpu0_lvc2_scl" )
			)
			( signal "SMB_HFI1_CPU0_LVC2_SDA"
				( objectStatus "@baseboard_fab2_lib.baseboard_fab2(sch_1):smb_hfi1_cpu0_lvc2_sda" )
			)
			( signal "TP_CPU0_RSVD_172"
				( objectStatus "@baseboard_fab2_lib.baseboard_fab2(sch_1):tp_cpu0_rsvd_172" )
			)
			( signal "TP_CPU0_RSVD_173"
				( objectStatus "@baseboard_fab2_lib.baseboard_fab2(sch_1):tp_cpu0_rsvd_173" )
			)
			( signal "TP_CPU0_RSVD_174"
				( objectStatus "@baseboard_fab2_lib.baseboard_fab2(sch_1):tp_cpu0_rsvd_174" )
			)
			( signal "TP_CPU0_RSVD_175"
				( objectStatus "@baseboard_fab2_lib.baseboard_fab2(sch_1):tp_cpu0_rsvd_175" )
			)
			( signal "TP_CPU0_RSVD_176"
				( objectStatus "@baseboard_fab2_lib.baseboard_fab2(sch_1):tp_cpu0_rsvd_176" )
			)
			( signal "TP_CPU0_RSVD_177"
				( objectStatus "@baseboard_fab2_lib.baseboard_fab2(sch_1):tp_cpu0_rsvd_177" )
			)
			( signal "TP_CPU0_RSVD_178"
				( objectStatus "@baseboard_fab2_lib.baseboard_fab2(sch_1):tp_cpu0_rsvd_178" )
			)
			( signal "TP_CPU0_RSVD_179"
				( objectStatus "@baseboard_fab2_lib.baseboard_fab2(sch_1):tp_cpu0_rsvd_179" )
			)
			( signal "TP_CPU0_RSVD_180"
				( objectStatus "@baseboard_fab2_lib.baseboard_fab2(sch_1):tp_cpu0_rsvd_180" )
			)
			( signal "TP_CPU0_RSVD_181"
				( objectStatus "@baseboard_fab2_lib.baseboard_fab2(sch_1):tp_cpu0_rsvd_181" )
			)
			( signal "TP_CPU0_RSVD_182"
				( objectStatus "@baseboard_fab2_lib.baseboard_fab2(sch_1):tp_cpu0_rsvd_182" )
			)
			( signal "TP_CPU0_RSVD_183"
				( objectStatus "@baseboard_fab2_lib.baseboard_fab2(sch_1):tp_cpu0_rsvd_183" )
			)
			( signal "TP_CPU0_RSVD_184"
				( objectStatus "@baseboard_fab2_lib.baseboard_fab2(sch_1):tp_cpu0_rsvd_184" )
			)
			( signal "TP_CPU0_RSVD_186"
				( objectStatus "@baseboard_fab2_lib.baseboard_fab2(sch_1):tp_cpu0_rsvd_186" )
			)
			( signal "TP_CPU0_RSVD_189"
				( objectStatus "@baseboard_fab2_lib.baseboard_fab2(sch_1):tp_cpu0_rsvd_189" )
			)
			( signal "TP_CPU0_RSVD_190"
				( objectStatus "@baseboard_fab2_lib.baseboard_fab2(sch_1):tp_cpu0_rsvd_190" )
			)
			( signal "P3E_CPU0_PE1_PCH_RXN<8>"
				( objectStatus "@baseboard_fab2_lib.baseboard_fab2(sch_1):p3e_cpu0_pe1_pch_rxn(8)" )
			)
			( signal "P3E_CPU0_PE1_PCH_RXN<9>"
				( objectStatus "@baseboard_fab2_lib.baseboard_fab2(sch_1):p3e_cpu0_pe1_pch_rxn(9)" )
			)
			( signal "P3E_CPU0_PE1_PCH_RXN<10>"
				( objectStatus "@baseboard_fab2_lib.baseboard_fab2(sch_1):p3e_cpu0_pe1_pch_rxn(10)" )
			)
			( signal "P3E_CPU0_PE1_PCH_RXN<11>"
				( objectStatus "@baseboard_fab2_lib.baseboard_fab2(sch_1):p3e_cpu0_pe1_pch_rxn(11)" )
			)
			( signal "P3E_CPU0_PE1_PCH_RXN<12>"
				( objectStatus "@baseboard_fab2_lib.baseboard_fab2(sch_1):p3e_cpu0_pe1_pch_rxn(12)" )
			)
			( signal "P3E_CPU0_PE1_PCH_RXN<13>"
				( objectStatus "@baseboard_fab2_lib.baseboard_fab2(sch_1):p3e_cpu0_pe1_pch_rxn(13)" )
			)
			( signal "P3E_CPU0_PE1_PCH_RXN<14>"
				( objectStatus "@baseboard_fab2_lib.baseboard_fab2(sch_1):p3e_cpu0_pe1_pch_rxn(14)" )
			)
			( signal "P3E_CPU0_PE1_PCH_RXN<15>"
				( objectStatus "@baseboard_fab2_lib.baseboard_fab2(sch_1):p3e_cpu0_pe1_pch_rxn(15)" )
			)
			( signal "P3E_CPU0_PE1_PCH_RXP<8>"
				( objectStatus "@baseboard_fab2_lib.baseboard_fab2(sch_1):p3e_cpu0_pe1_pch_rxp(8)" )
			)
			( signal "P3E_CPU0_PE1_PCH_RXP<9>"
				( objectStatus "@baseboard_fab2_lib.baseboard_fab2(sch_1):p3e_cpu0_pe1_pch_rxp(9)" )
			)
			( signal "P3E_CPU0_PE1_PCH_RXP<10>"
				( objectStatus "@baseboard_fab2_lib.baseboard_fab2(sch_1):p3e_cpu0_pe1_pch_rxp(10)" )
			)
			( signal "P3E_CPU0_PE1_PCH_RXP<11>"
				( objectStatus "@baseboard_fab2_lib.baseboard_fab2(sch_1):p3e_cpu0_pe1_pch_rxp(11)" )
			)
			( signal "P3E_CPU0_PE1_PCH_RXP<12>"
				( objectStatus "@baseboard_fab2_lib.baseboard_fab2(sch_1):p3e_cpu0_pe1_pch_rxp(12)" )
			)
			( signal "P3E_CPU0_PE1_PCH_RXP<13>"
				( objectStatus "@baseboard_fab2_lib.baseboard_fab2(sch_1):p3e_cpu0_pe1_pch_rxp(13)" )
			)
			( signal "P3E_CPU0_PE1_PCH_RXP<14>"
				( objectStatus "@baseboard_fab2_lib.baseboard_fab2(sch_1):p3e_cpu0_pe1_pch_rxp(14)" )
			)
			( signal "P3E_CPU0_PE1_PCH_RXP<15>"
				( objectStatus "@baseboard_fab2_lib.baseboard_fab2(sch_1):p3e_cpu0_pe1_pch_rxp(15)" )
			)
			( signal "P3E_CPU0_PE1_PCH_TXN<8>"
				( objectStatus "@baseboard_fab2_lib.baseboard_fab2(sch_1):p3e_cpu0_pe1_pch_txn(8)" )
			)
			( signal "P3E_CPU0_PE1_PCH_TXN<9>"
				( objectStatus "@baseboard_fab2_lib.baseboard_fab2(sch_1):p3e_cpu0_pe1_pch_txn(9)" )
			)
			( signal "P3E_CPU0_PE1_PCH_TXN<10>"
				( objectStatus "@baseboard_fab2_lib.baseboard_fab2(sch_1):p3e_cpu0_pe1_pch_txn(10)" )
			)
			( signal "P3E_CPU0_PE1_PCH_TXN<11>"
				( objectStatus "@baseboard_fab2_lib.baseboard_fab2(sch_1):p3e_cpu0_pe1_pch_txn(11)" )
			)
			( signal "P3E_CPU0_PE1_PCH_TXN<12>"
				( objectStatus "@baseboard_fab2_lib.baseboard_fab2(sch_1):p3e_cpu0_pe1_pch_txn(12)" )
			)
			( signal "P3E_CPU0_PE1_PCH_TXN<13>"
				( objectStatus "@baseboard_fab2_lib.baseboard_fab2(sch_1):p3e_cpu0_pe1_pch_txn(13)" )
			)
			( signal "P3E_CPU0_PE1_PCH_TXN<14>"
				( objectStatus "@baseboard_fab2_lib.baseboard_fab2(sch_1):p3e_cpu0_pe1_pch_txn(14)" )
			)
			( signal "P3E_CPU0_PE1_PCH_TXN<15>"
				( objectStatus "@baseboard_fab2_lib.baseboard_fab2(sch_1):p3e_cpu0_pe1_pch_txn(15)" )
			)
			( signal "P3E_CPU0_PE1_PCH_TXP<8>"
				( objectStatus "@baseboard_fab2_lib.baseboard_fab2(sch_1):p3e_cpu0_pe1_pch_txp(8)" )
			)
			( signal "P3E_CPU0_PE1_PCH_TXP<9>"
				( objectStatus "@baseboard_fab2_lib.baseboard_fab2(sch_1):p3e_cpu0_pe1_pch_txp(9)" )
			)
			( signal "P3E_CPU0_PE1_PCH_TXP<10>"
				( objectStatus "@baseboard_fab2_lib.baseboard_fab2(sch_1):p3e_cpu0_pe1_pch_txp(10)" )
			)
			( signal "P3E_CPU0_PE1_PCH_TXP<11>"
				( objectStatus "@baseboard_fab2_lib.baseboard_fab2(sch_1):p3e_cpu0_pe1_pch_txp(11)" )
			)
			( signal "P3E_CPU0_PE1_PCH_TXP<12>"
				( objectStatus "@baseboard_fab2_lib.baseboard_fab2(sch_1):p3e_cpu0_pe1_pch_txp(12)" )
			)
			( signal "P3E_CPU0_PE1_PCH_TXP<13>"
				( objectStatus "@baseboard_fab2_lib.baseboard_fab2(sch_1):p3e_cpu0_pe1_pch_txp(13)" )
			)
			( signal "P3E_CPU0_PE1_PCH_TXP<14>"
				( objectStatus "@baseboard_fab2_lib.baseboard_fab2(sch_1):p3e_cpu0_pe1_pch_txp(14)" )
			)
			( signal "P3E_CPU0_PE1_PCH_TXP<15>"
				( objectStatus "@baseboard_fab2_lib.baseboard_fab2(sch_1):p3e_cpu0_pe1_pch_txp(15)" )
			)
			( signal "P3E_CPU0_PE1_SS_RXN<0>"
				( objectStatus "@baseboard_fab2_lib.baseboard_fab2(sch_1):p3e_cpu0_pe1_ss_rxn(0)" )
			)
			( signal "P3E_CPU0_PE1_SS_RXN<1>"
				( objectStatus "@baseboard_fab2_lib.baseboard_fab2(sch_1):p3e_cpu0_pe1_ss_rxn(1)" )
			)
			( signal "P3E_CPU0_PE1_SS_RXN<2>"
				( objectStatus "@baseboard_fab2_lib.baseboard_fab2(sch_1):p3e_cpu0_pe1_ss_rxn(2)" )
			)
			( signal "P3E_CPU0_PE1_SS_RXN<3>"
				( objectStatus "@baseboard_fab2_lib.baseboard_fab2(sch_1):p3e_cpu0_pe1_ss_rxn(3)" )
			)
			( signal "P3E_CPU0_PE1_SS_RXN<4>"
				( objectStatus "@baseboard_fab2_lib.baseboard_fab2(sch_1):p3e_cpu0_pe1_ss_rxn(4)" )
			)
			( signal "P3E_CPU0_PE1_SS_RXN<5>"
				( objectStatus "@baseboard_fab2_lib.baseboard_fab2(sch_1):p3e_cpu0_pe1_ss_rxn(5)" )
			)
			( signal "P3E_CPU0_PE1_SS_RXN<6>"
				( objectStatus "@baseboard_fab2_lib.baseboard_fab2(sch_1):p3e_cpu0_pe1_ss_rxn(6)" )
			)
			( signal "P3E_CPU0_PE1_SS_RXN<7>"
				( objectStatus "@baseboard_fab2_lib.baseboard_fab2(sch_1):p3e_cpu0_pe1_ss_rxn(7)" )
			)
			( signal "P3E_CPU0_PE1_SS_RXP<0>"
				( objectStatus "@baseboard_fab2_lib.baseboard_fab2(sch_1):p3e_cpu0_pe1_ss_rxp(0)" )
			)
			( signal "P3E_CPU0_PE1_SS_RXP<1>"
				( objectStatus "@baseboard_fab2_lib.baseboard_fab2(sch_1):p3e_cpu0_pe1_ss_rxp(1)" )
			)
			( signal "P3E_CPU0_PE1_SS_RXP<2>"
				( objectStatus "@baseboard_fab2_lib.baseboard_fab2(sch_1):p3e_cpu0_pe1_ss_rxp(2)" )
			)
			( signal "P3E_CPU0_PE1_SS_RXP<3>"
				( objectStatus "@baseboard_fab2_lib.baseboard_fab2(sch_1):p3e_cpu0_pe1_ss_rxp(3)" )
			)
			( signal "P3E_CPU0_PE1_SS_RXP<4>"
				( objectStatus "@baseboard_fab2_lib.baseboard_fab2(sch_1):p3e_cpu0_pe1_ss_rxp(4)" )
			)
			( signal "P3E_CPU0_PE1_SS_RXP<5>"
				( objectStatus "@baseboard_fab2_lib.baseboard_fab2(sch_1):p3e_cpu0_pe1_ss_rxp(5)" )
			)
			( signal "P3E_CPU0_PE1_SS_RXP<6>"
				( objectStatus "@baseboard_fab2_lib.baseboard_fab2(sch_1):p3e_cpu0_pe1_ss_rxp(6)" )
			)
			( signal "P3E_CPU0_PE1_SS_RXP<7>"
				( objectStatus "@baseboard_fab2_lib.baseboard_fab2(sch_1):p3e_cpu0_pe1_ss_rxp(7)" )
			)
			( signal "P3E_CPU0_PE1_SS_TXN<0>"
				( objectStatus "@baseboard_fab2_lib.baseboard_fab2(sch_1):p3e_cpu0_pe1_ss_txn(0)" )
			)
			( signal "P3E_CPU0_PE1_SS_TXN<1>"
				( objectStatus "@baseboard_fab2_lib.baseboard_fab2(sch_1):p3e_cpu0_pe1_ss_txn(1)" )
			)
			( signal "P3E_CPU0_PE1_SS_TXN<2>"
				( objectStatus "@baseboard_fab2_lib.baseboard_fab2(sch_1):p3e_cpu0_pe1_ss_txn(2)" )
			)
			( signal "P3E_CPU0_PE1_SS_TXN<3>"
				( objectStatus "@baseboard_fab2_lib.baseboard_fab2(sch_1):p3e_cpu0_pe1_ss_txn(3)" )
			)
			( signal "P3E_CPU0_PE1_SS_TXN<4>"
				( objectStatus "@baseboard_fab2_lib.baseboard_fab2(sch_1):p3e_cpu0_pe1_ss_txn(4)" )
			)
			( signal "P3E_CPU0_PE1_SS_TXN<5>"
				( objectStatus "@baseboard_fab2_lib.baseboard_fab2(sch_1):p3e_cpu0_pe1_ss_txn(5)" )
			)
			( signal "P3E_CPU0_PE1_SS_TXN<6>"
				( objectStatus "@baseboard_fab2_lib.baseboard_fab2(sch_1):p3e_cpu0_pe1_ss_txn(6)" )
			)
			( signal "P3E_CPU0_PE1_SS_TXN<7>"
				( objectStatus "@baseboard_fab2_lib.baseboard_fab2(sch_1):p3e_cpu0_pe1_ss_txn(7)" )
			)
			( signal "P3E_CPU0_PE1_SS_TXP<0>"
				( objectStatus "@baseboard_fab2_lib.baseboard_fab2(sch_1):p3e_cpu0_pe1_ss_txp(0)" )
			)
			( signal "P3E_CPU0_PE1_SS_TXP<1>"
				( objectStatus "@baseboard_fab2_lib.baseboard_fab2(sch_1):p3e_cpu0_pe1_ss_txp(1)" )
			)
			( signal "P3E_CPU0_PE1_SS_TXP<2>"
				( objectStatus "@baseboard_fab2_lib.baseboard_fab2(sch_1):p3e_cpu0_pe1_ss_txp(2)" )
			)
			( signal "P3E_CPU0_PE1_SS_TXP<3>"
				( objectStatus "@baseboard_fab2_lib.baseboard_fab2(sch_1):p3e_cpu0_pe1_ss_txp(3)" )
			)
			( signal "P3E_CPU0_PE1_SS_TXP<4>"
				( objectStatus "@baseboard_fab2_lib.baseboard_fab2(sch_1):p3e_cpu0_pe1_ss_txp(4)" )
			)
			( signal "P3E_CPU0_PE1_SS_TXP<5>"
				( objectStatus "@baseboard_fab2_lib.baseboard_fab2(sch_1):p3e_cpu0_pe1_ss_txp(5)" )
			)
			( signal "P3E_CPU0_PE1_SS_TXP<6>"
				( objectStatus "@baseboard_fab2_lib.baseboard_fab2(sch_1):p3e_cpu0_pe1_ss_txp(6)" )
			)
			( signal "P3E_CPU0_PE1_SS_TXP<7>"
				( objectStatus "@baseboard_fab2_lib.baseboard_fab2(sch_1):p3e_cpu0_pe1_ss_txp(7)" )
			)
			( signal "P3E_CPU0_PE2_SS_RXN<0>"
				( objectStatus "@baseboard_fab2_lib.baseboard_fab2(sch_1):p3e_cpu0_pe2_ss_rxn(0)" )
			)
			( signal "P3E_CPU0_PE2_SS_RXN<1>"
				( objectStatus "@baseboard_fab2_lib.baseboard_fab2(sch_1):p3e_cpu0_pe2_ss_rxn(1)" )
			)
			( signal "P3E_CPU0_PE2_SS_RXN<2>"
				( objectStatus "@baseboard_fab2_lib.baseboard_fab2(sch_1):p3e_cpu0_pe2_ss_rxn(2)" )
			)
			( signal "P3E_CPU0_PE2_SS_RXN<3>"
				( objectStatus "@baseboard_fab2_lib.baseboard_fab2(sch_1):p3e_cpu0_pe2_ss_rxn(3)" )
			)
			( signal "P3E_CPU0_PE2_SS_RXN<4>"
				( objectStatus "@baseboard_fab2_lib.baseboard_fab2(sch_1):p3e_cpu0_pe2_ss_rxn(4)" )
			)
			( signal "P3E_CPU0_PE2_SS_RXN<5>"
				( objectStatus "@baseboard_fab2_lib.baseboard_fab2(sch_1):p3e_cpu0_pe2_ss_rxn(5)" )
			)
			( signal "P3E_CPU0_PE2_SS_RXN<6>"
				( objectStatus "@baseboard_fab2_lib.baseboard_fab2(sch_1):p3e_cpu0_pe2_ss_rxn(6)" )
			)
			( signal "P3E_CPU0_PE2_SS_RXN<7>"
				( objectStatus "@baseboard_fab2_lib.baseboard_fab2(sch_1):p3e_cpu0_pe2_ss_rxn(7)" )
			)
			( signal "P3E_CPU0_PE2_SS_RXN<8>"
				( objectStatus "@baseboard_fab2_lib.baseboard_fab2(sch_1):p3e_cpu0_pe2_ss_rxn(8)" )
			)
			( signal "P3E_CPU0_PE2_SS_RXN<9>"
				( objectStatus "@baseboard_fab2_lib.baseboard_fab2(sch_1):p3e_cpu0_pe2_ss_rxn(9)" )
			)
			( signal "P3E_CPU0_PE2_SS_RXN<10>"
				( objectStatus "@baseboard_fab2_lib.baseboard_fab2(sch_1):p3e_cpu0_pe2_ss_rxn(10)" )
			)
			( signal "P3E_CPU0_PE2_SS_RXN<11>"
				( objectStatus "@baseboard_fab2_lib.baseboard_fab2(sch_1):p3e_cpu0_pe2_ss_rxn(11)" )
			)
			( signal "P3E_CPU0_PE2_SS_RXN<12>"
				( objectStatus "@baseboard_fab2_lib.baseboard_fab2(sch_1):p3e_cpu0_pe2_ss_rxn(12)" )
			)
			( signal "P3E_CPU0_PE2_SS_RXN<13>"
				( objectStatus "@baseboard_fab2_lib.baseboard_fab2(sch_1):p3e_cpu0_pe2_ss_rxn(13)" )
			)
			( signal "P3E_CPU0_PE2_SS_RXN<14>"
				( objectStatus "@baseboard_fab2_lib.baseboard_fab2(sch_1):p3e_cpu0_pe2_ss_rxn(14)" )
			)
			( signal "P3E_CPU0_PE2_SS_RXN<15>"
				( objectStatus "@baseboard_fab2_lib.baseboard_fab2(sch_1):p3e_cpu0_pe2_ss_rxn(15)" )
			)
			( signal "P3E_CPU0_PE2_SS_RXP<0>"
				( objectStatus "@baseboard_fab2_lib.baseboard_fab2(sch_1):p3e_cpu0_pe2_ss_rxp(0)" )
			)
			( signal "P3E_CPU0_PE2_SS_RXP<1>"
				( objectStatus "@baseboard_fab2_lib.baseboard_fab2(sch_1):p3e_cpu0_pe2_ss_rxp(1)" )
			)
			( signal "P3E_CPU0_PE2_SS_RXP<2>"
				( objectStatus "@baseboard_fab2_lib.baseboard_fab2(sch_1):p3e_cpu0_pe2_ss_rxp(2)" )
			)
			( signal "P3E_CPU0_PE2_SS_RXP<3>"
				( objectStatus "@baseboard_fab2_lib.baseboard_fab2(sch_1):p3e_cpu0_pe2_ss_rxp(3)" )
			)
			( signal "P3E_CPU0_PE2_SS_RXP<4>"
				( objectStatus "@baseboard_fab2_lib.baseboard_fab2(sch_1):p3e_cpu0_pe2_ss_rxp(4)" )
			)
			( signal "P3E_CPU0_PE2_SS_RXP<5>"
				( objectStatus "@baseboard_fab2_lib.baseboard_fab2(sch_1):p3e_cpu0_pe2_ss_rxp(5)" )
			)
			( signal "P3E_CPU0_PE2_SS_RXP<6>"
				( objectStatus "@baseboard_fab2_lib.baseboard_fab2(sch_1):p3e_cpu0_pe2_ss_rxp(6)" )
			)
			( signal "P3E_CPU0_PE2_SS_RXP<7>"
				( objectStatus "@baseboard_fab2_lib.baseboard_fab2(sch_1):p3e_cpu0_pe2_ss_rxp(7)" )
			)
			( signal "P3E_CPU0_PE2_SS_RXP<8>"
				( objectStatus "@baseboard_fab2_lib.baseboard_fab2(sch_1):p3e_cpu0_pe2_ss_rxp(8)" )
			)
			( signal "P3E_CPU0_PE2_SS_RXP<9>"
				( objectStatus "@baseboard_fab2_lib.baseboard_fab2(sch_1):p3e_cpu0_pe2_ss_rxp(9)" )
			)
			( signal "P3E_CPU0_PE2_SS_RXP<10>"
				( objectStatus "@baseboard_fab2_lib.baseboard_fab2(sch_1):p3e_cpu0_pe2_ss_rxp(10)" )
			)
			( signal "P3E_CPU0_PE2_SS_RXP<11>"
				( objectStatus "@baseboard_fab2_lib.baseboard_fab2(sch_1):p3e_cpu0_pe2_ss_rxp(11)" )
			)
			( signal "P3E_CPU0_PE2_SS_RXP<12>"
				( objectStatus "@baseboard_fab2_lib.baseboard_fab2(sch_1):p3e_cpu0_pe2_ss_rxp(12)" )
			)
			( signal "P3E_CPU0_PE2_SS_RXP<13>"
				( objectStatus "@baseboard_fab2_lib.baseboard_fab2(sch_1):p3e_cpu0_pe2_ss_rxp(13)" )
			)
			( signal "P3E_CPU0_PE2_SS_RXP<14>"
				( objectStatus "@baseboard_fab2_lib.baseboard_fab2(sch_1):p3e_cpu0_pe2_ss_rxp(14)" )
			)
			( signal "P3E_CPU0_PE2_SS_RXP<15>"
				( objectStatus "@baseboard_fab2_lib.baseboard_fab2(sch_1):p3e_cpu0_pe2_ss_rxp(15)" )
			)
			( signal "P3E_CPU0_PE2_SS_TXN<0>"
				( objectStatus "@baseboard_fab2_lib.baseboard_fab2(sch_1):p3e_cpu0_pe2_ss_txn(0)" )
			)
			( signal "P3E_CPU0_PE2_SS_TXN<1>"
				( objectStatus "@baseboard_fab2_lib.baseboard_fab2(sch_1):p3e_cpu0_pe2_ss_txn(1)" )
			)
			( signal "P3E_CPU0_PE2_SS_TXN<2>"
				( objectStatus "@baseboard_fab2_lib.baseboard_fab2(sch_1):p3e_cpu0_pe2_ss_txn(2)" )
			)
			( signal "P3E_CPU0_PE2_SS_TXN<3>"
				( objectStatus "@baseboard_fab2_lib.baseboard_fab2(sch_1):p3e_cpu0_pe2_ss_txn(3)" )
			)
			( signal "P3E_CPU0_PE2_SS_TXN<4>"
				( objectStatus "@baseboard_fab2_lib.baseboard_fab2(sch_1):p3e_cpu0_pe2_ss_txn(4)" )
			)
			( signal "P3E_CPU0_PE2_SS_TXN<5>"
				( objectStatus "@baseboard_fab2_lib.baseboard_fab2(sch_1):p3e_cpu0_pe2_ss_txn(5)" )
			)
			( signal "P3E_CPU0_PE2_SS_TXN<6>"
				( objectStatus "@baseboard_fab2_lib.baseboard_fab2(sch_1):p3e_cpu0_pe2_ss_txn(6)" )
			)
			( signal "P3E_CPU0_PE2_SS_TXN<7>"
				( objectStatus "@baseboard_fab2_lib.baseboard_fab2(sch_1):p3e_cpu0_pe2_ss_txn(7)" )
			)
			( signal "P3E_CPU0_PE2_SS_TXN<8>"
				( objectStatus "@baseboard_fab2_lib.baseboard_fab2(sch_1):p3e_cpu0_pe2_ss_txn(8)" )
			)
			( signal "P3E_CPU0_PE2_SS_TXN<9>"
				( objectStatus "@baseboard_fab2_lib.baseboard_fab2(sch_1):p3e_cpu0_pe2_ss_txn(9)" )
			)
			( signal "P3E_CPU0_PE2_SS_TXN<10>"
				( objectStatus "@baseboard_fab2_lib.baseboard_fab2(sch_1):p3e_cpu0_pe2_ss_txn(10)" )
			)
			( signal "P3E_CPU0_PE2_SS_TXN<11>"
				( objectStatus "@baseboard_fab2_lib.baseboard_fab2(sch_1):p3e_cpu0_pe2_ss_txn(11)" )
			)
			( signal "P3E_CPU0_PE2_SS_TXN<12>"
				( objectStatus "@baseboard_fab2_lib.baseboard_fab2(sch_1):p3e_cpu0_pe2_ss_txn(12)" )
			)
			( signal "P3E_CPU0_PE2_SS_TXN<13>"
				( objectStatus "@baseboard_fab2_lib.baseboard_fab2(sch_1):p3e_cpu0_pe2_ss_txn(13)" )
			)
			( signal "P3E_CPU0_PE2_SS_TXN<14>"
				( objectStatus "@baseboard_fab2_lib.baseboard_fab2(sch_1):p3e_cpu0_pe2_ss_txn(14)" )
			)
			( signal "P3E_CPU0_PE2_SS_TXN<15>"
				( objectStatus "@baseboard_fab2_lib.baseboard_fab2(sch_1):p3e_cpu0_pe2_ss_txn(15)" )
			)
			( signal "P3E_CPU0_PE2_SS_TXP<0>"
				( objectStatus "@baseboard_fab2_lib.baseboard_fab2(sch_1):p3e_cpu0_pe2_ss_txp(0)" )
			)
			( signal "P3E_CPU0_PE2_SS_TXP<1>"
				( objectStatus "@baseboard_fab2_lib.baseboard_fab2(sch_1):p3e_cpu0_pe2_ss_txp(1)" )
			)
			( signal "P3E_CPU0_PE2_SS_TXP<2>"
				( objectStatus "@baseboard_fab2_lib.baseboard_fab2(sch_1):p3e_cpu0_pe2_ss_txp(2)" )
			)
			( signal "P3E_CPU0_PE2_SS_TXP<3>"
				( objectStatus "@baseboard_fab2_lib.baseboard_fab2(sch_1):p3e_cpu0_pe2_ss_txp(3)" )
			)
			( signal "P3E_CPU0_PE2_SS_TXP<4>"
				( objectStatus "@baseboard_fab2_lib.baseboard_fab2(sch_1):p3e_cpu0_pe2_ss_txp(4)" )
			)
			( signal "P3E_CPU0_PE2_SS_TXP<5>"
				( objectStatus "@baseboard_fab2_lib.baseboard_fab2(sch_1):p3e_cpu0_pe2_ss_txp(5)" )
			)
			( signal "P3E_CPU0_PE2_SS_TXP<6>"
				( objectStatus "@baseboard_fab2_lib.baseboard_fab2(sch_1):p3e_cpu0_pe2_ss_txp(6)" )
			)
			( signal "P3E_CPU0_PE2_SS_TXP<7>"
				( objectStatus "@baseboard_fab2_lib.baseboard_fab2(sch_1):p3e_cpu0_pe2_ss_txp(7)" )
			)
			( signal "P3E_CPU0_PE2_SS_TXP<8>"
				( objectStatus "@baseboard_fab2_lib.baseboard_fab2(sch_1):p3e_cpu0_pe2_ss_txp(8)" )
			)
			( signal "P3E_CPU0_PE2_SS_TXP<9>"
				( objectStatus "@baseboard_fab2_lib.baseboard_fab2(sch_1):p3e_cpu0_pe2_ss_txp(9)" )
			)
			( signal "P3E_CPU0_PE2_SS_TXP<10>"
				( objectStatus "@baseboard_fab2_lib.baseboard_fab2(sch_1):p3e_cpu0_pe2_ss_txp(10)" )
			)
			( signal "P3E_CPU0_PE2_SS_TXP<11>"
				( objectStatus "@baseboard_fab2_lib.baseboard_fab2(sch_1):p3e_cpu0_pe2_ss_txp(11)" )
			)
			( signal "P3E_CPU0_PE2_SS_TXP<12>"
				( objectStatus "@baseboard_fab2_lib.baseboard_fab2(sch_1):p3e_cpu0_pe2_ss_txp(12)" )
			)
			( signal "P3E_CPU0_PE2_SS_TXP<13>"
				( objectStatus "@baseboard_fab2_lib.baseboard_fab2(sch_1):p3e_cpu0_pe2_ss_txp(13)" )
			)
			( signal "P3E_CPU0_PE2_SS_TXP<14>"
				( objectStatus "@baseboard_fab2_lib.baseboard_fab2(sch_1):p3e_cpu0_pe2_ss_txp(14)" )
			)
			( signal "P3E_CPU0_PE2_SS_TXP<15>"
				( objectStatus "@baseboard_fab2_lib.baseboard_fab2(sch_1):p3e_cpu0_pe2_ss_txp(15)" )
			)
			( signal "P3E_CPU0_PE3_OCP_RXN<0>"
				( objectStatus "@baseboard_fab2_lib.baseboard_fab2(sch_1):p3e_cpu0_pe3_ocp_rxn(0)" )
			)
			( signal "P3E_CPU0_PE3_OCP_RXN<1>"
				( objectStatus "@baseboard_fab2_lib.baseboard_fab2(sch_1):p3e_cpu0_pe3_ocp_rxn(1)" )
			)
			( signal "P3E_CPU0_PE3_OCP_RXN<2>"
				( objectStatus "@baseboard_fab2_lib.baseboard_fab2(sch_1):p3e_cpu0_pe3_ocp_rxn(2)" )
			)
			( signal "P3E_CPU0_PE3_OCP_RXN<3>"
				( objectStatus "@baseboard_fab2_lib.baseboard_fab2(sch_1):p3e_cpu0_pe3_ocp_rxn(3)" )
			)
			( signal "P3E_CPU0_PE3_OCP_RXN<4>"
				( objectStatus "@baseboard_fab2_lib.baseboard_fab2(sch_1):p3e_cpu0_pe3_ocp_rxn(4)" )
			)
			( signal "P3E_CPU0_PE3_OCP_RXN<5>"
				( objectStatus "@baseboard_fab2_lib.baseboard_fab2(sch_1):p3e_cpu0_pe3_ocp_rxn(5)" )
			)
			( signal "P3E_CPU0_PE3_OCP_RXN<6>"
				( objectStatus "@baseboard_fab2_lib.baseboard_fab2(sch_1):p3e_cpu0_pe3_ocp_rxn(6)" )
			)
			( signal "P3E_CPU0_PE3_OCP_RXN<7>"
				( objectStatus "@baseboard_fab2_lib.baseboard_fab2(sch_1):p3e_cpu0_pe3_ocp_rxn(7)" )
			)
			( signal "P3E_CPU0_PE3_OCP_RXN<8>"
				( objectStatus "@baseboard_fab2_lib.baseboard_fab2(sch_1):p3e_cpu0_pe3_ocp_rxn(8)" )
			)
			( signal "P3E_CPU0_PE3_OCP_RXN<9>"
				( objectStatus "@baseboard_fab2_lib.baseboard_fab2(sch_1):p3e_cpu0_pe3_ocp_rxn(9)" )
			)
			( signal "P3E_CPU0_PE3_OCP_RXN<10>"
				( objectStatus "@baseboard_fab2_lib.baseboard_fab2(sch_1):p3e_cpu0_pe3_ocp_rxn(10)" )
			)
			( signal "P3E_CPU0_PE3_OCP_RXN<11>"
				( objectStatus "@baseboard_fab2_lib.baseboard_fab2(sch_1):p3e_cpu0_pe3_ocp_rxn(11)" )
			)
			( signal "P3E_CPU0_PE3_OCP_RXN<12>"
				( objectStatus "@baseboard_fab2_lib.baseboard_fab2(sch_1):p3e_cpu0_pe3_ocp_rxn(12)" )
			)
			( signal "P3E_CPU0_PE3_OCP_RXN<13>"
				( objectStatus "@baseboard_fab2_lib.baseboard_fab2(sch_1):p3e_cpu0_pe3_ocp_rxn(13)" )
			)
			( signal "P3E_CPU0_PE3_OCP_RXN<14>"
				( objectStatus "@baseboard_fab2_lib.baseboard_fab2(sch_1):p3e_cpu0_pe3_ocp_rxn(14)" )
			)
			( signal "P3E_CPU0_PE3_OCP_RXN<15>"
				( objectStatus "@baseboard_fab2_lib.baseboard_fab2(sch_1):p3e_cpu0_pe3_ocp_rxn(15)" )
			)
			( signal "P3E_CPU0_PE3_OCP_RXP<0>"
				( objectStatus "@baseboard_fab2_lib.baseboard_fab2(sch_1):p3e_cpu0_pe3_ocp_rxp(0)" )
			)
			( signal "P3E_CPU0_PE3_OCP_RXP<1>"
				( objectStatus "@baseboard_fab2_lib.baseboard_fab2(sch_1):p3e_cpu0_pe3_ocp_rxp(1)" )
			)
			( signal "P3E_CPU0_PE3_OCP_RXP<2>"
				( objectStatus "@baseboard_fab2_lib.baseboard_fab2(sch_1):p3e_cpu0_pe3_ocp_rxp(2)" )
			)
			( signal "P3E_CPU0_PE3_OCP_RXP<3>"
				( objectStatus "@baseboard_fab2_lib.baseboard_fab2(sch_1):p3e_cpu0_pe3_ocp_rxp(3)" )
			)
			( signal "P3E_CPU0_PE3_OCP_RXP<4>"
				( objectStatus "@baseboard_fab2_lib.baseboard_fab2(sch_1):p3e_cpu0_pe3_ocp_rxp(4)" )
			)
			( signal "P3E_CPU0_PE3_OCP_RXP<5>"
				( objectStatus "@baseboard_fab2_lib.baseboard_fab2(sch_1):p3e_cpu0_pe3_ocp_rxp(5)" )
			)
			( signal "P3E_CPU0_PE3_OCP_RXP<6>"
				( objectStatus "@baseboard_fab2_lib.baseboard_fab2(sch_1):p3e_cpu0_pe3_ocp_rxp(6)" )
			)
			( signal "P3E_CPU0_PE3_OCP_RXP<7>"
				( objectStatus "@baseboard_fab2_lib.baseboard_fab2(sch_1):p3e_cpu0_pe3_ocp_rxp(7)" )
			)
			( signal "P3E_CPU0_PE3_OCP_RXP<8>"
				( objectStatus "@baseboard_fab2_lib.baseboard_fab2(sch_1):p3e_cpu0_pe3_ocp_rxp(8)" )
			)
			( signal "P3E_CPU0_PE3_OCP_RXP<9>"
				( objectStatus "@baseboard_fab2_lib.baseboard_fab2(sch_1):p3e_cpu0_pe3_ocp_rxp(9)" )
			)
			( signal "P3E_CPU0_PE3_OCP_RXP<10>"
				( objectStatus "@baseboard_fab2_lib.baseboard_fab2(sch_1):p3e_cpu0_pe3_ocp_rxp(10)" )
			)
			( signal "P3E_CPU0_PE3_OCP_RXP<11>"
				( objectStatus "@baseboard_fab2_lib.baseboard_fab2(sch_1):p3e_cpu0_pe3_ocp_rxp(11)" )
			)
			( signal "P3E_CPU0_PE3_OCP_RXP<12>"
				( objectStatus "@baseboard_fab2_lib.baseboard_fab2(sch_1):p3e_cpu0_pe3_ocp_rxp(12)" )
			)
			( signal "P3E_CPU0_PE3_OCP_RXP<13>"
				( objectStatus "@baseboard_fab2_lib.baseboard_fab2(sch_1):p3e_cpu0_pe3_ocp_rxp(13)" )
			)
			( signal "P3E_CPU0_PE3_OCP_RXP<14>"
				( objectStatus "@baseboard_fab2_lib.baseboard_fab2(sch_1):p3e_cpu0_pe3_ocp_rxp(14)" )
			)
			( signal "P3E_CPU0_PE3_OCP_RXP<15>"
				( objectStatus "@baseboard_fab2_lib.baseboard_fab2(sch_1):p3e_cpu0_pe3_ocp_rxp(15)" )
			)
			( signal "P3E_CPU0_PE3_OCP_TXN<0>"
				( objectStatus "@baseboard_fab2_lib.baseboard_fab2(sch_1):p3e_cpu0_pe3_ocp_txn(0)" )
			)
			( signal "P3E_CPU0_PE3_OCP_TXN<1>"
				( objectStatus "@baseboard_fab2_lib.baseboard_fab2(sch_1):p3e_cpu0_pe3_ocp_txn(1)" )
			)
			( signal "P3E_CPU0_PE3_OCP_TXN<2>"
				( objectStatus "@baseboard_fab2_lib.baseboard_fab2(sch_1):p3e_cpu0_pe3_ocp_txn(2)" )
			)
			( signal "P3E_CPU0_PE3_OCP_TXN<3>"
				( objectStatus "@baseboard_fab2_lib.baseboard_fab2(sch_1):p3e_cpu0_pe3_ocp_txn(3)" )
			)
			( signal "P3E_CPU0_PE3_OCP_TXN<4>"
				( objectStatus "@baseboard_fab2_lib.baseboard_fab2(sch_1):p3e_cpu0_pe3_ocp_txn(4)" )
			)
			( signal "P3E_CPU0_PE3_OCP_TXN<5>"
				( objectStatus "@baseboard_fab2_lib.baseboard_fab2(sch_1):p3e_cpu0_pe3_ocp_txn(5)" )
			)
			( signal "P3E_CPU0_PE3_OCP_TXN<6>"
				( objectStatus "@baseboard_fab2_lib.baseboard_fab2(sch_1):p3e_cpu0_pe3_ocp_txn(6)" )
			)
			( signal "P3E_CPU0_PE3_OCP_TXN<7>"
				( objectStatus "@baseboard_fab2_lib.baseboard_fab2(sch_1):p3e_cpu0_pe3_ocp_txn(7)" )
			)
			( signal "P3E_CPU0_PE3_OCP_TXN<8>"
				( objectStatus "@baseboard_fab2_lib.baseboard_fab2(sch_1):p3e_cpu0_pe3_ocp_txn(8)" )
			)
			( signal "P3E_CPU0_PE3_OCP_TXN<9>"
				( objectStatus "@baseboard_fab2_lib.baseboard_fab2(sch_1):p3e_cpu0_pe3_ocp_txn(9)" )
			)
			( signal "P3E_CPU0_PE3_OCP_TXN<10>"
				( objectStatus "@baseboard_fab2_lib.baseboard_fab2(sch_1):p3e_cpu0_pe3_ocp_txn(10)" )
			)
			( signal "P3E_CPU0_PE3_OCP_TXN<11>"
				( objectStatus "@baseboard_fab2_lib.baseboard_fab2(sch_1):p3e_cpu0_pe3_ocp_txn(11)" )
			)
			( signal "P3E_CPU0_PE3_OCP_TXN<12>"
				( objectStatus "@baseboard_fab2_lib.baseboard_fab2(sch_1):p3e_cpu0_pe3_ocp_txn(12)" )
			)
			( signal "P3E_CPU0_PE3_OCP_TXN<13>"
				( objectStatus "@baseboard_fab2_lib.baseboard_fab2(sch_1):p3e_cpu0_pe3_ocp_txn(13)" )
			)
			( signal "P3E_CPU0_PE3_OCP_TXN<14>"
				( objectStatus "@baseboard_fab2_lib.baseboard_fab2(sch_1):p3e_cpu0_pe3_ocp_txn(14)" )
			)
			( signal "P3E_CPU0_PE3_OCP_TXN<15>"
				( objectStatus "@baseboard_fab2_lib.baseboard_fab2(sch_1):p3e_cpu0_pe3_ocp_txn(15)" )
			)
			( signal "P3E_CPU0_PE3_OCP_TXP<0>"
				( objectStatus "@baseboard_fab2_lib.baseboard_fab2(sch_1):p3e_cpu0_pe3_ocp_txp(0)" )
			)
			( signal "P3E_CPU0_PE3_OCP_TXP<1>"
				( objectStatus "@baseboard_fab2_lib.baseboard_fab2(sch_1):p3e_cpu0_pe3_ocp_txp(1)" )
			)
			( signal "P3E_CPU0_PE3_OCP_TXP<2>"
				( objectStatus "@baseboard_fab2_lib.baseboard_fab2(sch_1):p3e_cpu0_pe3_ocp_txp(2)" )
			)
			( signal "P3E_CPU0_PE3_OCP_TXP<3>"
				( objectStatus "@baseboard_fab2_lib.baseboard_fab2(sch_1):p3e_cpu0_pe3_ocp_txp(3)" )
			)
			( signal "P3E_CPU0_PE3_OCP_TXP<4>"
				( objectStatus "@baseboard_fab2_lib.baseboard_fab2(sch_1):p3e_cpu0_pe3_ocp_txp(4)" )
			)
			( signal "P3E_CPU0_PE3_OCP_TXP<5>"
				( objectStatus "@baseboard_fab2_lib.baseboard_fab2(sch_1):p3e_cpu0_pe3_ocp_txp(5)" )
			)
			( signal "P3E_CPU0_PE3_OCP_TXP<6>"
				( objectStatus "@baseboard_fab2_lib.baseboard_fab2(sch_1):p3e_cpu0_pe3_ocp_txp(6)" )
			)
			( signal "P3E_CPU0_PE3_OCP_TXP<7>"
				( objectStatus "@baseboard_fab2_lib.baseboard_fab2(sch_1):p3e_cpu0_pe3_ocp_txp(7)" )
			)
			( signal "P3E_CPU0_PE3_OCP_TXP<8>"
				( objectStatus "@baseboard_fab2_lib.baseboard_fab2(sch_1):p3e_cpu0_pe3_ocp_txp(8)" )
			)
			( signal "P3E_CPU0_PE3_OCP_TXP<9>"
				( objectStatus "@baseboard_fab2_lib.baseboard_fab2(sch_1):p3e_cpu0_pe3_ocp_txp(9)" )
			)
			( signal "P3E_CPU0_PE3_OCP_TXP<10>"
				( objectStatus "@baseboard_fab2_lib.baseboard_fab2(sch_1):p3e_cpu0_pe3_ocp_txp(10)" )
			)
			( signal "P3E_CPU0_PE3_OCP_TXP<11>"
				( objectStatus "@baseboard_fab2_lib.baseboard_fab2(sch_1):p3e_cpu0_pe3_ocp_txp(11)" )
			)
			( signal "P3E_CPU0_PE3_OCP_TXP<12>"
				( objectStatus "@baseboard_fab2_lib.baseboard_fab2(sch_1):p3e_cpu0_pe3_ocp_txp(12)" )
			)
			( signal "P3E_CPU0_PE3_OCP_TXP<13>"
				( objectStatus "@baseboard_fab2_lib.baseboard_fab2(sch_1):p3e_cpu0_pe3_ocp_txp(13)" )
			)
			( signal "P3E_CPU0_PE3_OCP_TXP<14>"
				( objectStatus "@baseboard_fab2_lib.baseboard_fab2(sch_1):p3e_cpu0_pe3_ocp_txp(14)" )
			)
			( signal "P3E_CPU0_PE3_OCP_TXP<15>"
				( objectStatus "@baseboard_fab2_lib.baseboard_fab2(sch_1):p3e_cpu0_pe3_ocp_txp(15)" )
			)
			( signal "UPI_CPU0_CPU1_P0P0_DN<0>"
				( objectStatus "@baseboard_fab2_lib.baseboard_fab2(sch_1):upi_cpu0_cpu1_p0p0_dn(0)" )
			)
			( signal "UPI_CPU0_CPU1_P0P0_DN<1>"
				( objectStatus "@baseboard_fab2_lib.baseboard_fab2(sch_1):upi_cpu0_cpu1_p0p0_dn(1)" )
			)
			( signal "UPI_CPU0_CPU1_P0P0_DN<2>"
				( objectStatus "@baseboard_fab2_lib.baseboard_fab2(sch_1):upi_cpu0_cpu1_p0p0_dn(2)" )
			)
			( signal "UPI_CPU0_CPU1_P0P0_DN<3>"
				( objectStatus "@baseboard_fab2_lib.baseboard_fab2(sch_1):upi_cpu0_cpu1_p0p0_dn(3)" )
			)
			( signal "UPI_CPU0_CPU1_P0P0_DN<4>"
				( objectStatus "@baseboard_fab2_lib.baseboard_fab2(sch_1):upi_cpu0_cpu1_p0p0_dn(4)" )
			)
			( signal "UPI_CPU0_CPU1_P0P0_DN<5>"
				( objectStatus "@baseboard_fab2_lib.baseboard_fab2(sch_1):upi_cpu0_cpu1_p0p0_dn(5)" )
			)
			( signal "UPI_CPU0_CPU1_P0P0_DN<6>"
				( objectStatus "@baseboard_fab2_lib.baseboard_fab2(sch_1):upi_cpu0_cpu1_p0p0_dn(6)" )
			)
			( signal "UPI_CPU0_CPU1_P0P0_DN<7>"
				( objectStatus "@baseboard_fab2_lib.baseboard_fab2(sch_1):upi_cpu0_cpu1_p0p0_dn(7)" )
			)
			( signal "UPI_CPU0_CPU1_P0P0_DN<8>"
				( objectStatus "@baseboard_fab2_lib.baseboard_fab2(sch_1):upi_cpu0_cpu1_p0p0_dn(8)" )
			)
			( signal "UPI_CPU0_CPU1_P0P0_DN<9>"
				( objectStatus "@baseboard_fab2_lib.baseboard_fab2(sch_1):upi_cpu0_cpu1_p0p0_dn(9)" )
			)
			( signal "UPI_CPU0_CPU1_P0P0_DN<10>"
				( objectStatus "@baseboard_fab2_lib.baseboard_fab2(sch_1):upi_cpu0_cpu1_p0p0_dn(10)" )
			)
			( signal "UPI_CPU0_CPU1_P0P0_DN<11>"
				( objectStatus "@baseboard_fab2_lib.baseboard_fab2(sch_1):upi_cpu0_cpu1_p0p0_dn(11)" )
			)
			( signal "UPI_CPU0_CPU1_P0P0_DN<12>"
				( objectStatus "@baseboard_fab2_lib.baseboard_fab2(sch_1):upi_cpu0_cpu1_p0p0_dn(12)" )
			)
			( signal "UPI_CPU0_CPU1_P0P0_DN<13>"
				( objectStatus "@baseboard_fab2_lib.baseboard_fab2(sch_1):upi_cpu0_cpu1_p0p0_dn(13)" )
			)
			( signal "UPI_CPU0_CPU1_P0P0_DN<14>"
				( objectStatus "@baseboard_fab2_lib.baseboard_fab2(sch_1):upi_cpu0_cpu1_p0p0_dn(14)" )
			)
			( signal "UPI_CPU0_CPU1_P0P0_DN<15>"
				( objectStatus "@baseboard_fab2_lib.baseboard_fab2(sch_1):upi_cpu0_cpu1_p0p0_dn(15)" )
			)
			( signal "UPI_CPU0_CPU1_P0P0_DN<16>"
				( objectStatus "@baseboard_fab2_lib.baseboard_fab2(sch_1):upi_cpu0_cpu1_p0p0_dn(16)" )
			)
			( signal "UPI_CPU0_CPU1_P0P0_DN<17>"
				( objectStatus "@baseboard_fab2_lib.baseboard_fab2(sch_1):upi_cpu0_cpu1_p0p0_dn(17)" )
			)
			( signal "UPI_CPU0_CPU1_P0P0_DN<18>"
				( objectStatus "@baseboard_fab2_lib.baseboard_fab2(sch_1):upi_cpu0_cpu1_p0p0_dn(18)" )
			)
			( signal "UPI_CPU0_CPU1_P0P0_DN<19>"
				( objectStatus "@baseboard_fab2_lib.baseboard_fab2(sch_1):upi_cpu0_cpu1_p0p0_dn(19)" )
			)
			( signal "UPI_CPU0_CPU1_P0P0_DP<0>"
				( objectStatus "@baseboard_fab2_lib.baseboard_fab2(sch_1):upi_cpu0_cpu1_p0p0_dp(0)" )
			)
			( signal "UPI_CPU0_CPU1_P0P0_DP<1>"
				( objectStatus "@baseboard_fab2_lib.baseboard_fab2(sch_1):upi_cpu0_cpu1_p0p0_dp(1)" )
			)
			( signal "UPI_CPU0_CPU1_P0P0_DP<2>"
				( objectStatus "@baseboard_fab2_lib.baseboard_fab2(sch_1):upi_cpu0_cpu1_p0p0_dp(2)" )
			)
			( signal "UPI_CPU0_CPU1_P0P0_DP<3>"
				( objectStatus "@baseboard_fab2_lib.baseboard_fab2(sch_1):upi_cpu0_cpu1_p0p0_dp(3)" )
			)
			( signal "UPI_CPU0_CPU1_P0P0_DP<4>"
				( objectStatus "@baseboard_fab2_lib.baseboard_fab2(sch_1):upi_cpu0_cpu1_p0p0_dp(4)" )
			)
			( signal "UPI_CPU0_CPU1_P0P0_DP<5>"
				( objectStatus "@baseboard_fab2_lib.baseboard_fab2(sch_1):upi_cpu0_cpu1_p0p0_dp(5)" )
			)
			( signal "UPI_CPU0_CPU1_P0P0_DP<6>"
				( objectStatus "@baseboard_fab2_lib.baseboard_fab2(sch_1):upi_cpu0_cpu1_p0p0_dp(6)" )
			)
			( signal "UPI_CPU0_CPU1_P0P0_DP<7>"
				( objectStatus "@baseboard_fab2_lib.baseboard_fab2(sch_1):upi_cpu0_cpu1_p0p0_dp(7)" )
			)
			( signal "UPI_CPU0_CPU1_P0P0_DP<8>"
				( objectStatus "@baseboard_fab2_lib.baseboard_fab2(sch_1):upi_cpu0_cpu1_p0p0_dp(8)" )
			)
			( signal "UPI_CPU0_CPU1_P0P0_DP<9>"
				( objectStatus "@baseboard_fab2_lib.baseboard_fab2(sch_1):upi_cpu0_cpu1_p0p0_dp(9)" )
			)
			( signal "UPI_CPU0_CPU1_P0P0_DP<10>"
				( objectStatus "@baseboard_fab2_lib.baseboard_fab2(sch_1):upi_cpu0_cpu1_p0p0_dp(10)" )
			)
			( signal "UPI_CPU0_CPU1_P0P0_DP<11>"
				( objectStatus "@baseboard_fab2_lib.baseboard_fab2(sch_1):upi_cpu0_cpu1_p0p0_dp(11)" )
			)
			( signal "UPI_CPU0_CPU1_P0P0_DP<12>"
				( objectStatus "@baseboard_fab2_lib.baseboard_fab2(sch_1):upi_cpu0_cpu1_p0p0_dp(12)" )
			)
			( signal "UPI_CPU0_CPU1_P0P0_DP<13>"
				( objectStatus "@baseboard_fab2_lib.baseboard_fab2(sch_1):upi_cpu0_cpu1_p0p0_dp(13)" )
			)
			( signal "UPI_CPU0_CPU1_P0P0_DP<14>"
				( objectStatus "@baseboard_fab2_lib.baseboard_fab2(sch_1):upi_cpu0_cpu1_p0p0_dp(14)" )
			)
			( signal "UPI_CPU0_CPU1_P0P0_DP<15>"
				( objectStatus "@baseboard_fab2_lib.baseboard_fab2(sch_1):upi_cpu0_cpu1_p0p0_dp(15)" )
			)
			( signal "UPI_CPU0_CPU1_P0P0_DP<16>"
				( objectStatus "@baseboard_fab2_lib.baseboard_fab2(sch_1):upi_cpu0_cpu1_p0p0_dp(16)" )
			)
			( signal "UPI_CPU0_CPU1_P0P0_DP<17>"
				( objectStatus "@baseboard_fab2_lib.baseboard_fab2(sch_1):upi_cpu0_cpu1_p0p0_dp(17)" )
			)
			( signal "UPI_CPU0_CPU1_P0P0_DP<18>"
				( objectStatus "@baseboard_fab2_lib.baseboard_fab2(sch_1):upi_cpu0_cpu1_p0p0_dp(18)" )
			)
			( signal "UPI_CPU0_CPU1_P0P0_DP<19>"
				( objectStatus "@baseboard_fab2_lib.baseboard_fab2(sch_1):upi_cpu0_cpu1_p0p0_dp(19)" )
			)
			( signal "UPI_CPU1_CPU0_P0P0_DN<0>"
				( objectStatus "@baseboard_fab2_lib.baseboard_fab2(sch_1):upi_cpu1_cpu0_p0p0_dn(0)" )
			)
			( signal "UPI_CPU1_CPU0_P0P0_DN<1>"
				( objectStatus "@baseboard_fab2_lib.baseboard_fab2(sch_1):upi_cpu1_cpu0_p0p0_dn(1)" )
			)
			( signal "UPI_CPU1_CPU0_P0P0_DN<2>"
				( objectStatus "@baseboard_fab2_lib.baseboard_fab2(sch_1):upi_cpu1_cpu0_p0p0_dn(2)" )
			)
			( signal "UPI_CPU1_CPU0_P0P0_DN<3>"
				( objectStatus "@baseboard_fab2_lib.baseboard_fab2(sch_1):upi_cpu1_cpu0_p0p0_dn(3)" )
			)
			( signal "UPI_CPU1_CPU0_P0P0_DN<4>"
				( objectStatus "@baseboard_fab2_lib.baseboard_fab2(sch_1):upi_cpu1_cpu0_p0p0_dn(4)" )
			)
			( signal "UPI_CPU1_CPU0_P0P0_DN<5>"
				( objectStatus "@baseboard_fab2_lib.baseboard_fab2(sch_1):upi_cpu1_cpu0_p0p0_dn(5)" )
			)
			( signal "UPI_CPU1_CPU0_P0P0_DN<6>"
				( objectStatus "@baseboard_fab2_lib.baseboard_fab2(sch_1):upi_cpu1_cpu0_p0p0_dn(6)" )
			)
			( signal "UPI_CPU1_CPU0_P0P0_DN<7>"
				( objectStatus "@baseboard_fab2_lib.baseboard_fab2(sch_1):upi_cpu1_cpu0_p0p0_dn(7)" )
			)
			( signal "UPI_CPU1_CPU0_P0P0_DN<8>"
				( objectStatus "@baseboard_fab2_lib.baseboard_fab2(sch_1):upi_cpu1_cpu0_p0p0_dn(8)" )
			)
			( signal "UPI_CPU1_CPU0_P0P0_DN<9>"
				( objectStatus "@baseboard_fab2_lib.baseboard_fab2(sch_1):upi_cpu1_cpu0_p0p0_dn(9)" )
			)
			( signal "UPI_CPU1_CPU0_P0P0_DN<10>"
				( objectStatus "@baseboard_fab2_lib.baseboard_fab2(sch_1):upi_cpu1_cpu0_p0p0_dn(10)" )
			)
			( signal "UPI_CPU1_CPU0_P0P0_DN<11>"
				( objectStatus "@baseboard_fab2_lib.baseboard_fab2(sch_1):upi_cpu1_cpu0_p0p0_dn(11)" )
			)
			( signal "UPI_CPU1_CPU0_P0P0_DN<12>"
				( objectStatus "@baseboard_fab2_lib.baseboard_fab2(sch_1):upi_cpu1_cpu0_p0p0_dn(12)" )
			)
			( signal "UPI_CPU1_CPU0_P0P0_DN<13>"
				( objectStatus "@baseboard_fab2_lib.baseboard_fab2(sch_1):upi_cpu1_cpu0_p0p0_dn(13)" )
			)
			( signal "UPI_CPU1_CPU0_P0P0_DN<14>"
				( objectStatus "@baseboard_fab2_lib.baseboard_fab2(sch_1):upi_cpu1_cpu0_p0p0_dn(14)" )
			)
			( signal "UPI_CPU1_CPU0_P0P0_DN<15>"
				( objectStatus "@baseboard_fab2_lib.baseboard_fab2(sch_1):upi_cpu1_cpu0_p0p0_dn(15)" )
			)
			( signal "UPI_CPU1_CPU0_P0P0_DN<16>"
				( objectStatus "@baseboard_fab2_lib.baseboard_fab2(sch_1):upi_cpu1_cpu0_p0p0_dn(16)" )
			)
			( signal "UPI_CPU1_CPU0_P0P0_DN<17>"
				( objectStatus "@baseboard_fab2_lib.baseboard_fab2(sch_1):upi_cpu1_cpu0_p0p0_dn(17)" )
			)
			( signal "UPI_CPU1_CPU0_P0P0_DN<18>"
				( objectStatus "@baseboard_fab2_lib.baseboard_fab2(sch_1):upi_cpu1_cpu0_p0p0_dn(18)" )
			)
			( signal "UPI_CPU1_CPU0_P0P0_DN<19>"
				( objectStatus "@baseboard_fab2_lib.baseboard_fab2(sch_1):upi_cpu1_cpu0_p0p0_dn(19)" )
			)
			( signal "UPI_CPU1_CPU0_P0P0_DP<0>"
				( objectStatus "@baseboard_fab2_lib.baseboard_fab2(sch_1):upi_cpu1_cpu0_p0p0_dp(0)" )
			)
			( signal "UPI_CPU1_CPU0_P0P0_DP<1>"
				( objectStatus "@baseboard_fab2_lib.baseboard_fab2(sch_1):upi_cpu1_cpu0_p0p0_dp(1)" )
			)
			( signal "UPI_CPU1_CPU0_P0P0_DP<2>"
				( objectStatus "@baseboard_fab2_lib.baseboard_fab2(sch_1):upi_cpu1_cpu0_p0p0_dp(2)" )
			)
			( signal "UPI_CPU1_CPU0_P0P0_DP<3>"
				( objectStatus "@baseboard_fab2_lib.baseboard_fab2(sch_1):upi_cpu1_cpu0_p0p0_dp(3)" )
			)
			( signal "UPI_CPU1_CPU0_P0P0_DP<4>"
				( objectStatus "@baseboard_fab2_lib.baseboard_fab2(sch_1):upi_cpu1_cpu0_p0p0_dp(4)" )
			)
			( signal "UPI_CPU1_CPU0_P0P0_DP<5>"
				( objectStatus "@baseboard_fab2_lib.baseboard_fab2(sch_1):upi_cpu1_cpu0_p0p0_dp(5)" )
			)
			( signal "UPI_CPU1_CPU0_P0P0_DP<6>"
				( objectStatus "@baseboard_fab2_lib.baseboard_fab2(sch_1):upi_cpu1_cpu0_p0p0_dp(6)" )
			)
			( signal "UPI_CPU1_CPU0_P0P0_DP<7>"
				( objectStatus "@baseboard_fab2_lib.baseboard_fab2(sch_1):upi_cpu1_cpu0_p0p0_dp(7)" )
			)
			( signal "UPI_CPU1_CPU0_P0P0_DP<8>"
				( objectStatus "@baseboard_fab2_lib.baseboard_fab2(sch_1):upi_cpu1_cpu0_p0p0_dp(8)" )
			)
			( signal "UPI_CPU1_CPU0_P0P0_DP<9>"
				( objectStatus "@baseboard_fab2_lib.baseboard_fab2(sch_1):upi_cpu1_cpu0_p0p0_dp(9)" )
			)
			( signal "UPI_CPU1_CPU0_P0P0_DP<10>"
				( objectStatus "@baseboard_fab2_lib.baseboard_fab2(sch_1):upi_cpu1_cpu0_p0p0_dp(10)" )
			)
			( signal "UPI_CPU1_CPU0_P0P0_DP<11>"
				( objectStatus "@baseboard_fab2_lib.baseboard_fab2(sch_1):upi_cpu1_cpu0_p0p0_dp(11)" )
			)
			( signal "UPI_CPU1_CPU0_P0P0_DP<12>"
				( objectStatus "@baseboard_fab2_lib.baseboard_fab2(sch_1):upi_cpu1_cpu0_p0p0_dp(12)" )
			)
			( signal "UPI_CPU1_CPU0_P0P0_DP<13>"
				( objectStatus "@baseboard_fab2_lib.baseboard_fab2(sch_1):upi_cpu1_cpu0_p0p0_dp(13)" )
			)
			( signal "UPI_CPU1_CPU0_P0P0_DP<14>"
				( objectStatus "@baseboard_fab2_lib.baseboard_fab2(sch_1):upi_cpu1_cpu0_p0p0_dp(14)" )
			)
			( signal "UPI_CPU1_CPU0_P0P0_DP<15>"
				( objectStatus "@baseboard_fab2_lib.baseboard_fab2(sch_1):upi_cpu1_cpu0_p0p0_dp(15)" )
			)
			( signal "UPI_CPU1_CPU0_P0P0_DP<16>"
				( objectStatus "@baseboard_fab2_lib.baseboard_fab2(sch_1):upi_cpu1_cpu0_p0p0_dp(16)" )
			)
			( signal "UPI_CPU1_CPU0_P0P0_DP<17>"
				( objectStatus "@baseboard_fab2_lib.baseboard_fab2(sch_1):upi_cpu1_cpu0_p0p0_dp(17)" )
			)
			( signal "UPI_CPU1_CPU0_P0P0_DP<18>"
				( objectStatus "@baseboard_fab2_lib.baseboard_fab2(sch_1):upi_cpu1_cpu0_p0p0_dp(18)" )
			)
			( signal "UPI_CPU1_CPU0_P0P0_DP<19>"
				( objectStatus "@baseboard_fab2_lib.baseboard_fab2(sch_1):upi_cpu1_cpu0_p0p0_dp(19)" )
			)
			( signal "UPI_CPU0_CPU1_P1P1_DN<0>"
				( objectStatus "@baseboard_fab2_lib.baseboard_fab2(sch_1):upi_cpu0_cpu1_p1p1_dn(0)" )
			)
			( signal "UPI_CPU0_CPU1_P1P1_DN<1>"
				( objectStatus "@baseboard_fab2_lib.baseboard_fab2(sch_1):upi_cpu0_cpu1_p1p1_dn(1)" )
			)
			( signal "UPI_CPU0_CPU1_P1P1_DN<2>"
				( objectStatus "@baseboard_fab2_lib.baseboard_fab2(sch_1):upi_cpu0_cpu1_p1p1_dn(2)" )
			)
			( signal "UPI_CPU0_CPU1_P1P1_DN<3>"
				( objectStatus "@baseboard_fab2_lib.baseboard_fab2(sch_1):upi_cpu0_cpu1_p1p1_dn(3)" )
			)
			( signal "UPI_CPU0_CPU1_P1P1_DN<4>"
				( objectStatus "@baseboard_fab2_lib.baseboard_fab2(sch_1):upi_cpu0_cpu1_p1p1_dn(4)" )
			)
			( signal "UPI_CPU0_CPU1_P1P1_DN<5>"
				( objectStatus "@baseboard_fab2_lib.baseboard_fab2(sch_1):upi_cpu0_cpu1_p1p1_dn(5)" )
			)
			( signal "UPI_CPU0_CPU1_P1P1_DN<6>"
				( objectStatus "@baseboard_fab2_lib.baseboard_fab2(sch_1):upi_cpu0_cpu1_p1p1_dn(6)" )
			)
			( signal "UPI_CPU0_CPU1_P1P1_DN<7>"
				( objectStatus "@baseboard_fab2_lib.baseboard_fab2(sch_1):upi_cpu0_cpu1_p1p1_dn(7)" )
			)
			( signal "UPI_CPU0_CPU1_P1P1_DN<8>"
				( objectStatus "@baseboard_fab2_lib.baseboard_fab2(sch_1):upi_cpu0_cpu1_p1p1_dn(8)" )
			)
			( signal "UPI_CPU0_CPU1_P1P1_DN<9>"
				( objectStatus "@baseboard_fab2_lib.baseboard_fab2(sch_1):upi_cpu0_cpu1_p1p1_dn(9)" )
			)
			( signal "UPI_CPU0_CPU1_P1P1_DN<10>"
				( objectStatus "@baseboard_fab2_lib.baseboard_fab2(sch_1):upi_cpu0_cpu1_p1p1_dn(10)" )
			)
			( signal "UPI_CPU0_CPU1_P1P1_DN<11>"
				( objectStatus "@baseboard_fab2_lib.baseboard_fab2(sch_1):upi_cpu0_cpu1_p1p1_dn(11)" )
			)
			( signal "UPI_CPU0_CPU1_P1P1_DN<12>"
				( objectStatus "@baseboard_fab2_lib.baseboard_fab2(sch_1):upi_cpu0_cpu1_p1p1_dn(12)" )
			)
			( signal "UPI_CPU0_CPU1_P1P1_DN<13>"
				( objectStatus "@baseboard_fab2_lib.baseboard_fab2(sch_1):upi_cpu0_cpu1_p1p1_dn(13)" )
			)
			( signal "UPI_CPU0_CPU1_P1P1_DN<14>"
				( objectStatus "@baseboard_fab2_lib.baseboard_fab2(sch_1):upi_cpu0_cpu1_p1p1_dn(14)" )
			)
			( signal "UPI_CPU0_CPU1_P1P1_DN<15>"
				( objectStatus "@baseboard_fab2_lib.baseboard_fab2(sch_1):upi_cpu0_cpu1_p1p1_dn(15)" )
			)
			( signal "UPI_CPU0_CPU1_P1P1_DN<16>"
				( objectStatus "@baseboard_fab2_lib.baseboard_fab2(sch_1):upi_cpu0_cpu1_p1p1_dn(16)" )
			)
			( signal "UPI_CPU0_CPU1_P1P1_DN<17>"
				( objectStatus "@baseboard_fab2_lib.baseboard_fab2(sch_1):upi_cpu0_cpu1_p1p1_dn(17)" )
			)
			( signal "UPI_CPU0_CPU1_P1P1_DN<18>"
				( objectStatus "@baseboard_fab2_lib.baseboard_fab2(sch_1):upi_cpu0_cpu1_p1p1_dn(18)" )
			)
			( signal "UPI_CPU0_CPU1_P1P1_DN<19>"
				( objectStatus "@baseboard_fab2_lib.baseboard_fab2(sch_1):upi_cpu0_cpu1_p1p1_dn(19)" )
			)
			( signal "UPI_CPU0_CPU1_P1P1_DP<0>"
				( objectStatus "@baseboard_fab2_lib.baseboard_fab2(sch_1):upi_cpu0_cpu1_p1p1_dp(0)" )
			)
			( signal "UPI_CPU0_CPU1_P1P1_DP<1>"
				( objectStatus "@baseboard_fab2_lib.baseboard_fab2(sch_1):upi_cpu0_cpu1_p1p1_dp(1)" )
			)
			( signal "UPI_CPU0_CPU1_P1P1_DP<2>"
				( objectStatus "@baseboard_fab2_lib.baseboard_fab2(sch_1):upi_cpu0_cpu1_p1p1_dp(2)" )
			)
			( signal "UPI_CPU0_CPU1_P1P1_DP<3>"
				( objectStatus "@baseboard_fab2_lib.baseboard_fab2(sch_1):upi_cpu0_cpu1_p1p1_dp(3)" )
			)
			( signal "UPI_CPU0_CPU1_P1P1_DP<4>"
				( objectStatus "@baseboard_fab2_lib.baseboard_fab2(sch_1):upi_cpu0_cpu1_p1p1_dp(4)" )
			)
			( signal "UPI_CPU0_CPU1_P1P1_DP<5>"
				( objectStatus "@baseboard_fab2_lib.baseboard_fab2(sch_1):upi_cpu0_cpu1_p1p1_dp(5)" )
			)
			( signal "UPI_CPU0_CPU1_P1P1_DP<6>"
				( objectStatus "@baseboard_fab2_lib.baseboard_fab2(sch_1):upi_cpu0_cpu1_p1p1_dp(6)" )
			)
			( signal "UPI_CPU0_CPU1_P1P1_DP<7>"
				( objectStatus "@baseboard_fab2_lib.baseboard_fab2(sch_1):upi_cpu0_cpu1_p1p1_dp(7)" )
			)
			( signal "UPI_CPU0_CPU1_P1P1_DP<8>"
				( objectStatus "@baseboard_fab2_lib.baseboard_fab2(sch_1):upi_cpu0_cpu1_p1p1_dp(8)" )
			)
			( signal "UPI_CPU0_CPU1_P1P1_DP<9>"
				( objectStatus "@baseboard_fab2_lib.baseboard_fab2(sch_1):upi_cpu0_cpu1_p1p1_dp(9)" )
			)
			( signal "UPI_CPU0_CPU1_P1P1_DP<10>"
				( objectStatus "@baseboard_fab2_lib.baseboard_fab2(sch_1):upi_cpu0_cpu1_p1p1_dp(10)" )
			)
			( signal "UPI_CPU0_CPU1_P1P1_DP<11>"
				( objectStatus "@baseboard_fab2_lib.baseboard_fab2(sch_1):upi_cpu0_cpu1_p1p1_dp(11)" )
			)
			( signal "UPI_CPU0_CPU1_P1P1_DP<12>"
				( objectStatus "@baseboard_fab2_lib.baseboard_fab2(sch_1):upi_cpu0_cpu1_p1p1_dp(12)" )
			)
			( signal "UPI_CPU0_CPU1_P1P1_DP<13>"
				( objectStatus "@baseboard_fab2_lib.baseboard_fab2(sch_1):upi_cpu0_cpu1_p1p1_dp(13)" )
			)
			( signal "UPI_CPU0_CPU1_P1P1_DP<14>"
				( objectStatus "@baseboard_fab2_lib.baseboard_fab2(sch_1):upi_cpu0_cpu1_p1p1_dp(14)" )
			)
			( signal "UPI_CPU0_CPU1_P1P1_DP<15>"
				( objectStatus "@baseboard_fab2_lib.baseboard_fab2(sch_1):upi_cpu0_cpu1_p1p1_dp(15)" )
			)
			( signal "UPI_CPU0_CPU1_P1P1_DP<16>"
				( objectStatus "@baseboard_fab2_lib.baseboard_fab2(sch_1):upi_cpu0_cpu1_p1p1_dp(16)" )
			)
			( signal "UPI_CPU0_CPU1_P1P1_DP<17>"
				( objectStatus "@baseboard_fab2_lib.baseboard_fab2(sch_1):upi_cpu0_cpu1_p1p1_dp(17)" )
			)
			( signal "UPI_CPU0_CPU1_P1P1_DP<18>"
				( objectStatus "@baseboard_fab2_lib.baseboard_fab2(sch_1):upi_cpu0_cpu1_p1p1_dp(18)" )
			)
			( signal "UPI_CPU0_CPU1_P1P1_DP<19>"
				( objectStatus "@baseboard_fab2_lib.baseboard_fab2(sch_1):upi_cpu0_cpu1_p1p1_dp(19)" )
			)
			( signal "UPI_CPU1_CPU0_P1P1_DN<0>"
				( objectStatus "@baseboard_fab2_lib.baseboard_fab2(sch_1):upi_cpu1_cpu0_p1p1_dn(0)" )
			)
			( signal "UPI_CPU1_CPU0_P1P1_DN<1>"
				( objectStatus "@baseboard_fab2_lib.baseboard_fab2(sch_1):upi_cpu1_cpu0_p1p1_dn(1)" )
			)
			( signal "UPI_CPU1_CPU0_P1P1_DN<2>"
				( objectStatus "@baseboard_fab2_lib.baseboard_fab2(sch_1):upi_cpu1_cpu0_p1p1_dn(2)" )
			)
			( signal "UPI_CPU1_CPU0_P1P1_DN<3>"
				( objectStatus "@baseboard_fab2_lib.baseboard_fab2(sch_1):upi_cpu1_cpu0_p1p1_dn(3)" )
			)
			( signal "UPI_CPU1_CPU0_P1P1_DN<4>"
				( objectStatus "@baseboard_fab2_lib.baseboard_fab2(sch_1):upi_cpu1_cpu0_p1p1_dn(4)" )
			)
			( signal "UPI_CPU1_CPU0_P1P1_DN<5>"
				( objectStatus "@baseboard_fab2_lib.baseboard_fab2(sch_1):upi_cpu1_cpu0_p1p1_dn(5)" )
			)
			( signal "UPI_CPU1_CPU0_P1P1_DN<6>"
				( objectStatus "@baseboard_fab2_lib.baseboard_fab2(sch_1):upi_cpu1_cpu0_p1p1_dn(6)" )
			)
			( signal "UPI_CPU1_CPU0_P1P1_DN<7>"
				( objectStatus "@baseboard_fab2_lib.baseboard_fab2(sch_1):upi_cpu1_cpu0_p1p1_dn(7)" )
			)
			( signal "UPI_CPU1_CPU0_P1P1_DN<8>"
				( objectStatus "@baseboard_fab2_lib.baseboard_fab2(sch_1):upi_cpu1_cpu0_p1p1_dn(8)" )
			)
			( signal "UPI_CPU1_CPU0_P1P1_DN<9>"
				( objectStatus "@baseboard_fab2_lib.baseboard_fab2(sch_1):upi_cpu1_cpu0_p1p1_dn(9)" )
			)
			( signal "UPI_CPU1_CPU0_P1P1_DN<10>"
				( objectStatus "@baseboard_fab2_lib.baseboard_fab2(sch_1):upi_cpu1_cpu0_p1p1_dn(10)" )
			)
			( signal "UPI_CPU1_CPU0_P1P1_DN<11>"
				( objectStatus "@baseboard_fab2_lib.baseboard_fab2(sch_1):upi_cpu1_cpu0_p1p1_dn(11)" )
			)
			( signal "UPI_CPU1_CPU0_P1P1_DN<12>"
				( objectStatus "@baseboard_fab2_lib.baseboard_fab2(sch_1):upi_cpu1_cpu0_p1p1_dn(12)" )
			)
			( signal "UPI_CPU1_CPU0_P1P1_DN<13>"
				( objectStatus "@baseboard_fab2_lib.baseboard_fab2(sch_1):upi_cpu1_cpu0_p1p1_dn(13)" )
			)
			( signal "UPI_CPU1_CPU0_P1P1_DN<14>"
				( objectStatus "@baseboard_fab2_lib.baseboard_fab2(sch_1):upi_cpu1_cpu0_p1p1_dn(14)" )
			)
			( signal "UPI_CPU1_CPU0_P1P1_DN<15>"
				( objectStatus "@baseboard_fab2_lib.baseboard_fab2(sch_1):upi_cpu1_cpu0_p1p1_dn(15)" )
			)
			( signal "UPI_CPU1_CPU0_P1P1_DN<16>"
				( objectStatus "@baseboard_fab2_lib.baseboard_fab2(sch_1):upi_cpu1_cpu0_p1p1_dn(16)" )
			)
			( signal "UPI_CPU1_CPU0_P1P1_DN<17>"
				( objectStatus "@baseboard_fab2_lib.baseboard_fab2(sch_1):upi_cpu1_cpu0_p1p1_dn(17)" )
			)
			( signal "UPI_CPU1_CPU0_P1P1_DN<18>"
				( objectStatus "@baseboard_fab2_lib.baseboard_fab2(sch_1):upi_cpu1_cpu0_p1p1_dn(18)" )
			)
			( signal "UPI_CPU1_CPU0_P1P1_DN<19>"
				( objectStatus "@baseboard_fab2_lib.baseboard_fab2(sch_1):upi_cpu1_cpu0_p1p1_dn(19)" )
			)
			( signal "UPI_CPU1_CPU0_P1P1_DP<0>"
				( objectStatus "@baseboard_fab2_lib.baseboard_fab2(sch_1):upi_cpu1_cpu0_p1p1_dp(0)" )
			)
			( signal "UPI_CPU1_CPU0_P1P1_DP<1>"
				( objectStatus "@baseboard_fab2_lib.baseboard_fab2(sch_1):upi_cpu1_cpu0_p1p1_dp(1)" )
			)
			( signal "UPI_CPU1_CPU0_P1P1_DP<2>"
				( objectStatus "@baseboard_fab2_lib.baseboard_fab2(sch_1):upi_cpu1_cpu0_p1p1_dp(2)" )
			)
			( signal "UPI_CPU1_CPU0_P1P1_DP<3>"
				( objectStatus "@baseboard_fab2_lib.baseboard_fab2(sch_1):upi_cpu1_cpu0_p1p1_dp(3)" )
			)
			( signal "UPI_CPU1_CPU0_P1P1_DP<4>"
				( objectStatus "@baseboard_fab2_lib.baseboard_fab2(sch_1):upi_cpu1_cpu0_p1p1_dp(4)" )
			)
			( signal "UPI_CPU1_CPU0_P1P1_DP<5>"
				( objectStatus "@baseboard_fab2_lib.baseboard_fab2(sch_1):upi_cpu1_cpu0_p1p1_dp(5)" )
			)
			( signal "UPI_CPU1_CPU0_P1P1_DP<6>"
				( objectStatus "@baseboard_fab2_lib.baseboard_fab2(sch_1):upi_cpu1_cpu0_p1p1_dp(6)" )
			)
			( signal "UPI_CPU1_CPU0_P1P1_DP<7>"
				( objectStatus "@baseboard_fab2_lib.baseboard_fab2(sch_1):upi_cpu1_cpu0_p1p1_dp(7)" )
			)
			( signal "UPI_CPU1_CPU0_P1P1_DP<8>"
				( objectStatus "@baseboard_fab2_lib.baseboard_fab2(sch_1):upi_cpu1_cpu0_p1p1_dp(8)" )
			)
			( signal "UPI_CPU1_CPU0_P1P1_DP<9>"
				( objectStatus "@baseboard_fab2_lib.baseboard_fab2(sch_1):upi_cpu1_cpu0_p1p1_dp(9)" )
			)
			( signal "UPI_CPU1_CPU0_P1P1_DP<10>"
				( objectStatus "@baseboard_fab2_lib.baseboard_fab2(sch_1):upi_cpu1_cpu0_p1p1_dp(10)" )
			)
			( signal "UPI_CPU1_CPU0_P1P1_DP<11>"
				( objectStatus "@baseboard_fab2_lib.baseboard_fab2(sch_1):upi_cpu1_cpu0_p1p1_dp(11)" )
			)
			( signal "UPI_CPU1_CPU0_P1P1_DP<12>"
				( objectStatus "@baseboard_fab2_lib.baseboard_fab2(sch_1):upi_cpu1_cpu0_p1p1_dp(12)" )
			)
			( signal "UPI_CPU1_CPU0_P1P1_DP<13>"
				( objectStatus "@baseboard_fab2_lib.baseboard_fab2(sch_1):upi_cpu1_cpu0_p1p1_dp(13)" )
			)
			( signal "UPI_CPU1_CPU0_P1P1_DP<14>"
				( objectStatus "@baseboard_fab2_lib.baseboard_fab2(sch_1):upi_cpu1_cpu0_p1p1_dp(14)" )
			)
			( signal "UPI_CPU1_CPU0_P1P1_DP<15>"
				( objectStatus "@baseboard_fab2_lib.baseboard_fab2(sch_1):upi_cpu1_cpu0_p1p1_dp(15)" )
			)
			( signal "UPI_CPU1_CPU0_P1P1_DP<16>"
				( objectStatus "@baseboard_fab2_lib.baseboard_fab2(sch_1):upi_cpu1_cpu0_p1p1_dp(16)" )
			)
			( signal "UPI_CPU1_CPU0_P1P1_DP<17>"
				( objectStatus "@baseboard_fab2_lib.baseboard_fab2(sch_1):upi_cpu1_cpu0_p1p1_dp(17)" )
			)
			( signal "UPI_CPU1_CPU0_P1P1_DP<18>"
				( objectStatus "@baseboard_fab2_lib.baseboard_fab2(sch_1):upi_cpu1_cpu0_p1p1_dp(18)" )
			)
			( signal "UPI_CPU1_CPU0_P1P1_DP<19>"
				( objectStatus "@baseboard_fab2_lib.baseboard_fab2(sch_1):upi_cpu1_cpu0_p1p1_dp(19)" )
			)
			( signal "TP_CPU0_UPI2_RSVD_CA12"
				( objectStatus "@baseboard_fab2_lib.baseboard_fab2(sch_1):tp_cpu0_upi2_rsvd_ca12" )
			)
			( signal "TP_CPU0_UPI2_RSVD_CB11"
				( objectStatus "@baseboard_fab2_lib.baseboard_fab2(sch_1):tp_cpu0_upi2_rsvd_cb11" )
			)
			( signal "TP_CPU0_UPI2_RSVD_CC10"
				( objectStatus "@baseboard_fab2_lib.baseboard_fab2(sch_1):tp_cpu0_upi2_rsvd_cc10" )
			)
			( signal "TP_CPU0_UPI2_RSVD_CC12"
				( objectStatus "@baseboard_fab2_lib.baseboard_fab2(sch_1):tp_cpu0_upi2_rsvd_cc12" )
			)
			( signal "TP_CPU0_UPI2_RSVD_CD11"
				( objectStatus "@baseboard_fab2_lib.baseboard_fab2(sch_1):tp_cpu0_upi2_rsvd_cd11" )
			)
			( signal "TP_CPU0_UPI2_RSVD_CE12"
				( objectStatus "@baseboard_fab2_lib.baseboard_fab2(sch_1):tp_cpu0_upi2_rsvd_ce12" )
			)
			( signal "TP_CPU0_UPI2_RSVD_CF11"
				( objectStatus "@baseboard_fab2_lib.baseboard_fab2(sch_1):tp_cpu0_upi2_rsvd_cf11" )
			)
			( signal "TP_CPU0_UPI2_RSVD_CF13"
				( objectStatus "@baseboard_fab2_lib.baseboard_fab2(sch_1):tp_cpu0_upi2_rsvd_cf13" )
			)
			( signal "TP_CPU0_UPI2_RSVD_CG12"
				( objectStatus "@baseboard_fab2_lib.baseboard_fab2(sch_1):tp_cpu0_upi2_rsvd_cg12" )
			)
			( signal "TP_CPU0_UPI2_RSVD_CH11"
				( objectStatus "@baseboard_fab2_lib.baseboard_fab2(sch_1):tp_cpu0_upi2_rsvd_ch11" )
			)
			( signal "TP_CPU0_UPI2_RSVD_CH13"
				( objectStatus "@baseboard_fab2_lib.baseboard_fab2(sch_1):tp_cpu0_upi2_rsvd_ch13" )
			)
			( signal "TP_CPU0_UPI2_RSVD_CJ14"
				( objectStatus "@baseboard_fab2_lib.baseboard_fab2(sch_1):tp_cpu0_upi2_rsvd_cj14" )
			)
			( signal "TP_CPU0_UPI2_RSVD_CK13"
				( objectStatus "@baseboard_fab2_lib.baseboard_fab2(sch_1):tp_cpu0_upi2_rsvd_ck13" )
			)
			( signal "TP_CPU0_UPI2_RSVD_CM13"
				( objectStatus "@baseboard_fab2_lib.baseboard_fab2(sch_1):tp_cpu0_upi2_rsvd_cm13" )
			)
			( signal "TP_CPU0_UPI2_RSVD_CR14"
				( objectStatus "@baseboard_fab2_lib.baseboard_fab2(sch_1):tp_cpu0_upi2_rsvd_cr14" )
			)
			( signal "TP_CPU0_UPI2_RSVD_CU14"
				( objectStatus "@baseboard_fab2_lib.baseboard_fab2(sch_1):tp_cpu0_upi2_rsvd_cu14" )
			)
			( signal "TP_CPU0_UPI2_RSVD_CV13"
				( objectStatus "@baseboard_fab2_lib.baseboard_fab2(sch_1):tp_cpu0_upi2_rsvd_cv13" )
			)
			( signal "TP_CPU0_UPI2_RSVD_CW14"
				( objectStatus "@baseboard_fab2_lib.baseboard_fab2(sch_1):tp_cpu0_upi2_rsvd_cw14" )
			)
			( signal "TP_CPU0_UPI2_RSVD_CW16"
				( objectStatus "@baseboard_fab2_lib.baseboard_fab2(sch_1):tp_cpu0_upi2_rsvd_cw16" )
			)
			( signal "TP_CPU0_UPI2_RSVD_DA16"
				( objectStatus "@baseboard_fab2_lib.baseboard_fab2(sch_1):tp_cpu0_upi2_rsvd_da16" )
			)
			( signal "TP_CPU0_UPI2_RSVD_DB15"
				( objectStatus "@baseboard_fab2_lib.baseboard_fab2(sch_1):tp_cpu0_upi2_rsvd_db15" )
			)
			( signal "TP_CPU0_UPI2_RSVD_DC16"
				( objectStatus "@baseboard_fab2_lib.baseboard_fab2(sch_1):tp_cpu0_upi2_rsvd_dc16" )
			)
			( signal "TP_CPU0_UPI2_RSVD_DD15"
				( objectStatus "@baseboard_fab2_lib.baseboard_fab2(sch_1):tp_cpu0_upi2_rsvd_dd15" )
			)
			( signal "TP_CPU0_UPI2_RSVD_DD17"
				( objectStatus "@baseboard_fab2_lib.baseboard_fab2(sch_1):tp_cpu0_upi2_rsvd_dd17" )
			)
			( signal "TP_CPU0_UPI2_RSVD_DE16"
				( objectStatus "@baseboard_fab2_lib.baseboard_fab2(sch_1):tp_cpu0_upi2_rsvd_de16" )
			)
			( signal "TP_CPU0_UPI2_RSVD_DF15"
				( objectStatus "@baseboard_fab2_lib.baseboard_fab2(sch_1):tp_cpu0_upi2_rsvd_df15" )
			)
			( signal "TP_CPU0_UPI2_RSVD_DF17"
				( objectStatus "@baseboard_fab2_lib.baseboard_fab2(sch_1):tp_cpu0_upi2_rsvd_df17" )
			)
			( signal "TP_CPU0_UPI2_RSVD_DG18"
				( objectStatus "@baseboard_fab2_lib.baseboard_fab2(sch_1):tp_cpu0_upi2_rsvd_dg18" )
			)
			( signal "TP_CPU0_UPI2_RSVD_DG20"
				( objectStatus "@baseboard_fab2_lib.baseboard_fab2(sch_1):tp_cpu0_upi2_rsvd_dg20" )
			)
			( signal "TP_CPU0_UPI2_RSVD_DH17"
				( objectStatus "@baseboard_fab2_lib.baseboard_fab2(sch_1):tp_cpu0_upi2_rsvd_dh17" )
			)
			( signal "TP_CPU0_UPI2_RSVD_DH19"
				( objectStatus "@baseboard_fab2_lib.baseboard_fab2(sch_1):tp_cpu0_upi2_rsvd_dh19" )
			)
			( signal "TP_CPU0_UPI2_RSVD_DJ18"
				( objectStatus "@baseboard_fab2_lib.baseboard_fab2(sch_1):tp_cpu0_upi2_rsvd_dj18" )
			)
			( signal "TP_CPU0_UPI2_RSVD_DJ20"
				( objectStatus "@baseboard_fab2_lib.baseboard_fab2(sch_1):tp_cpu0_upi2_rsvd_dj20" )
			)
			( signal "TP_CPU0_UPI2_RSVD_DK17"
				( objectStatus "@baseboard_fab2_lib.baseboard_fab2(sch_1):tp_cpu0_upi2_rsvd_dk17" )
			)
			( signal "TP_CPU0_UPI2_RSVD_DK19"
				( objectStatus "@baseboard_fab2_lib.baseboard_fab2(sch_1):tp_cpu0_upi2_rsvd_dk19" )
			)
			( signal "TP_CPU0_UPI2_RSVD_DL20"
				( objectStatus "@baseboard_fab2_lib.baseboard_fab2(sch_1):tp_cpu0_upi2_rsvd_dl20" )
			)
			( signal "TP_CPU0_UPI2_RSVD_DM21"
				( objectStatus "@baseboard_fab2_lib.baseboard_fab2(sch_1):tp_cpu0_upi2_rsvd_dm21" )
			)
			( signal "TP_CPU0_UPI2_RSVD_DN20"
				( objectStatus "@baseboard_fab2_lib.baseboard_fab2(sch_1):tp_cpu0_upi2_rsvd_dn20" )
			)
			( signal "TP_CPU0_UPI2_RSVD_DP21"
				( objectStatus "@baseboard_fab2_lib.baseboard_fab2(sch_1):tp_cpu0_upi2_rsvd_dp21" )
			)
			( signal "TP_CPU0_UPI2_RSVD_DT21"
				( objectStatus "@baseboard_fab2_lib.baseboard_fab2(sch_1):tp_cpu0_upi2_rsvd_dt21" )
			)
			( signal "CLK_100M_CPU0_RC_REFCLK1_DN"
				( objectStatus "@baseboard_fab2_lib.baseboard_fab2(sch_1):clk_100m_cpu0_rc_refclk1_dn" )
			)
			( signal "CLK_100M_CPU0_RC_REFCLK1_DP"
				( objectStatus "@baseboard_fab2_lib.baseboard_fab2(sch_1):clk_100m_cpu0_rc_refclk1_dp" )
			)
			( signal "TP_CPU0_RSVD_100"
				( objectStatus "@baseboard_fab2_lib.baseboard_fab2(sch_1):tp_cpu0_rsvd_100" )
			)
			( signal "TP_CPU0_RSVD_101"
				( objectStatus "@baseboard_fab2_lib.baseboard_fab2(sch_1):tp_cpu0_rsvd_101" )
			)
			( signal "TP_CPU0_RSVD_105"
				( objectStatus "@baseboard_fab2_lib.baseboard_fab2(sch_1):tp_cpu0_rsvd_105" )
			)
			( signal "TP_CPU0_RSVD_106"
				( objectStatus "@baseboard_fab2_lib.baseboard_fab2(sch_1):tp_cpu0_rsvd_106" )
			)
			( signal "TP_CPU0_RSVD_108"
				( objectStatus "@baseboard_fab2_lib.baseboard_fab2(sch_1):tp_cpu0_rsvd_108" )
			)
			( signal "TP_CPU0_RSVD_111"
				( objectStatus "@baseboard_fab2_lib.baseboard_fab2(sch_1):tp_cpu0_rsvd_111" )
			)
			( signal "TP_CPU0_RSVD_113"
				( objectStatus "@baseboard_fab2_lib.baseboard_fab2(sch_1):tp_cpu0_rsvd_113" )
			)
			( signal "TP_CPU0_RSVD_114"
				( objectStatus "@baseboard_fab2_lib.baseboard_fab2(sch_1):tp_cpu0_rsvd_114" )
			)
			( signal "TP_CPU0_RSVD_117"
				( objectStatus "@baseboard_fab2_lib.baseboard_fab2(sch_1):tp_cpu0_rsvd_117" )
			)
			( signal "TP_CPU0_RSVD_119"
				( objectStatus "@baseboard_fab2_lib.baseboard_fab2(sch_1):tp_cpu0_rsvd_119" )
			)
			( signal "TP_CPU0_RSVD_121"
				( objectStatus "@baseboard_fab2_lib.baseboard_fab2(sch_1):tp_cpu0_rsvd_121" )
			)
			( signal "TP_CPU0_RSVD_123"
				( objectStatus "@baseboard_fab2_lib.baseboard_fab2(sch_1):tp_cpu0_rsvd_123" )
			)
			( signal "TP_CPU0_RSVD_124"
				( objectStatus "@baseboard_fab2_lib.baseboard_fab2(sch_1):tp_cpu0_rsvd_124" )
			)
			( signal "TP_CPU0_RSVD_144"
				( objectStatus "@baseboard_fab2_lib.baseboard_fab2(sch_1):tp_cpu0_rsvd_144" )
			)
			( signal "TP_CPU0_RSVD_145"
				( objectStatus "@baseboard_fab2_lib.baseboard_fab2(sch_1):tp_cpu0_rsvd_145" )
			)
			( signal "TP_CPU0_RSVD_146"
				( objectStatus "@baseboard_fab2_lib.baseboard_fab2(sch_1):tp_cpu0_rsvd_146" )
			)
			( signal "TP_CPU0_RSVD_147"
				( objectStatus "@baseboard_fab2_lib.baseboard_fab2(sch_1):tp_cpu0_rsvd_147" )
			)
			( signal "TP_CPU0_RSVD_148"
				( objectStatus "@baseboard_fab2_lib.baseboard_fab2(sch_1):tp_cpu0_rsvd_148" )
			)
			( signal "TP_CPU0_RSVD_149"
				( objectStatus "@baseboard_fab2_lib.baseboard_fab2(sch_1):tp_cpu0_rsvd_149" )
			)
			( signal "TP_CPU0_RSVD_150"
				( objectStatus "@baseboard_fab2_lib.baseboard_fab2(sch_1):tp_cpu0_rsvd_150" )
			)
			( signal "TP_CPU0_RSVD_151"
				( objectStatus "@baseboard_fab2_lib.baseboard_fab2(sch_1):tp_cpu0_rsvd_151" )
			)
			( signal "TP_CPU0_RSVD_152"
				( objectStatus "@baseboard_fab2_lib.baseboard_fab2(sch_1):tp_cpu0_rsvd_152" )
			)
			( signal "TP_CPU0_RSVD_154"
				( objectStatus "@baseboard_fab2_lib.baseboard_fab2(sch_1):tp_cpu0_rsvd_154" )
			)
			( signal "TP_CPU0_RSVD_155"
				( objectStatus "@baseboard_fab2_lib.baseboard_fab2(sch_1):tp_cpu0_rsvd_155" )
			)
			( signal "TP_CPU0_RSVD_156"
				( objectStatus "@baseboard_fab2_lib.baseboard_fab2(sch_1):tp_cpu0_rsvd_156" )
			)
			( signal "TP_CPU0_RSVD_157"
				( objectStatus "@baseboard_fab2_lib.baseboard_fab2(sch_1):tp_cpu0_rsvd_157" )
			)
			( signal "TP_CPU0_RSVD_158"
				( objectStatus "@baseboard_fab2_lib.baseboard_fab2(sch_1):tp_cpu0_rsvd_158" )
			)
			( signal "TP_CPU0_RSVD_159"
				( objectStatus "@baseboard_fab2_lib.baseboard_fab2(sch_1):tp_cpu0_rsvd_159" )
			)
			( signal "TP_CPU0_RSVD_160"
				( objectStatus "@baseboard_fab2_lib.baseboard_fab2(sch_1):tp_cpu0_rsvd_160" )
			)
			( signal "TP_CPU0_RSVD_161"
				( objectStatus "@baseboard_fab2_lib.baseboard_fab2(sch_1):tp_cpu0_rsvd_161" )
			)
			( signal "TP_CPU0_RSVD_162"
				( objectStatus "@baseboard_fab2_lib.baseboard_fab2(sch_1):tp_cpu0_rsvd_162" )
			)
			( signal "TP_CPU0_RSVD_163"
				( objectStatus "@baseboard_fab2_lib.baseboard_fab2(sch_1):tp_cpu0_rsvd_163" )
			)
			( signal "TP_CPU0_RSVD_164"
				( objectStatus "@baseboard_fab2_lib.baseboard_fab2(sch_1):tp_cpu0_rsvd_164" )
			)
			( signal "TP_CPU0_RSVD_166"
				( objectStatus "@baseboard_fab2_lib.baseboard_fab2(sch_1):tp_cpu0_rsvd_166" )
			)
			( signal "TP_CPU0_RSVD_167"
				( objectStatus "@baseboard_fab2_lib.baseboard_fab2(sch_1):tp_cpu0_rsvd_167" )
			)
			( signal "TP_CPU0_RSVD_168"
				( objectStatus "@baseboard_fab2_lib.baseboard_fab2(sch_1):tp_cpu0_rsvd_168" )
			)
			( signal "TP_CPU0_RSVD_169"
				( objectStatus "@baseboard_fab2_lib.baseboard_fab2(sch_1):tp_cpu0_rsvd_169" )
			)
			( signal "TP_CPU0_RSVD_170"
				( objectStatus "@baseboard_fab2_lib.baseboard_fab2(sch_1):tp_cpu0_rsvd_170" )
			)
			( signal "TP_CPU0_RSVD_171"
				( objectStatus "@baseboard_fab2_lib.baseboard_fab2(sch_1):tp_cpu0_rsvd_171" )
			)
			( signal "TP_CPU0_RSVD_255"
				( objectStatus "@baseboard_fab2_lib.baseboard_fab2(sch_1):tp_cpu0_rsvd_255" )
			)
			( signal "TP_CPU0_RSVD_82"
				( objectStatus "@baseboard_fab2_lib.baseboard_fab2(sch_1):tp_cpu0_rsvd_82" )
			)
			( signal "TP_CPU0_RSVD_85"
				( objectStatus "@baseboard_fab2_lib.baseboard_fab2(sch_1):tp_cpu0_rsvd_85" )
			)
			( signal "TP_CPU0_RSVD_90"
				( objectStatus "@baseboard_fab2_lib.baseboard_fab2(sch_1):tp_cpu0_rsvd_90" )
			)
			( signal "TP_CPU0_RSVD_91"
				( objectStatus "@baseboard_fab2_lib.baseboard_fab2(sch_1):tp_cpu0_rsvd_91" )
			)
			( signal "TP_CPU0_RSVD_94"
				( objectStatus "@baseboard_fab2_lib.baseboard_fab2(sch_1):tp_cpu0_rsvd_94" )
			)
			( signal "TP_CPU0_RSVD_95"
				( objectStatus "@baseboard_fab2_lib.baseboard_fab2(sch_1):tp_cpu0_rsvd_95" )
			)
			( signal "TP_CPU0_RSVD_97"
				( objectStatus "@baseboard_fab2_lib.baseboard_fab2(sch_1):tp_cpu0_rsvd_97" )
			)
			( signal "TP_CPU0_RSVD_99"
				( objectStatus "@baseboard_fab2_lib.baseboard_fab2(sch_1):tp_cpu0_rsvd_99" )
			)
			( signal "TP_CPU0_TEST_10"
				( objectStatus "@baseboard_fab2_lib.baseboard_fab2(sch_1):tp_cpu0_test_10" )
			)
			( signal "TP_CPU0_TEST_6"
				( objectStatus "@baseboard_fab2_lib.baseboard_fab2(sch_1):tp_cpu0_test_6" )
			)
			( signal "TP_CPU0_TEST_7"
				( objectStatus "@baseboard_fab2_lib.baseboard_fab2(sch_1):tp_cpu0_test_7" )
			)
			( signal "TP_CPU0_TEST_8"
				( objectStatus "@baseboard_fab2_lib.baseboard_fab2(sch_1):tp_cpu0_test_8" )
			)
			( signal "TP_CPU0_TEST_9"
				( objectStatus "@baseboard_fab2_lib.baseboard_fab2(sch_1):tp_cpu0_test_9" )
			)
			( signal "PVCCIN_CPU0"
				( attribute "VOLTAGE" "2.0V"
					( Units "uVoltage" "V" 1.000000)
					( Status sAliasFlattened )
					( Origin gFrontEnd )
				)
				( objectStatus "@baseboard_fab2_lib.baseboard_fab2(sch_1):pvccin_cpu0" )
			)
			( signal "VSENSE_PMAX_CPU0"
				( attribute "VOLTAGE" "1.8"
					( Units "uVoltage" "V" 1.000000)
					( Status sAliasFlattened )
					( Origin gFrontEnd )
				)
				( objectStatus "@baseboard_fab2_lib.baseboard_fab2(sch_1):vsense_pmax_cpu0" )
			)
			( signal "VSENSE_PVCCIN_CPU0_SKT_VRTN"
				( attribute "VOLTAGE" "0.3"
					( Units "uVoltage" "V" 1.000000)
					( Status sAliasFlattened )
					( Origin gFrontEnd )
				)
				( objectStatus "@baseboard_fab2_lib.baseboard_fab2(sch_1):vsense_pvccin_cpu0_skt_vrtn" )
			)
			( signal "VSENSE_PVCCIN_CPU0_SKT_VSEN"
				( attribute "VOLTAGE" "2"
					( Units "uVoltage" "V" 1.000000)
					( Status sAliasFlattened )
					( Origin gFrontEnd )
				)
				( objectStatus "@baseboard_fab2_lib.baseboard_fab2(sch_1):vsense_pvccin_cpu0_skt_vsen" )
			)
			( signal "VSENSE_VCCINR2PMAX_CPU0"
				( objectStatus "@baseboard_fab2_lib.baseboard_fab2(sch_1):vsense_vccinr2pmax_cpu0" )
			)
			( signal "PVCCIOMCP_CPU0"
				( attribute "VOLTAGE" "+0.95"
					( Units "uVoltage" "V" 1.000000)
					( Status sAliasFlattened )
					( Origin gFrontEnd )
				)
				( objectStatus "@baseboard_fab2_lib.baseboard_fab2(sch_1):pvcciomcp_cpu0" )
			)
			( signal "PVDDQ_ABC"
				( attribute "VOLTAGE" "1.2V"
					( Units "uVoltage" "V" 1.000000)
					( Status sAliasFlattened )
					( Origin gFrontEnd )
				)
				( objectStatus "@baseboard_fab2_lib.baseboard_fab2(sch_1):pvddq_abc" )
			)
			( signal "PVDDQ_DEF"
				( attribute "VOLTAGE" "1.2V"
					( Units "uVoltage" "V" 1.000000)
					( Status sAliasFlattened )
					( Origin gFrontEnd )
				)
				( objectStatus "@baseboard_fab2_lib.baseboard_fab2(sch_1):pvddq_def" )
			)
			( signal "PVPP_ABC"
				( attribute "VOLTAGE" "2.5V"
					( Units "uVoltage" "V" 1.000000)
					( Status sAliasFlattened )
					( Origin gFrontEnd )
				)
				( objectStatus "@baseboard_fab2_lib.baseboard_fab2(sch_1):pvpp_abc" )
			)
			( signal "PVSA_CPU0"
				( attribute "VOLTAGE" "1.1V"
					( Units "uVoltage" "V" 1.000000)
					( Status sAliasFlattened )
					( Origin gFrontEnd )
				)
				( objectStatus "@baseboard_fab2_lib.baseboard_fab2(sch_1):pvsa_cpu0" )
			)
			( signal "PD_CPU0_MCP01_DMON"
				( objectStatus "@baseboard_fab2_lib.baseboard_fab2(sch_1):pd_cpu0_mcp01_dmon" )
			)
			( signal "TP_CPU0_KTI2_AMONV"
				( objectStatus "@baseboard_fab2_lib.baseboard_fab2(sch_1):tp_cpu0_kti2_amonv" )
			)
			( signal "TP_CPU0_KTI2_DFX_DN"
				( objectStatus "@baseboard_fab2_lib.baseboard_fab2(sch_1):tp_cpu0_kti2_dfx_dn" )
			)
			( signal "TP_CPU0_RSVD_0"
				( objectStatus "@baseboard_fab2_lib.baseboard_fab2(sch_1):tp_cpu0_rsvd_0" )
			)
			( signal "TP_CPU0_RSVD_1"
				( objectStatus "@baseboard_fab2_lib.baseboard_fab2(sch_1):tp_cpu0_rsvd_1" )
			)
			( signal "TP_CPU0_RSVD_10"
				( objectStatus "@baseboard_fab2_lib.baseboard_fab2(sch_1):tp_cpu0_rsvd_10" )
			)
			( signal "TP_CPU0_RSVD_11"
				( objectStatus "@baseboard_fab2_lib.baseboard_fab2(sch_1):tp_cpu0_rsvd_11" )
			)
			( signal "TP_CPU0_RSVD_12"
				( objectStatus "@baseboard_fab2_lib.baseboard_fab2(sch_1):tp_cpu0_rsvd_12" )
			)
			( signal "TP_CPU0_RSVD_13"
				( objectStatus "@baseboard_fab2_lib.baseboard_fab2(sch_1):tp_cpu0_rsvd_13" )
			)
			( signal "TP_CPU0_RSVD_14"
				( objectStatus "@baseboard_fab2_lib.baseboard_fab2(sch_1):tp_cpu0_rsvd_14" )
			)
			( signal "TP_CPU0_RSVD_15"
				( objectStatus "@baseboard_fab2_lib.baseboard_fab2(sch_1):tp_cpu0_rsvd_15" )
			)
			( signal "TP_CPU0_RSVD_16"
				( objectStatus "@baseboard_fab2_lib.baseboard_fab2(sch_1):tp_cpu0_rsvd_16" )
			)
			( signal "TP_CPU0_RSVD_17"
				( objectStatus "@baseboard_fab2_lib.baseboard_fab2(sch_1):tp_cpu0_rsvd_17" )
			)
			( signal "TP_CPU0_RSVD_18"
				( objectStatus "@baseboard_fab2_lib.baseboard_fab2(sch_1):tp_cpu0_rsvd_18" )
			)
			( signal "TP_CPU0_RSVD_19"
				( objectStatus "@baseboard_fab2_lib.baseboard_fab2(sch_1):tp_cpu0_rsvd_19" )
			)
			( signal "TP_CPU0_RSVD_2"
				( objectStatus "@baseboard_fab2_lib.baseboard_fab2(sch_1):tp_cpu0_rsvd_2" )
			)
			( signal "TP_CPU0_RSVD_20"
				( objectStatus "@baseboard_fab2_lib.baseboard_fab2(sch_1):tp_cpu0_rsvd_20" )
			)
			( signal "TP_CPU0_RSVD_21"
				( objectStatus "@baseboard_fab2_lib.baseboard_fab2(sch_1):tp_cpu0_rsvd_21" )
			)
			( signal "TP_CPU0_RSVD_22"
				( objectStatus "@baseboard_fab2_lib.baseboard_fab2(sch_1):tp_cpu0_rsvd_22" )
			)
			( signal "TP_CPU0_RSVD_23"
				( objectStatus "@baseboard_fab2_lib.baseboard_fab2(sch_1):tp_cpu0_rsvd_23" )
			)
			( signal "TP_CPU0_RSVD_24"
				( objectStatus "@baseboard_fab2_lib.baseboard_fab2(sch_1):tp_cpu0_rsvd_24" )
			)
			( signal "TP_CPU0_RSVD_25"
				( objectStatus "@baseboard_fab2_lib.baseboard_fab2(sch_1):tp_cpu0_rsvd_25" )
			)
			( signal "TP_CPU0_RSVD_26"
				( objectStatus "@baseboard_fab2_lib.baseboard_fab2(sch_1):tp_cpu0_rsvd_26" )
			)
			( signal "TP_CPU0_RSVD_27"
				( objectStatus "@baseboard_fab2_lib.baseboard_fab2(sch_1):tp_cpu0_rsvd_27" )
			)
			( signal "TP_CPU0_RSVD_28"
				( objectStatus "@baseboard_fab2_lib.baseboard_fab2(sch_1):tp_cpu0_rsvd_28" )
			)
			( signal "TP_CPU0_RSVD_29"
				( objectStatus "@baseboard_fab2_lib.baseboard_fab2(sch_1):tp_cpu0_rsvd_29" )
			)
			( signal "TP_CPU0_RSVD_3"
				( objectStatus "@baseboard_fab2_lib.baseboard_fab2(sch_1):tp_cpu0_rsvd_3" )
			)
			( signal "TP_CPU0_RSVD_30"
				( objectStatus "@baseboard_fab2_lib.baseboard_fab2(sch_1):tp_cpu0_rsvd_30" )
			)
			( signal "TP_CPU0_RSVD_31"
				( objectStatus "@baseboard_fab2_lib.baseboard_fab2(sch_1):tp_cpu0_rsvd_31" )
			)
			( signal "TP_CPU0_RSVD_32"
				( objectStatus "@baseboard_fab2_lib.baseboard_fab2(sch_1):tp_cpu0_rsvd_32" )
			)
			( signal "TP_CPU0_RSVD_33"
				( objectStatus "@baseboard_fab2_lib.baseboard_fab2(sch_1):tp_cpu0_rsvd_33" )
			)
			( signal "TP_CPU0_RSVD_34"
				( objectStatus "@baseboard_fab2_lib.baseboard_fab2(sch_1):tp_cpu0_rsvd_34" )
			)
			( signal "TP_CPU0_RSVD_35"
				( objectStatus "@baseboard_fab2_lib.baseboard_fab2(sch_1):tp_cpu0_rsvd_35" )
			)
			( signal "TP_CPU0_RSVD_36"
				( objectStatus "@baseboard_fab2_lib.baseboard_fab2(sch_1):tp_cpu0_rsvd_36" )
			)
			( signal "TP_CPU0_RSVD_37"
				( objectStatus "@baseboard_fab2_lib.baseboard_fab2(sch_1):tp_cpu0_rsvd_37" )
			)
			( signal "TP_CPU0_RSVD_38"
				( objectStatus "@baseboard_fab2_lib.baseboard_fab2(sch_1):tp_cpu0_rsvd_38" )
			)
			( signal "TP_CPU0_RSVD_39"
				( objectStatus "@baseboard_fab2_lib.baseboard_fab2(sch_1):tp_cpu0_rsvd_39" )
			)
			( signal "TP_CPU0_RSVD_4"
				( objectStatus "@baseboard_fab2_lib.baseboard_fab2(sch_1):tp_cpu0_rsvd_4" )
			)
			( signal "TP_CPU0_RSVD_40"
				( objectStatus "@baseboard_fab2_lib.baseboard_fab2(sch_1):tp_cpu0_rsvd_40" )
			)
			( signal "TP_CPU0_RSVD_41"
				( objectStatus "@baseboard_fab2_lib.baseboard_fab2(sch_1):tp_cpu0_rsvd_41" )
			)
			( signal "TP_CPU0_RSVD_42"
				( objectStatus "@baseboard_fab2_lib.baseboard_fab2(sch_1):tp_cpu0_rsvd_42" )
			)
			( signal "TP_CPU0_RSVD_43"
				( objectStatus "@baseboard_fab2_lib.baseboard_fab2(sch_1):tp_cpu0_rsvd_43" )
			)
			( signal "TP_CPU0_RSVD_44"
				( objectStatus "@baseboard_fab2_lib.baseboard_fab2(sch_1):tp_cpu0_rsvd_44" )
			)
			( signal "TP_CPU0_RSVD_45"
				( objectStatus "@baseboard_fab2_lib.baseboard_fab2(sch_1):tp_cpu0_rsvd_45" )
			)
			( signal "TP_CPU0_RSVD_46"
				( objectStatus "@baseboard_fab2_lib.baseboard_fab2(sch_1):tp_cpu0_rsvd_46" )
			)
			( signal "TP_CPU0_RSVD_47"
				( objectStatus "@baseboard_fab2_lib.baseboard_fab2(sch_1):tp_cpu0_rsvd_47" )
			)
			( signal "TP_CPU0_RSVD_48"
				( objectStatus "@baseboard_fab2_lib.baseboard_fab2(sch_1):tp_cpu0_rsvd_48" )
			)
			( signal "TP_CPU0_RSVD_49"
				( objectStatus "@baseboard_fab2_lib.baseboard_fab2(sch_1):tp_cpu0_rsvd_49" )
			)
			( signal "TP_CPU0_RSVD_5"
				( objectStatus "@baseboard_fab2_lib.baseboard_fab2(sch_1):tp_cpu0_rsvd_5" )
			)
			( signal "TP_CPU0_RSVD_50"
				( objectStatus "@baseboard_fab2_lib.baseboard_fab2(sch_1):tp_cpu0_rsvd_50" )
			)
			( signal "TP_CPU0_RSVD_51"
				( objectStatus "@baseboard_fab2_lib.baseboard_fab2(sch_1):tp_cpu0_rsvd_51" )
			)
			( signal "TP_CPU0_RSVD_53"
				( objectStatus "@baseboard_fab2_lib.baseboard_fab2(sch_1):tp_cpu0_rsvd_53" )
			)
			( signal "TP_CPU0_RSVD_54"
				( objectStatus "@baseboard_fab2_lib.baseboard_fab2(sch_1):tp_cpu0_rsvd_54" )
			)
			( signal "TP_CPU0_RSVD_55"
				( objectStatus "@baseboard_fab2_lib.baseboard_fab2(sch_1):tp_cpu0_rsvd_55" )
			)
			( signal "TP_CPU0_RSVD_56"
				( objectStatus "@baseboard_fab2_lib.baseboard_fab2(sch_1):tp_cpu0_rsvd_56" )
			)
			( signal "TP_CPU0_RSVD_57"
				( objectStatus "@baseboard_fab2_lib.baseboard_fab2(sch_1):tp_cpu0_rsvd_57" )
			)
			( signal "TP_CPU0_RSVD_59"
				( objectStatus "@baseboard_fab2_lib.baseboard_fab2(sch_1):tp_cpu0_rsvd_59" )
			)
			( signal "TP_CPU0_RSVD_6"
				( objectStatus "@baseboard_fab2_lib.baseboard_fab2(sch_1):tp_cpu0_rsvd_6" )
			)
			( signal "TP_CPU0_RSVD_60"
				( objectStatus "@baseboard_fab2_lib.baseboard_fab2(sch_1):tp_cpu0_rsvd_60" )
			)
			( signal "TP_CPU0_RSVD_61"
				( objectStatus "@baseboard_fab2_lib.baseboard_fab2(sch_1):tp_cpu0_rsvd_61" )
			)
			( signal "TP_CPU0_RSVD_64"
				( objectStatus "@baseboard_fab2_lib.baseboard_fab2(sch_1):tp_cpu0_rsvd_64" )
			)
			( signal "TP_CPU0_RSVD_66"
				( objectStatus "@baseboard_fab2_lib.baseboard_fab2(sch_1):tp_cpu0_rsvd_66" )
			)
			( signal "TP_CPU0_RSVD_67"
				( objectStatus "@baseboard_fab2_lib.baseboard_fab2(sch_1):tp_cpu0_rsvd_67" )
			)
			( signal "TP_CPU0_RSVD_69"
				( objectStatus "@baseboard_fab2_lib.baseboard_fab2(sch_1):tp_cpu0_rsvd_69" )
			)
			( signal "TP_CPU0_RSVD_7"
				( objectStatus "@baseboard_fab2_lib.baseboard_fab2(sch_1):tp_cpu0_rsvd_7" )
			)
			( signal "TP_CPU0_RSVD_70"
				( objectStatus "@baseboard_fab2_lib.baseboard_fab2(sch_1):tp_cpu0_rsvd_70" )
			)
			( signal "TP_CPU0_RSVD_72"
				( objectStatus "@baseboard_fab2_lib.baseboard_fab2(sch_1):tp_cpu0_rsvd_72" )
			)
			( signal "TP_CPU0_RSVD_73"
				( objectStatus "@baseboard_fab2_lib.baseboard_fab2(sch_1):tp_cpu0_rsvd_73" )
			)
			( signal "TP_CPU0_RSVD_8"
				( objectStatus "@baseboard_fab2_lib.baseboard_fab2(sch_1):tp_cpu0_rsvd_8" )
			)
			( signal "TP_CPU0_RSVD_9"
				( objectStatus "@baseboard_fab2_lib.baseboard_fab2(sch_1):tp_cpu0_rsvd_9" )
			)
			( signal "VSENSE_PVCCIO_CPU0_SKT_VRTN"
				( attribute "VOLTAGE" "0.3"
					( Units "uVoltage" "V" 1.000000)
					( Status sAliasFlattened )
					( Origin gFrontEnd )
				)
				( objectStatus "@baseboard_fab2_lib.baseboard_fab2(sch_1):vsense_pvccio_cpu0_skt_vrtn" )
			)
			( signal "VSENSE_PVCCIO_CPU0_SKT_VSEN"
				( attribute "VOLTAGE" "2"
					( Units "uVoltage" "V" 1.000000)
					( Status sAliasFlattened )
					( Origin gFrontEnd )
				)
				( objectStatus "@baseboard_fab2_lib.baseboard_fab2(sch_1):vsense_pvccio_cpu0_skt_vsen" )
			)
			( signal "VSENSE_PVCCIOMCP_CPU0_SKT_VRTN"
				( objectStatus "@baseboard_fab2_lib.baseboard_fab2(sch_1):vsense_pvcciomcp_cpu0_skt_vrtn" )
			)
			( signal "VSENSE_PVCCIOMCP_CPU0_SKT_VSEN"
				( objectStatus "@baseboard_fab2_lib.baseboard_fab2(sch_1):vsense_pvcciomcp_cpu0_skt_vsen" )
			)
			( signal "VSENSE_PVCCMCP_CPU0_SKT_VRTN"
				( objectStatus "@baseboard_fab2_lib.baseboard_fab2(sch_1):vsense_pvccmcp_cpu0_skt_vrtn" )
			)
			( signal "VSENSE_PVCCMCP_CPU0_SKT_VSEN"
				( objectStatus "@baseboard_fab2_lib.baseboard_fab2(sch_1):vsense_pvccmcp_cpu0_skt_vsen" )
			)
			( signal "VSENSE_PVSA_CPU0_SKT_VRTN"
				( attribute "VOLTAGE" "0.3"
					( Units "uVoltage" "V" 1.000000)
					( Status sAliasFlattened )
					( Origin gFrontEnd )
				)
				( objectStatus "@baseboard_fab2_lib.baseboard_fab2(sch_1):vsense_pvsa_cpu0_skt_vrtn" )
			)
			( signal "VSENSE_PVSA_CPU0_SKT_VSEN"
				( attribute "VOLTAGE" "1.0"
					( Units "uVoltage" "V" 1.000000)
					( Status sAliasFlattened )
					( Origin gFrontEnd )
				)
				( objectStatus "@baseboard_fab2_lib.baseboard_fab2(sch_1):vsense_pvsa_cpu0_skt_vsen" )
			)
			( signal "FM_ADR_COMPLETE_ABC_N"
				( objectStatus "@baseboard_fab2_lib.baseboard_fab2(sch_1):fm_adr_complete_abc_n" )
			)
			( signal "FM_DIMM_EVENT_COD_N"
				( objectStatus "@baseboard_fab2_lib.baseboard_fab2(sch_1):fm_dimm_event_cod_n" )
			)
			( signal "M_A_VREF"
				( objectStatus "@baseboard_fab2_lib.baseboard_fab2(sch_1):m_a_vref" )
			)
			( signal "P12V_NVDIMM_ABC"
				( attribute "VOLTAGE" "12.0"
					( Units "uVoltage" "V" 1.000000)
					( Status sAliasFlattened )
					( Origin gFrontEnd )
				)
				( objectStatus "@baseboard_fab2_lib.baseboard_fab2(sch_1):p12v_nvdimm_abc" )
			)
			( signal "PVTT_ABC"
				( attribute "VOLTAGE" "0.6V"
					( Units "uVoltage" "V" 1.000000)
					( Status sAliasFlattened )
					( Origin gFrontEnd )
				)
				( objectStatus "@baseboard_fab2_lib.baseboard_fab2(sch_1):pvtt_abc" )
			)
			( signal "SMB_DDR_ABC_VPP_SCL"
				( objectStatus "@baseboard_fab2_lib.baseboard_fab2(sch_1):smb_ddr_abc_vpp_scl" )
			)
			( signal "SMB_DDR_ABC_VPP_SDA"
				( objectStatus "@baseboard_fab2_lib.baseboard_fab2(sch_1):smb_ddr_abc_vpp_sda" )
			)
			( signal "TP_CH_A_DIMM_A0_RFU_0"
				( objectStatus "@baseboard_fab2_lib.baseboard_fab2(sch_1):tp_ch_a_dimm_a0_rfu_0" )
			)
			( signal "TP_CH_A_DIMM_A0_RFU_1"
				( objectStatus "@baseboard_fab2_lib.baseboard_fab2(sch_1):tp_ch_a_dimm_a0_rfu_1" )
			)
			( signal "TP_CH_A_DIMM_A0_RFU_2"
				( objectStatus "@baseboard_fab2_lib.baseboard_fab2(sch_1):tp_ch_a_dimm_a0_rfu_2" )
			)
			( signal "TP_CH_A_DIMM_A1_RFU_0"
				( objectStatus "@baseboard_fab2_lib.baseboard_fab2(sch_1):tp_ch_a_dimm_a1_rfu_0" )
			)
			( signal "TP_CH_A_DIMM_A1_RFU_1"
				( objectStatus "@baseboard_fab2_lib.baseboard_fab2(sch_1):tp_ch_a_dimm_a1_rfu_1" )
			)
			( signal "TP_CH_A_DIMM_A1_RFU_2"
				( objectStatus "@baseboard_fab2_lib.baseboard_fab2(sch_1):tp_ch_a_dimm_a1_rfu_2" )
			)
			( signal "M_B_VREF"
				( objectStatus "@baseboard_fab2_lib.baseboard_fab2(sch_1):m_b_vref" )
			)
			( signal "TP_CH_B_DIMM_B0_RFU_0"
				( objectStatus "@baseboard_fab2_lib.baseboard_fab2(sch_1):tp_ch_b_dimm_b0_rfu_0" )
			)
			( signal "TP_CH_B_DIMM_B0_RFU_1"
				( objectStatus "@baseboard_fab2_lib.baseboard_fab2(sch_1):tp_ch_b_dimm_b0_rfu_1" )
			)
			( signal "TP_CH_B_DIMM_B0_RFU_2"
				( objectStatus "@baseboard_fab2_lib.baseboard_fab2(sch_1):tp_ch_b_dimm_b0_rfu_2" )
			)
			( signal "TP_CH_B_DIMM_B1_RFU_0"
				( objectStatus "@baseboard_fab2_lib.baseboard_fab2(sch_1):tp_ch_b_dimm_b1_rfu_0" )
			)
			( signal "TP_CH_B_DIMM_B1_RFU_1"
				( objectStatus "@baseboard_fab2_lib.baseboard_fab2(sch_1):tp_ch_b_dimm_b1_rfu_1" )
			)
			( signal "TP_CH_B_DIMM_B1_RFU_2"
				( objectStatus "@baseboard_fab2_lib.baseboard_fab2(sch_1):tp_ch_b_dimm_b1_rfu_2" )
			)
			( signal "M_C_VREF"
				( objectStatus "@baseboard_fab2_lib.baseboard_fab2(sch_1):m_c_vref" )
			)
			( signal "TP_CH_C_DIMM_C0_RFU_0"
				( objectStatus "@baseboard_fab2_lib.baseboard_fab2(sch_1):tp_ch_c_dimm_c0_rfu_0" )
			)
			( signal "TP_CH_C_DIMM_C0_RFU_1"
				( objectStatus "@baseboard_fab2_lib.baseboard_fab2(sch_1):tp_ch_c_dimm_c0_rfu_1" )
			)
			( signal "TP_CH_C_DIMM_C0_RFU_2"
				( objectStatus "@baseboard_fab2_lib.baseboard_fab2(sch_1):tp_ch_c_dimm_c0_rfu_2" )
			)
			( signal "TP_CH_C_DIMM_C1_RFU_0"
				( objectStatus "@baseboard_fab2_lib.baseboard_fab2(sch_1):tp_ch_c_dimm_c1_rfu_0" )
			)
			( signal "TP_CH_C_DIMM_C1_RFU_1"
				( objectStatus "@baseboard_fab2_lib.baseboard_fab2(sch_1):tp_ch_c_dimm_c1_rfu_1" )
			)
			( signal "TP_CH_C_DIMM_C1_RFU_2"
				( objectStatus "@baseboard_fab2_lib.baseboard_fab2(sch_1):tp_ch_c_dimm_c1_rfu_2" )
			)
			( signal "FM_ADR_COMPLETE_DEF_N"
				( objectStatus "@baseboard_fab2_lib.baseboard_fab2(sch_1):fm_adr_complete_def_n" )
			)
			( signal "M_D_VREF"
				( objectStatus "@baseboard_fab2_lib.baseboard_fab2(sch_1):m_d_vref" )
			)
			( signal "P12V_NVDIMM_DEF"
				( attribute "VOLTAGE" "12.0"
					( Units "uVoltage" "V" 1.000000)
					( Status sAliasFlattened )
					( Origin gFrontEnd )
				)
				( objectStatus "@baseboard_fab2_lib.baseboard_fab2(sch_1):p12v_nvdimm_def" )
			)
			( signal "PVPP_DEF"
				( attribute "VOLTAGE" "2.5V"
					( Units "uVoltage" "V" 1.000000)
					( Status sAliasFlattened )
					( Origin gFrontEnd )
				)
				( objectStatus "@baseboard_fab2_lib.baseboard_fab2(sch_1):pvpp_def" )
			)
			( signal "PVTT_DEF"
				( attribute "VOLTAGE" "0.6V"
					( Units "uVoltage" "V" 1.000000)
					( Status sAliasFlattened )
					( Origin gFrontEnd )
				)
				( objectStatus "@baseboard_fab2_lib.baseboard_fab2(sch_1):pvtt_def" )
			)
			( signal "SMB_DDR_DEF_VPP_SCL"
				( objectStatus "@baseboard_fab2_lib.baseboard_fab2(sch_1):smb_ddr_def_vpp_scl" )
			)
			( signal "SMB_DDR_DEF_VPP_SDA"
				( objectStatus "@baseboard_fab2_lib.baseboard_fab2(sch_1):smb_ddr_def_vpp_sda" )
			)
			( signal "TP_CH_D_DIMM_D0_RFU_0"
				( objectStatus "@baseboard_fab2_lib.baseboard_fab2(sch_1):tp_ch_d_dimm_d0_rfu_0" )
			)
			( signal "TP_CH_D_DIMM_D0_RFU_1"
				( objectStatus "@baseboard_fab2_lib.baseboard_fab2(sch_1):tp_ch_d_dimm_d0_rfu_1" )
			)
			( signal "TP_CH_D_DIMM_D0_RFU_2"
				( objectStatus "@baseboard_fab2_lib.baseboard_fab2(sch_1):tp_ch_d_dimm_d0_rfu_2" )
			)
			( signal "TP_CH_D_DIMM_D1_RFU_0"
				( objectStatus "@baseboard_fab2_lib.baseboard_fab2(sch_1):tp_ch_d_dimm_d1_rfu_0" )
			)
			( signal "TP_CH_D_DIMM_D1_RFU_1"
				( objectStatus "@baseboard_fab2_lib.baseboard_fab2(sch_1):tp_ch_d_dimm_d1_rfu_1" )
			)
			( signal "TP_CH_D_DIMM_D1_RFU_2"
				( objectStatus "@baseboard_fab2_lib.baseboard_fab2(sch_1):tp_ch_d_dimm_d1_rfu_2" )
			)
			( signal "M_E_VREF"
				( objectStatus "@baseboard_fab2_lib.baseboard_fab2(sch_1):m_e_vref" )
			)
			( signal "TP_CH_E_DIMM_E0_RFU_0"
				( objectStatus "@baseboard_fab2_lib.baseboard_fab2(sch_1):tp_ch_e_dimm_e0_rfu_0" )
			)
			( signal "TP_CH_E_DIMM_E0_RFU_1"
				( objectStatus "@baseboard_fab2_lib.baseboard_fab2(sch_1):tp_ch_e_dimm_e0_rfu_1" )
			)
			( signal "TP_CH_E_DIMM_E0_RFU_2"
				( objectStatus "@baseboard_fab2_lib.baseboard_fab2(sch_1):tp_ch_e_dimm_e0_rfu_2" )
			)
			( signal "TP_CH_E_DIMM_E1_RFU_0"
				( objectStatus "@baseboard_fab2_lib.baseboard_fab2(sch_1):tp_ch_e_dimm_e1_rfu_0" )
			)
			( signal "TP_CH_E_DIMM_E1_RFU_1"
				( objectStatus "@baseboard_fab2_lib.baseboard_fab2(sch_1):tp_ch_e_dimm_e1_rfu_1" )
			)
			( signal "TP_CH_E_DIMM_E1_RFU_2"
				( objectStatus "@baseboard_fab2_lib.baseboard_fab2(sch_1):tp_ch_e_dimm_e1_rfu_2" )
			)
			( signal "M_F_VREF"
				( objectStatus "@baseboard_fab2_lib.baseboard_fab2(sch_1):m_f_vref" )
			)
			( signal "TP_CH_F_DIMM_F0_RFU_0"
				( objectStatus "@baseboard_fab2_lib.baseboard_fab2(sch_1):tp_ch_f_dimm_f0_rfu_0" )
			)
			( signal "TP_CH_F_DIMM_F0_RFU_1"
				( objectStatus "@baseboard_fab2_lib.baseboard_fab2(sch_1):tp_ch_f_dimm_f0_rfu_1" )
			)
			( signal "TP_CH_F_DIMM_F0_RFU_2"
				( objectStatus "@baseboard_fab2_lib.baseboard_fab2(sch_1):tp_ch_f_dimm_f0_rfu_2" )
			)
			( signal "TP_CH_F_DIMM_F1_RFU_0"
				( objectStatus "@baseboard_fab2_lib.baseboard_fab2(sch_1):tp_ch_f_dimm_f1_rfu_0" )
			)
			( signal "TP_CH_F_DIMM_F1_RFU_1"
				( objectStatus "@baseboard_fab2_lib.baseboard_fab2(sch_1):tp_ch_f_dimm_f1_rfu_1" )
			)
			( signal "TP_CH_F_DIMM_F1_RFU_2"
				( objectStatus "@baseboard_fab2_lib.baseboard_fab2(sch_1):tp_ch_f_dimm_f1_rfu_2" )
			)
			( signal "A_CPU1_GHJ_RCOMP0"
				( objectStatus "@baseboard_fab2_lib.baseboard_fab2(sch_1):a_cpu1_ghj_rcomp0" )
			)
			( signal "A_CPU1_GHJ_RCOMP1"
				( objectStatus "@baseboard_fab2_lib.baseboard_fab2(sch_1):a_cpu1_ghj_rcomp1" )
			)
			( signal "A_CPU1_GHJ_RCOMP2"
				( objectStatus "@baseboard_fab2_lib.baseboard_fab2(sch_1):a_cpu1_ghj_rcomp2" )
			)
			( signal "A_CPU1_KLM_RCOMP0"
				( objectStatus "@baseboard_fab2_lib.baseboard_fab2(sch_1):a_cpu1_klm_rcomp0" )
			)
			( signal "A_CPU1_KLM_RCOMP1"
				( objectStatus "@baseboard_fab2_lib.baseboard_fab2(sch_1):a_cpu1_klm_rcomp1" )
			)
			( signal "A_CPU1_KLM_RCOMP2"
				( objectStatus "@baseboard_fab2_lib.baseboard_fab2(sch_1):a_cpu1_klm_rcomp2" )
			)
			( signal "A_CPU1_MCP01_RBIAS"
				( objectStatus "@baseboard_fab2_lib.baseboard_fab2(sch_1):a_cpu1_mcp01_rbias" )
			)
			( signal "A_CPU1_PE012_RBIAS"
				( objectStatus "@baseboard_fab2_lib.baseboard_fab2(sch_1):a_cpu1_pe012_rbias" )
			)
			( signal "A_CPU1_PE3_RBIAS"
				( objectStatus "@baseboard_fab2_lib.baseboard_fab2(sch_1):a_cpu1_pe3_rbias" )
			)
			( signal "A_CPU1_UPI01_RBIAS"
				( objectStatus "@baseboard_fab2_lib.baseboard_fab2(sch_1):a_cpu1_upi01_rbias" )
			)
			( signal "A_CPU1_UPI2_RBIAS"
				( objectStatus "@baseboard_fab2_lib.baseboard_fab2(sch_1):a_cpu1_upi2_rbias" )
			)
			( signal "CLK_100M_CPU1_BCLK0_DN"
				( objectStatus "@baseboard_fab2_lib.baseboard_fab2(sch_1):clk_100m_cpu1_bclk0_dn" )
			)
			( signal "CLK_100M_CPU1_BCLK0_DP"
				( objectStatus "@baseboard_fab2_lib.baseboard_fab2(sch_1):clk_100m_cpu1_bclk0_dp" )
			)
			( signal "CLK_100M_CPU1_BCLK1_DN"
				( objectStatus "@baseboard_fab2_lib.baseboard_fab2(sch_1):clk_100m_cpu1_bclk1_dn" )
			)
			( signal "CLK_100M_CPU1_BCLK1_DP"
				( objectStatus "@baseboard_fab2_lib.baseboard_fab2(sch_1):clk_100m_cpu1_bclk1_dp" )
			)
			( signal "CLK_100M_CPU1_BCLK2_DN"
				( objectStatus "@baseboard_fab2_lib.baseboard_fab2(sch_1):clk_100m_cpu1_bclk2_dn" )
			)
			( signal "CLK_100M_CPU1_BCLK2_DP"
				( objectStatus "@baseboard_fab2_lib.baseboard_fab2(sch_1):clk_100m_cpu1_bclk2_dp" )
			)
			( signal "FM_CPU1_PKGID0"
				( objectStatus "@baseboard_fab2_lib.baseboard_fab2(sch_1):fm_cpu1_pkgid0" )
			)
			( signal "FM_CPU1_PKGID1"
				( objectStatus "@baseboard_fab2_lib.baseboard_fab2(sch_1):fm_cpu1_pkgid1" )
			)
			( signal "FM_CPU1_PKGID2"
				( objectStatus "@baseboard_fab2_lib.baseboard_fab2(sch_1):fm_cpu1_pkgid2" )
			)
			( signal "FM_CPU1_PROC_ID0"
				( objectStatus "@baseboard_fab2_lib.baseboard_fab2(sch_1):fm_cpu1_proc_id0" )
			)
			( signal "FM_CPU1_PROC_ID1"
				( objectStatus "@baseboard_fab2_lib.baseboard_fab2(sch_1):fm_cpu1_proc_id1" )
			)
			( signal "FM_CPU1_SKTOCC_LVT3_N"
				( objectStatus "@baseboard_fab2_lib.baseboard_fab2(sch_1):fm_cpu1_sktocc_lvt3_n" )
			)
			( signal "FM_CPU1_SM_WP"
				( objectStatus "@baseboard_fab2_lib.baseboard_fab2(sch_1):fm_cpu1_sm_wp" )
			)
			( signal "H_CPU1_BMCINIT"
				( objectStatus "@baseboard_fab2_lib.baseboard_fab2(sch_1):h_cpu1_bmcinit" )
			)
			( signal "H_CPU1_CATERR_G_N"
				( objectStatus "@baseboard_fab2_lib.baseboard_fab2(sch_1):h_cpu1_caterr_g_n" )
			)
			( signal "H_CPU1_ERR0_G_N"
				( objectStatus "@baseboard_fab2_lib.baseboard_fab2(sch_1):h_cpu1_err0_g_n" )
			)
			( signal "H_CPU1_ERR1_G_N"
				( objectStatus "@baseboard_fab2_lib.baseboard_fab2(sch_1):h_cpu1_err1_g_n" )
			)
			( signal "H_CPU1_ERR2_G_N"
				( objectStatus "@baseboard_fab2_lib.baseboard_fab2(sch_1):h_cpu1_err2_g_n" )
			)
			( signal "H_CPU1_FAST_WAKE_N"
				( objectStatus "@baseboard_fab2_lib.baseboard_fab2(sch_1):h_cpu1_fast_wake_n" )
			)
			( signal "H_CPU1_MEMGHJ_MEMHOT_G_N"
				( objectStatus "@baseboard_fab2_lib.baseboard_fab2(sch_1):h_cpu1_memghj_memhot_g_n" )
			)
			( signal "H_CPU1_MEMKLM_MEMHOT_G_N"
				( objectStatus "@baseboard_fab2_lib.baseboard_fab2(sch_1):h_cpu1_memklm_memhot_g_n" )
			)
			( signal "H_CPU1_MSMI_G_N"
				( objectStatus "@baseboard_fab2_lib.baseboard_fab2(sch_1):h_cpu1_msmi_g_n" )
			)
			( signal "H_CPU1_PROCHOT_G_N"
				( objectStatus "@baseboard_fab2_lib.baseboard_fab2(sch_1):h_cpu1_prochot_g_n" )
			)
			( signal "H_CPU1_THERMTRIP_G_N"
				( objectStatus "@baseboard_fab2_lib.baseboard_fab2(sch_1):h_cpu1_thermtrip_g_n" )
			)
			( signal "H_PM_SYNC_GTL_R2"
				( objectStatus "@baseboard_fab2_lib.baseboard_fab2(sch_1):h_pm_sync_gtl_r2" )
			)
			( signal "H_PMSYNC_CLK_24M_CPU1"
				( objectStatus "@baseboard_fab2_lib.baseboard_fab2(sch_1):h_pmsync_clk_24m_cpu1" )
			)
			( signal "M_G_CPU_VREF"
				( objectStatus "@baseboard_fab2_lib.baseboard_fab2(sch_1):m_g_cpu_vref" )
			)
			( signal "M_GHJ_RST_N"
				( objectStatus "@baseboard_fab2_lib.baseboard_fab2(sch_1):m_ghj_rst_n" )
			)
			( signal "M_H_CPU_VREF"
				( objectStatus "@baseboard_fab2_lib.baseboard_fab2(sch_1):m_h_cpu_vref" )
			)
			( signal "M_J_CPU_VREF"
				( objectStatus "@baseboard_fab2_lib.baseboard_fab2(sch_1):m_j_cpu_vref" )
			)
			( signal "M_K_CPU_VREF"
				( objectStatus "@baseboard_fab2_lib.baseboard_fab2(sch_1):m_k_cpu_vref" )
			)
			( signal "M_KLM_RST_N"
				( objectStatus "@baseboard_fab2_lib.baseboard_fab2(sch_1):m_klm_rst_n" )
			)
			( signal "M_L_CPU_VREF"
				( objectStatus "@baseboard_fab2_lib.baseboard_fab2(sch_1):m_l_cpu_vref" )
			)
			( signal "M_M_CPU_VREF"
				( objectStatus "@baseboard_fab2_lib.baseboard_fab2(sch_1):m_m_cpu_vref" )
			)
			( signal "PD_CPU1_BIST_ENABLE"
				( objectStatus "@baseboard_fab2_lib.baseboard_fab2(sch_1):pd_cpu1_bist_enable" )
			)
			( signal "PD_CPU1_KSFC_DIS"
				( objectStatus "@baseboard_fab2_lib.baseboard_fab2(sch_1):pd_cpu1_ksfc_dis" )
			)
			( signal "PD_CPU1_TEST12"
				( objectStatus "@baseboard_fab2_lib.baseboard_fab2(sch_1):pd_cpu1_test12" )
			)
			( signal "PD_CPU1_TEST13"
				( objectStatus "@baseboard_fab2_lib.baseboard_fab2(sch_1):pd_cpu1_test13" )
			)
			( signal "PD_CPU1_TEST14"
				( objectStatus "@baseboard_fab2_lib.baseboard_fab2(sch_1):pd_cpu1_test14" )
			)
			( signal "PD_CPU1_TXT_PLTEN"
				( objectStatus "@baseboard_fab2_lib.baseboard_fab2(sch_1):pd_cpu1_txt_plten" )
			)
			( signal "PD_PIROM_CPU1_ADDR1"
				( objectStatus "@baseboard_fab2_lib.baseboard_fab2(sch_1):pd_pirom_cpu1_addr1" )
			)
			( signal "PD_PIROM_CPU1_ADDR2"
				( objectStatus "@baseboard_fab2_lib.baseboard_fab2(sch_1):pd_pirom_cpu1_addr2" )
			)
			( signal "PU_CPU1_EAR_N"
				( objectStatus "@baseboard_fab2_lib.baseboard_fab2(sch_1):pu_cpu1_ear_n" )
			)
			( signal "PU_CPU1_FRMAGENT"
				( objectStatus "@baseboard_fab2_lib.baseboard_fab2(sch_1):pu_cpu1_frmagent" )
			)
			( signal "PU_CPU1_LEGACY_SKT"
				( objectStatus "@baseboard_fab2_lib.baseboard_fab2(sch_1):pu_cpu1_legacy_skt" )
			)
			( signal "PU_CPU1_SAFE_MODE_BOOT"
				( objectStatus "@baseboard_fab2_lib.baseboard_fab2(sch_1):pu_cpu1_safe_mode_boot" )
			)
			( signal "PU_CPU1_SOCKET_ID_0"
				( objectStatus "@baseboard_fab2_lib.baseboard_fab2(sch_1):pu_cpu1_socket_id_0" )
			)
			( signal "PU_CPU1_SOCKET_ID_1"
				( objectStatus "@baseboard_fab2_lib.baseboard_fab2(sch_1):pu_cpu1_socket_id_1" )
			)
			( signal "PU_CPU1_TSC_SYNC"
				( objectStatus "@baseboard_fab2_lib.baseboard_fab2(sch_1):pu_cpu1_tsc_sync" )
			)
			( signal "PU_CPU1_TXT_AGENT"
				( objectStatus "@baseboard_fab2_lib.baseboard_fab2(sch_1):pu_cpu1_txt_agent" )
			)
			( signal "PU_PIROM_CPU1_ADDR0"
				( objectStatus "@baseboard_fab2_lib.baseboard_fab2(sch_1):pu_pirom_cpu1_addr0" )
			)
			( signal "PVCCIO_CPU1"
				( attribute "VOLTAGE" "1.1V"
					( Units "uVoltage" "V" 1.000000)
					( Status sAliasFlattened )
					( Origin gFrontEnd )
				)
				( objectStatus "@baseboard_fab2_lib.baseboard_fab2(sch_1):pvccio_cpu1" )
			)
			( signal "PWRGD_CPU1_DRAMPWROK_GHJ_G"
				( objectStatus "@baseboard_fab2_lib.baseboard_fab2(sch_1):pwrgd_cpu1_drampwrok_ghj_g" )
			)
			( signal "PWRGD_CPU1_DRAMPWROK_KLM_G"
				( objectStatus "@baseboard_fab2_lib.baseboard_fab2(sch_1):pwrgd_cpu1_drampwrok_klm_g" )
			)
			( signal "PWRGD_CPU1_G"
				( objectStatus "@baseboard_fab2_lib.baseboard_fab2(sch_1):pwrgd_cpu1_g" )
			)
			( signal "RST_CPU1_G_N"
				( objectStatus "@baseboard_fab2_lib.baseboard_fab2(sch_1):rst_cpu1_g_n" )
			)
			( signal "SMB_CPU1_PE_HP_GTL_SCL"
				( objectStatus "@baseboard_fab2_lib.baseboard_fab2(sch_1):smb_cpu1_pe_hp_gtl_scl" )
			)
			( signal "SMB_CPU1_PE_HP_GTL_SDA"
				( objectStatus "@baseboard_fab2_lib.baseboard_fab2(sch_1):smb_cpu1_pe_hp_gtl_sda" )
			)
			( signal "SMB_DDR_GHJ_SCL_G_R"
				( objectStatus "@baseboard_fab2_lib.baseboard_fab2(sch_1):smb_ddr_ghj_scl_g_r" )
			)
			( signal "SMB_DDR_GHJ_SDA_G_R"
				( objectStatus "@baseboard_fab2_lib.baseboard_fab2(sch_1):smb_ddr_ghj_sda_g_r" )
			)
			( signal "SMB_DDR_KLM_SCL_G_R"
				( objectStatus "@baseboard_fab2_lib.baseboard_fab2(sch_1):smb_ddr_klm_scl_g_r" )
			)
			( signal "SMB_DDR_KLM_SDA_G_R"
				( objectStatus "@baseboard_fab2_lib.baseboard_fab2(sch_1):smb_ddr_klm_sda_g_r" )
			)
			( signal "SMB_PIROM_CPU1_SCL"
				( objectStatus "@baseboard_fab2_lib.baseboard_fab2(sch_1):smb_pirom_cpu1_scl" )
			)
			( signal "SMB_PIROM_CPU1_SDA"
				( objectStatus "@baseboard_fab2_lib.baseboard_fab2(sch_1):smb_pirom_cpu1_sda" )
			)
			( signal "SVID_ALERT0_CPU1_N"
				( objectStatus "@baseboard_fab2_lib.baseboard_fab2(sch_1):svid_alert0_cpu1_n" )
			)
			( signal "SVID_ALERT0_CPU1_R_N"
				( objectStatus "@baseboard_fab2_lib.baseboard_fab2(sch_1):svid_alert0_cpu1_r_n" )
			)
			( signal "SVID_ALERT1_CPU1_N"
				( objectStatus "@baseboard_fab2_lib.baseboard_fab2(sch_1):svid_alert1_cpu1_n" )
			)
			( signal "SVID_ALERT1_CPU1_R_N"
				( objectStatus "@baseboard_fab2_lib.baseboard_fab2(sch_1):svid_alert1_cpu1_r_n" )
			)
			( signal "SVID_CLK0_CPU1"
				( objectStatus "@baseboard_fab2_lib.baseboard_fab2(sch_1):svid_clk0_cpu1" )
			)
			( signal "SVID_CLK0_CPU1_R"
				( objectStatus "@baseboard_fab2_lib.baseboard_fab2(sch_1):svid_clk0_cpu1_r" )
			)
			( signal "SVID_CLK1_CPU1"
				( objectStatus "@baseboard_fab2_lib.baseboard_fab2(sch_1):svid_clk1_cpu1" )
			)
			( signal "SVID_CLK1_CPU1_R"
				( objectStatus "@baseboard_fab2_lib.baseboard_fab2(sch_1):svid_clk1_cpu1_r" )
			)
			( signal "SVID_DIO0_CPU1"
				( objectStatus "@baseboard_fab2_lib.baseboard_fab2(sch_1):svid_dio0_cpu1" )
			)
			( signal "SVID_DIO0_CPU1_R"
				( objectStatus "@baseboard_fab2_lib.baseboard_fab2(sch_1):svid_dio0_cpu1_r" )
			)
			( signal "SVID_DIO1_CPU1"
				( objectStatus "@baseboard_fab2_lib.baseboard_fab2(sch_1):svid_dio1_cpu1" )
			)
			( signal "SVID_DIO1_CPU1_R"
				( objectStatus "@baseboard_fab2_lib.baseboard_fab2(sch_1):svid_dio1_cpu1_r" )
			)
			( signal "TP_CPU1_NMI"
				( objectStatus "@baseboard_fab2_lib.baseboard_fab2(sch_1):tp_cpu1_nmi" )
			)
			( signal "TP_CPU1_PROC_DIS_G_N"
				( objectStatus "@baseboard_fab2_lib.baseboard_fab2(sch_1):tp_cpu1_proc_dis_g_n" )
			)
			( signal "TP_CPU1_SOCKET_ID_2"
				( objectStatus "@baseboard_fab2_lib.baseboard_fab2(sch_1):tp_cpu1_socket_id_2" )
			)
			( signal "TP_XDP_CPU1_OBSDATA_B0_MBP2_N"
				( objectStatus "@baseboard_fab2_lib.baseboard_fab2(sch_1):tp_xdp_cpu1_obsdata_b0_mbp2_n" )
			)
			( signal "TP_XDP_CPU1_OBSDATA_B1_MBP3_N"
				( objectStatus "@baseboard_fab2_lib.baseboard_fab2(sch_1):tp_xdp_cpu1_obsdata_b1_mbp3_n" )
			)
			( signal "TP_XDP_CPU1_OBSDATA_B2_MBP4_N"
				( objectStatus "@baseboard_fab2_lib.baseboard_fab2(sch_1):tp_xdp_cpu1_obsdata_b2_mbp4_n" )
			)
			( signal "TP_XDP_CPU1_OBSDATA_B3_MBP5_N"
				( objectStatus "@baseboard_fab2_lib.baseboard_fab2(sch_1):tp_xdp_cpu1_obsdata_b3_mbp5_n" )
			)
			( signal "XDP_CPU1_TDI"
				( objectStatus "@baseboard_fab2_lib.baseboard_fab2(sch_1):xdp_cpu1_tdi" )
			)
			( signal "XDP_CPU1_TDO"
				( objectStatus "@baseboard_fab2_lib.baseboard_fab2(sch_1):xdp_cpu1_tdo" )
			)
			( signal "CLK_100M_CPU1_RC_REFCLK0_DN"
				( objectStatus "@baseboard_fab2_lib.baseboard_fab2(sch_1):clk_100m_cpu1_rc_refclk0_dn" )
			)
			( signal "CLK_100M_CPU1_RC_REFCLK0_DP"
				( objectStatus "@baseboard_fab2_lib.baseboard_fab2(sch_1):clk_100m_cpu1_rc_refclk0_dp" )
			)
			( signal "CLK_322M_OSC_CPU1_RC_DN"
				( objectStatus "@baseboard_fab2_lib.baseboard_fab2(sch_1):clk_322m_osc_cpu1_rc_dn" )
			)
			( signal "CLK_322M_OSC_CPU1_RC_DP"
				( objectStatus "@baseboard_fab2_lib.baseboard_fab2(sch_1):clk_322m_osc_cpu1_rc_dp" )
			)
			( signal "FM_CPU1_RC_ERROR_N"
				( objectStatus "@baseboard_fab2_lib.baseboard_fab2(sch_1):fm_cpu1_rc_error_n" )
			)
			( signal "H_CPU1_FIVR_FAULT_G"
				( objectStatus "@baseboard_fab2_lib.baseboard_fab2(sch_1):h_cpu1_fivr_fault_g" )
			)
			( signal "P1V8_MCP_CPU1"
				( attribute "VOLTAGE" "1.8"
					( Units "uVoltage" "V" 1.000000)
					( Status sAliasFlattened )
					( Origin gFrontEnd )
				)
				( objectStatus "@baseboard_fab2_lib.baseboard_fab2(sch_1):p1v8_mcp_cpu1" )
			)
			( signal "PD_CPU1_DMIMODE_OVERRIDE"
				( objectStatus "@baseboard_fab2_lib.baseboard_fab2(sch_1):pd_cpu1_dmimode_override" )
			)
			( signal "PD_CPU1_RSVD_TEST_1"
				( objectStatus "@baseboard_fab2_lib.baseboard_fab2(sch_1):pd_cpu1_rsvd_test_1" )
			)
			( signal "PD_CPU1_RSVD_TEST_2"
				( objectStatus "@baseboard_fab2_lib.baseboard_fab2(sch_1):pd_cpu1_rsvd_test_2" )
			)
			( signal "PVCCMCP_CPU1"
				( attribute "VOLTAGE" "+0.95"
					( Units "uVoltage" "V" 1.000000)
					( Status sAliasFlattened )
					( Origin gFrontEnd )
				)
				( objectStatus "@baseboard_fab2_lib.baseboard_fab2(sch_1):pvccmcp_cpu1" )
			)
			( signal "TP_CPU1_RSVD_194"
				( objectStatus "@baseboard_fab2_lib.baseboard_fab2(sch_1):tp_cpu1_rsvd_194" )
			)
			( signal "TP_CPU1_RSVD_198"
				( objectStatus "@baseboard_fab2_lib.baseboard_fab2(sch_1):tp_cpu1_rsvd_198" )
			)
			( signal "TP_CPU1_RSVD_199"
				( objectStatus "@baseboard_fab2_lib.baseboard_fab2(sch_1):tp_cpu1_rsvd_199" )
			)
			( signal "TP_CPU1_RSVD_204"
				( objectStatus "@baseboard_fab2_lib.baseboard_fab2(sch_1):tp_cpu1_rsvd_204" )
			)
			( signal "TP_CPU1_RSVD_205"
				( objectStatus "@baseboard_fab2_lib.baseboard_fab2(sch_1):tp_cpu1_rsvd_205" )
			)
			( signal "TP_CPU1_RSVD_208"
				( objectStatus "@baseboard_fab2_lib.baseboard_fab2(sch_1):tp_cpu1_rsvd_208" )
			)
			( signal "TP_CPU1_RSVD_210"
				( objectStatus "@baseboard_fab2_lib.baseboard_fab2(sch_1):tp_cpu1_rsvd_210" )
			)
			( signal "TP_CPU1_RSVD_211"
				( objectStatus "@baseboard_fab2_lib.baseboard_fab2(sch_1):tp_cpu1_rsvd_211" )
			)
			( signal "TP_CPU1_RSVD_212"
				( objectStatus "@baseboard_fab2_lib.baseboard_fab2(sch_1):tp_cpu1_rsvd_212" )
			)
			( signal "TP_CPU1_RSVD_214"
				( objectStatus "@baseboard_fab2_lib.baseboard_fab2(sch_1):tp_cpu1_rsvd_214" )
			)
			( signal "TP_CPU1_RSVD_216"
				( objectStatus "@baseboard_fab2_lib.baseboard_fab2(sch_1):tp_cpu1_rsvd_216" )
			)
			( signal "TP_CPU1_RSVD_217"
				( objectStatus "@baseboard_fab2_lib.baseboard_fab2(sch_1):tp_cpu1_rsvd_217" )
			)
			( signal "TP_CPU1_RSVD_218"
				( objectStatus "@baseboard_fab2_lib.baseboard_fab2(sch_1):tp_cpu1_rsvd_218" )
			)
			( signal "TP_CPU1_RSVD_219"
				( objectStatus "@baseboard_fab2_lib.baseboard_fab2(sch_1):tp_cpu1_rsvd_219" )
			)
			( signal "TP_CPU1_RSVD_222"
				( objectStatus "@baseboard_fab2_lib.baseboard_fab2(sch_1):tp_cpu1_rsvd_222" )
			)
			( signal "TP_CPU1_RSVD_223"
				( objectStatus "@baseboard_fab2_lib.baseboard_fab2(sch_1):tp_cpu1_rsvd_223" )
			)
			( signal "TP_CPU1_RSVD_224"
				( objectStatus "@baseboard_fab2_lib.baseboard_fab2(sch_1):tp_cpu1_rsvd_224" )
			)
			( signal "TP_CPU1_RSVD_225"
				( objectStatus "@baseboard_fab2_lib.baseboard_fab2(sch_1):tp_cpu1_rsvd_225" )
			)
			( signal "TP_CPU1_RSVD_226"
				( objectStatus "@baseboard_fab2_lib.baseboard_fab2(sch_1):tp_cpu1_rsvd_226" )
			)
			( signal "TP_CPU1_RSVD_227"
				( objectStatus "@baseboard_fab2_lib.baseboard_fab2(sch_1):tp_cpu1_rsvd_227" )
			)
			( signal "TP_CPU1_RSVD_228"
				( objectStatus "@baseboard_fab2_lib.baseboard_fab2(sch_1):tp_cpu1_rsvd_228" )
			)
			( signal "TP_CPU1_RSVD_229"
				( objectStatus "@baseboard_fab2_lib.baseboard_fab2(sch_1):tp_cpu1_rsvd_229" )
			)
			( signal "TP_CPU1_RSVD_230"
				( objectStatus "@baseboard_fab2_lib.baseboard_fab2(sch_1):tp_cpu1_rsvd_230" )
			)
			( signal "TP_CPU1_RSVD_231"
				( objectStatus "@baseboard_fab2_lib.baseboard_fab2(sch_1):tp_cpu1_rsvd_231" )
			)
			( signal "TP_CPU1_RSVD_232"
				( objectStatus "@baseboard_fab2_lib.baseboard_fab2(sch_1):tp_cpu1_rsvd_232" )
			)
			( signal "TP_CPU1_RSVD_233"
				( objectStatus "@baseboard_fab2_lib.baseboard_fab2(sch_1):tp_cpu1_rsvd_233" )
			)
			( signal "TP_CPU1_RSVD_234"
				( objectStatus "@baseboard_fab2_lib.baseboard_fab2(sch_1):tp_cpu1_rsvd_234" )
			)
			( signal "TP_CPU1_RSVD_235"
				( objectStatus "@baseboard_fab2_lib.baseboard_fab2(sch_1):tp_cpu1_rsvd_235" )
			)
			( signal "TP_CPU1_RSVD_236"
				( objectStatus "@baseboard_fab2_lib.baseboard_fab2(sch_1):tp_cpu1_rsvd_236" )
			)
			( signal "TP_CPU1_RSVD_237"
				( objectStatus "@baseboard_fab2_lib.baseboard_fab2(sch_1):tp_cpu1_rsvd_237" )
			)
			( signal "TP_CPU1_RSVD_238"
				( objectStatus "@baseboard_fab2_lib.baseboard_fab2(sch_1):tp_cpu1_rsvd_238" )
			)
			( signal "TP_CPU1_RSVD_239"
				( objectStatus "@baseboard_fab2_lib.baseboard_fab2(sch_1):tp_cpu1_rsvd_239" )
			)
			( signal "TP_CPU1_RSVD_240"
				( objectStatus "@baseboard_fab2_lib.baseboard_fab2(sch_1):tp_cpu1_rsvd_240" )
			)
			( signal "TP_CPU1_RSVD_241"
				( objectStatus "@baseboard_fab2_lib.baseboard_fab2(sch_1):tp_cpu1_rsvd_241" )
			)
			( signal "TP_CPU1_RSVD_242"
				( objectStatus "@baseboard_fab2_lib.baseboard_fab2(sch_1):tp_cpu1_rsvd_242" )
			)
			( signal "TP_CPU1_RSVD_243"
				( objectStatus "@baseboard_fab2_lib.baseboard_fab2(sch_1):tp_cpu1_rsvd_243" )
			)
			( signal "TP_CPU1_RSVD_244"
				( objectStatus "@baseboard_fab2_lib.baseboard_fab2(sch_1):tp_cpu1_rsvd_244" )
			)
			( signal "TP_CPU1_RSVD_245"
				( objectStatus "@baseboard_fab2_lib.baseboard_fab2(sch_1):tp_cpu1_rsvd_245" )
			)
			( signal "TP_CPU1_RSVD_246"
				( objectStatus "@baseboard_fab2_lib.baseboard_fab2(sch_1):tp_cpu1_rsvd_246" )
			)
			( signal "TP_CPU1_RSVD_247"
				( objectStatus "@baseboard_fab2_lib.baseboard_fab2(sch_1):tp_cpu1_rsvd_247" )
			)
			( signal "TP_CPU1_RSVD_248"
				( objectStatus "@baseboard_fab2_lib.baseboard_fab2(sch_1):tp_cpu1_rsvd_248" )
			)
			( signal "TP_CPU1_RSVD_249"
				( objectStatus "@baseboard_fab2_lib.baseboard_fab2(sch_1):tp_cpu1_rsvd_249" )
			)
			( signal "TP_CPU1_RSVD_250"
				( objectStatus "@baseboard_fab2_lib.baseboard_fab2(sch_1):tp_cpu1_rsvd_250" )
			)
			( signal "TP_CPU1_RSVD_251"
				( objectStatus "@baseboard_fab2_lib.baseboard_fab2(sch_1):tp_cpu1_rsvd_251" )
			)
			( signal "TP_CPU1_RSVD_252"
				( objectStatus "@baseboard_fab2_lib.baseboard_fab2(sch_1):tp_cpu1_rsvd_252" )
			)
			( signal "TP_CPU1_RSVD_253"
				( objectStatus "@baseboard_fab2_lib.baseboard_fab2(sch_1):tp_cpu1_rsvd_253" )
			)
			( signal "TP_CPU1_RSVD_254"
				( objectStatus "@baseboard_fab2_lib.baseboard_fab2(sch_1):tp_cpu1_rsvd_254" )
			)
			( signal "TP_CPU1_RSVD_256"
				( objectStatus "@baseboard_fab2_lib.baseboard_fab2(sch_1):tp_cpu1_rsvd_256" )
			)
			( signal "TP_CPU1_RSVD_258"
				( objectStatus "@baseboard_fab2_lib.baseboard_fab2(sch_1):tp_cpu1_rsvd_258" )
			)
			( signal "TP_CPU1_RSVD_259"
				( objectStatus "@baseboard_fab2_lib.baseboard_fab2(sch_1):tp_cpu1_rsvd_259" )
			)
			( signal "TP_CPU1_RSVD_260"
				( objectStatus "@baseboard_fab2_lib.baseboard_fab2(sch_1):tp_cpu1_rsvd_260" )
			)
			( signal "TP_CPU1_RSVD_261"
				( objectStatus "@baseboard_fab2_lib.baseboard_fab2(sch_1):tp_cpu1_rsvd_261" )
			)
			( signal "TP_CPU1_RSVD_262"
				( objectStatus "@baseboard_fab2_lib.baseboard_fab2(sch_1):tp_cpu1_rsvd_262" )
			)
			( signal "TP_CPU1_RSVD_263"
				( objectStatus "@baseboard_fab2_lib.baseboard_fab2(sch_1):tp_cpu1_rsvd_263" )
			)
			( signal "TP_CPU1_RSVD_264"
				( objectStatus "@baseboard_fab2_lib.baseboard_fab2(sch_1):tp_cpu1_rsvd_264" )
			)
			( signal "TP_CPU1_RSVD_265"
				( objectStatus "@baseboard_fab2_lib.baseboard_fab2(sch_1):tp_cpu1_rsvd_265" )
			)
			( signal "TP_CPU1_RSVD_266"
				( objectStatus "@baseboard_fab2_lib.baseboard_fab2(sch_1):tp_cpu1_rsvd_266" )
			)
			( signal "TP_CPU1_RSVD_267"
				( objectStatus "@baseboard_fab2_lib.baseboard_fab2(sch_1):tp_cpu1_rsvd_267" )
			)
			( signal "TP_CPU1_RSVD_268"
				( objectStatus "@baseboard_fab2_lib.baseboard_fab2(sch_1):tp_cpu1_rsvd_268" )
			)
			( signal "TP_CPU1_RSVD_269"
				( objectStatus "@baseboard_fab2_lib.baseboard_fab2(sch_1):tp_cpu1_rsvd_269" )
			)
			( signal "TP_CPU1_RSVD_270"
				( objectStatus "@baseboard_fab2_lib.baseboard_fab2(sch_1):tp_cpu1_rsvd_270" )
			)
			( signal "TP_CPU1_RSVD_271"
				( objectStatus "@baseboard_fab2_lib.baseboard_fab2(sch_1):tp_cpu1_rsvd_271" )
			)
			( signal "TP_CPU1_RSVD_272"
				( objectStatus "@baseboard_fab2_lib.baseboard_fab2(sch_1):tp_cpu1_rsvd_272" )
			)
			( signal "TP_CPU1_RSVD_273"
				( objectStatus "@baseboard_fab2_lib.baseboard_fab2(sch_1):tp_cpu1_rsvd_273" )
			)
			( signal "TP_CPU1_RSVD_274"
				( objectStatus "@baseboard_fab2_lib.baseboard_fab2(sch_1):tp_cpu1_rsvd_274" )
			)
			( signal "TP_CPU1_RSVD_275"
				( objectStatus "@baseboard_fab2_lib.baseboard_fab2(sch_1):tp_cpu1_rsvd_275" )
			)
			( signal "TP_CPU1_RSVD_276"
				( objectStatus "@baseboard_fab2_lib.baseboard_fab2(sch_1):tp_cpu1_rsvd_276" )
			)
			( signal "TP_CPU1_RSVD_277"
				( objectStatus "@baseboard_fab2_lib.baseboard_fab2(sch_1):tp_cpu1_rsvd_277" )
			)
			( signal "TP_CPU1_RSVD_278"
				( objectStatus "@baseboard_fab2_lib.baseboard_fab2(sch_1):tp_cpu1_rsvd_278" )
			)
			( signal "TP_CPU1_RSVD_279"
				( objectStatus "@baseboard_fab2_lib.baseboard_fab2(sch_1):tp_cpu1_rsvd_279" )
			)
			( signal "TP_CPU1_RSVD_280"
				( objectStatus "@baseboard_fab2_lib.baseboard_fab2(sch_1):tp_cpu1_rsvd_280" )
			)
			( signal "TP_CPU1_RSVD_281"
				( objectStatus "@baseboard_fab2_lib.baseboard_fab2(sch_1):tp_cpu1_rsvd_281" )
			)
			( signal "TP_CPU1_RSVD_282"
				( objectStatus "@baseboard_fab2_lib.baseboard_fab2(sch_1):tp_cpu1_rsvd_282" )
			)
			( signal "TP_CPU1_RSVD_283"
				( objectStatus "@baseboard_fab2_lib.baseboard_fab2(sch_1):tp_cpu1_rsvd_283" )
			)
			( signal "TP_CPU1_RSVD_284"
				( objectStatus "@baseboard_fab2_lib.baseboard_fab2(sch_1):tp_cpu1_rsvd_284" )
			)
			( signal "TP_CPU1_RSVD_285"
				( objectStatus "@baseboard_fab2_lib.baseboard_fab2(sch_1):tp_cpu1_rsvd_285" )
			)
			( signal "TP_CPU1_RSVD_286"
				( objectStatus "@baseboard_fab2_lib.baseboard_fab2(sch_1):tp_cpu1_rsvd_286" )
			)
			( signal "TP_CPU1_RSVD_287"
				( objectStatus "@baseboard_fab2_lib.baseboard_fab2(sch_1):tp_cpu1_rsvd_287" )
			)
			( signal "TP_CPU1_RSVD_288"
				( objectStatus "@baseboard_fab2_lib.baseboard_fab2(sch_1):tp_cpu1_rsvd_288" )
			)
			( signal "TP_CPU1_RSVD_289"
				( objectStatus "@baseboard_fab2_lib.baseboard_fab2(sch_1):tp_cpu1_rsvd_289" )
			)
			( signal "TP_CPU1_RSVD_290"
				( objectStatus "@baseboard_fab2_lib.baseboard_fab2(sch_1):tp_cpu1_rsvd_290" )
			)
			( signal "TP_CPU1_RSVD_291"
				( objectStatus "@baseboard_fab2_lib.baseboard_fab2(sch_1):tp_cpu1_rsvd_291" )
			)
			( signal "TP_CPU1_RSVD_292"
				( objectStatus "@baseboard_fab2_lib.baseboard_fab2(sch_1):tp_cpu1_rsvd_292" )
			)
			( signal "TP_CPU1_RSVD_293"
				( objectStatus "@baseboard_fab2_lib.baseboard_fab2(sch_1):tp_cpu1_rsvd_293" )
			)
			( signal "TP_CPU1_RSVD_298"
				( objectStatus "@baseboard_fab2_lib.baseboard_fab2(sch_1):tp_cpu1_rsvd_298" )
			)
			( signal "TP_CPU1_RSVD_299"
				( objectStatus "@baseboard_fab2_lib.baseboard_fab2(sch_1):tp_cpu1_rsvd_299" )
			)
			( signal "TP_CPU1_RSVD_300"
				( objectStatus "@baseboard_fab2_lib.baseboard_fab2(sch_1):tp_cpu1_rsvd_300" )
			)
			( signal "TP_CPU1_RSVD_303"
				( objectStatus "@baseboard_fab2_lib.baseboard_fab2(sch_1):tp_cpu1_rsvd_303" )
			)
			( signal "TP_CPU1_RSVD_304"
				( objectStatus "@baseboard_fab2_lib.baseboard_fab2(sch_1):tp_cpu1_rsvd_304" )
			)
			( signal "TP_CPU1_RSVD_TEST_11"
				( objectStatus "@baseboard_fab2_lib.baseboard_fab2(sch_1):tp_cpu1_rsvd_test_11" )
			)
			( signal "TP_CPU1_RSVD_TEST_3"
				( objectStatus "@baseboard_fab2_lib.baseboard_fab2(sch_1):tp_cpu1_rsvd_test_3" )
			)
			( signal "TP_CPU1_RSVD_TEST_4"
				( objectStatus "@baseboard_fab2_lib.baseboard_fab2(sch_1):tp_cpu1_rsvd_test_4" )
			)
			( signal "TP_CPU1_RSVD_TEST_5"
				( objectStatus "@baseboard_fab2_lib.baseboard_fab2(sch_1):tp_cpu1_rsvd_test_5" )
			)
			( signal "VSENSE_P1V8MCP_CPU1_SKT_VRTN"
				( objectStatus "@baseboard_fab2_lib.baseboard_fab2(sch_1):vsense_p1v8mcp_cpu1_skt_vrtn" )
			)
			( signal "VSENSE_P1V8MCP_CPU1_SKT_VSEN"
				( objectStatus "@baseboard_fab2_lib.baseboard_fab2(sch_1):vsense_p1v8mcp_cpu1_skt_vsen" )
			)
			( signal "M_G_ACT_N"
				( objectStatus "@baseboard_fab2_lib.baseboard_fab2(sch_1):m_g_act_n" )
			)
			( signal "M_G_ALERT_N"
				( objectStatus "@baseboard_fab2_lib.baseboard_fab2(sch_1):m_g_alert_n" )
			)
			( signal "M_G_BA<0>"
				( objectStatus "@baseboard_fab2_lib.baseboard_fab2(sch_1):m_g_ba(0)" )
			)
			( signal "M_G_BA<1>"
				( objectStatus "@baseboard_fab2_lib.baseboard_fab2(sch_1):m_g_ba(1)" )
			)
			( signal "M_G_BG<0>"
				( objectStatus "@baseboard_fab2_lib.baseboard_fab2(sch_1):m_g_bg(0)" )
			)
			( signal "M_G_BG<1>"
				( objectStatus "@baseboard_fab2_lib.baseboard_fab2(sch_1):m_g_bg(1)" )
			)
			( signal "M_G_C<2>"
				( objectStatus "@baseboard_fab2_lib.baseboard_fab2(sch_1):m_g_c(2)" )
			)
			( signal "M_G_CKE<0>"
				( objectStatus "@baseboard_fab2_lib.baseboard_fab2(sch_1):m_g_cke(0)" )
			)
			( signal "M_G_CKE<1>"
				( objectStatus "@baseboard_fab2_lib.baseboard_fab2(sch_1):m_g_cke(1)" )
			)
			( signal "M_G_CKE<2>"
				( objectStatus "@baseboard_fab2_lib.baseboard_fab2(sch_1):m_g_cke(2)" )
			)
			( signal "M_G_CKE<3>"
				( objectStatus "@baseboard_fab2_lib.baseboard_fab2(sch_1):m_g_cke(3)" )
			)
			( signal "M_G_CLK_DN<0>"
				( objectStatus "@baseboard_fab2_lib.baseboard_fab2(sch_1):m_g_clk_dn(0)" )
			)
			( signal "M_G_CLK_DN<1>"
				( objectStatus "@baseboard_fab2_lib.baseboard_fab2(sch_1):m_g_clk_dn(1)" )
			)
			( signal "M_G_CLK_DN<2>"
				( objectStatus "@baseboard_fab2_lib.baseboard_fab2(sch_1):m_g_clk_dn(2)" )
			)
			( signal "M_G_CLK_DN<3>"
				( objectStatus "@baseboard_fab2_lib.baseboard_fab2(sch_1):m_g_clk_dn(3)" )
			)
			( signal "M_G_CLK_DP<0>"
				( objectStatus "@baseboard_fab2_lib.baseboard_fab2(sch_1):m_g_clk_dp(0)" )
			)
			( signal "M_G_CLK_DP<1>"
				( objectStatus "@baseboard_fab2_lib.baseboard_fab2(sch_1):m_g_clk_dp(1)" )
			)
			( signal "M_G_CLK_DP<2>"
				( objectStatus "@baseboard_fab2_lib.baseboard_fab2(sch_1):m_g_clk_dp(2)" )
			)
			( signal "M_G_CLK_DP<3>"
				( objectStatus "@baseboard_fab2_lib.baseboard_fab2(sch_1):m_g_clk_dp(3)" )
			)
			( signal "M_G_CS_N<0>"
				( objectStatus "@baseboard_fab2_lib.baseboard_fab2(sch_1):m_g_cs_n(0)" )
			)
			( signal "M_G_CS_N<1>"
				( objectStatus "@baseboard_fab2_lib.baseboard_fab2(sch_1):m_g_cs_n(1)" )
			)
			( signal "M_G_CS_N<2>"
				( objectStatus "@baseboard_fab2_lib.baseboard_fab2(sch_1):m_g_cs_n(2)" )
			)
			( signal "M_G_CS_N<3>"
				( objectStatus "@baseboard_fab2_lib.baseboard_fab2(sch_1):m_g_cs_n(3)" )
			)
			( signal "M_G_CS_N<4>"
				( objectStatus "@baseboard_fab2_lib.baseboard_fab2(sch_1):m_g_cs_n(4)" )
			)
			( signal "M_G_CS_N<5>"
				( objectStatus "@baseboard_fab2_lib.baseboard_fab2(sch_1):m_g_cs_n(5)" )
			)
			( signal "M_G_CS_N<6>"
				( objectStatus "@baseboard_fab2_lib.baseboard_fab2(sch_1):m_g_cs_n(6)" )
			)
			( signal "M_G_CS_N<7>"
				( objectStatus "@baseboard_fab2_lib.baseboard_fab2(sch_1):m_g_cs_n(7)" )
			)
			( signal "M_G_DQ<0>"
				( objectStatus "@baseboard_fab2_lib.baseboard_fab2(sch_1):m_g_dq(0)" )
			)
			( signal "M_G_DQ<1>"
				( objectStatus "@baseboard_fab2_lib.baseboard_fab2(sch_1):m_g_dq(1)" )
			)
			( signal "M_G_DQ<2>"
				( objectStatus "@baseboard_fab2_lib.baseboard_fab2(sch_1):m_g_dq(2)" )
			)
			( signal "M_G_DQ<3>"
				( objectStatus "@baseboard_fab2_lib.baseboard_fab2(sch_1):m_g_dq(3)" )
			)
			( signal "M_G_DQ<4>"
				( objectStatus "@baseboard_fab2_lib.baseboard_fab2(sch_1):m_g_dq(4)" )
			)
			( signal "M_G_DQ<5>"
				( objectStatus "@baseboard_fab2_lib.baseboard_fab2(sch_1):m_g_dq(5)" )
			)
			( signal "M_G_DQ<6>"
				( objectStatus "@baseboard_fab2_lib.baseboard_fab2(sch_1):m_g_dq(6)" )
			)
			( signal "M_G_DQ<7>"
				( objectStatus "@baseboard_fab2_lib.baseboard_fab2(sch_1):m_g_dq(7)" )
			)
			( signal "M_G_DQ<8>"
				( objectStatus "@baseboard_fab2_lib.baseboard_fab2(sch_1):m_g_dq(8)" )
			)
			( signal "M_G_DQ<9>"
				( objectStatus "@baseboard_fab2_lib.baseboard_fab2(sch_1):m_g_dq(9)" )
			)
			( signal "M_G_DQ<10>"
				( objectStatus "@baseboard_fab2_lib.baseboard_fab2(sch_1):m_g_dq(10)" )
			)
			( signal "M_G_DQ<11>"
				( objectStatus "@baseboard_fab2_lib.baseboard_fab2(sch_1):m_g_dq(11)" )
			)
			( signal "M_G_DQ<12>"
				( objectStatus "@baseboard_fab2_lib.baseboard_fab2(sch_1):m_g_dq(12)" )
			)
			( signal "M_G_DQ<13>"
				( objectStatus "@baseboard_fab2_lib.baseboard_fab2(sch_1):m_g_dq(13)" )
			)
			( signal "M_G_DQ<14>"
				( objectStatus "@baseboard_fab2_lib.baseboard_fab2(sch_1):m_g_dq(14)" )
			)
			( signal "M_G_DQ<15>"
				( objectStatus "@baseboard_fab2_lib.baseboard_fab2(sch_1):m_g_dq(15)" )
			)
			( signal "M_G_DQ<16>"
				( objectStatus "@baseboard_fab2_lib.baseboard_fab2(sch_1):m_g_dq(16)" )
			)
			( signal "M_G_DQ<17>"
				( objectStatus "@baseboard_fab2_lib.baseboard_fab2(sch_1):m_g_dq(17)" )
			)
			( signal "M_G_DQ<18>"
				( objectStatus "@baseboard_fab2_lib.baseboard_fab2(sch_1):m_g_dq(18)" )
			)
			( signal "M_G_DQ<19>"
				( objectStatus "@baseboard_fab2_lib.baseboard_fab2(sch_1):m_g_dq(19)" )
			)
			( signal "M_G_DQ<20>"
				( objectStatus "@baseboard_fab2_lib.baseboard_fab2(sch_1):m_g_dq(20)" )
			)
			( signal "M_G_DQ<21>"
				( objectStatus "@baseboard_fab2_lib.baseboard_fab2(sch_1):m_g_dq(21)" )
			)
			( signal "M_G_DQ<22>"
				( objectStatus "@baseboard_fab2_lib.baseboard_fab2(sch_1):m_g_dq(22)" )
			)
			( signal "M_G_DQ<23>"
				( objectStatus "@baseboard_fab2_lib.baseboard_fab2(sch_1):m_g_dq(23)" )
			)
			( signal "M_G_DQ<24>"
				( objectStatus "@baseboard_fab2_lib.baseboard_fab2(sch_1):m_g_dq(24)" )
			)
			( signal "M_G_DQ<25>"
				( objectStatus "@baseboard_fab2_lib.baseboard_fab2(sch_1):m_g_dq(25)" )
			)
			( signal "M_G_DQ<26>"
				( objectStatus "@baseboard_fab2_lib.baseboard_fab2(sch_1):m_g_dq(26)" )
			)
			( signal "M_G_DQ<27>"
				( objectStatus "@baseboard_fab2_lib.baseboard_fab2(sch_1):m_g_dq(27)" )
			)
			( signal "M_G_DQ<28>"
				( objectStatus "@baseboard_fab2_lib.baseboard_fab2(sch_1):m_g_dq(28)" )
			)
			( signal "M_G_DQ<29>"
				( objectStatus "@baseboard_fab2_lib.baseboard_fab2(sch_1):m_g_dq(29)" )
			)
			( signal "M_G_DQ<30>"
				( objectStatus "@baseboard_fab2_lib.baseboard_fab2(sch_1):m_g_dq(30)" )
			)
			( signal "M_G_DQ<31>"
				( objectStatus "@baseboard_fab2_lib.baseboard_fab2(sch_1):m_g_dq(31)" )
			)
			( signal "M_G_DQ<32>"
				( objectStatus "@baseboard_fab2_lib.baseboard_fab2(sch_1):m_g_dq(32)" )
			)
			( signal "M_G_DQ<33>"
				( objectStatus "@baseboard_fab2_lib.baseboard_fab2(sch_1):m_g_dq(33)" )
			)
			( signal "M_G_DQ<34>"
				( objectStatus "@baseboard_fab2_lib.baseboard_fab2(sch_1):m_g_dq(34)" )
			)
			( signal "M_G_DQ<35>"
				( objectStatus "@baseboard_fab2_lib.baseboard_fab2(sch_1):m_g_dq(35)" )
			)
			( signal "M_G_DQ<36>"
				( objectStatus "@baseboard_fab2_lib.baseboard_fab2(sch_1):m_g_dq(36)" )
			)
			( signal "M_G_DQ<37>"
				( objectStatus "@baseboard_fab2_lib.baseboard_fab2(sch_1):m_g_dq(37)" )
			)
			( signal "M_G_DQ<38>"
				( objectStatus "@baseboard_fab2_lib.baseboard_fab2(sch_1):m_g_dq(38)" )
			)
			( signal "M_G_DQ<39>"
				( objectStatus "@baseboard_fab2_lib.baseboard_fab2(sch_1):m_g_dq(39)" )
			)
			( signal "M_G_DQ<40>"
				( objectStatus "@baseboard_fab2_lib.baseboard_fab2(sch_1):m_g_dq(40)" )
			)
			( signal "M_G_DQ<41>"
				( objectStatus "@baseboard_fab2_lib.baseboard_fab2(sch_1):m_g_dq(41)" )
			)
			( signal "M_G_DQ<42>"
				( objectStatus "@baseboard_fab2_lib.baseboard_fab2(sch_1):m_g_dq(42)" )
			)
			( signal "M_G_DQ<43>"
				( objectStatus "@baseboard_fab2_lib.baseboard_fab2(sch_1):m_g_dq(43)" )
			)
			( signal "M_G_DQ<44>"
				( objectStatus "@baseboard_fab2_lib.baseboard_fab2(sch_1):m_g_dq(44)" )
			)
			( signal "M_G_DQ<45>"
				( objectStatus "@baseboard_fab2_lib.baseboard_fab2(sch_1):m_g_dq(45)" )
			)
			( signal "M_G_DQ<46>"
				( objectStatus "@baseboard_fab2_lib.baseboard_fab2(sch_1):m_g_dq(46)" )
			)
			( signal "M_G_DQ<47>"
				( objectStatus "@baseboard_fab2_lib.baseboard_fab2(sch_1):m_g_dq(47)" )
			)
			( signal "M_G_DQ<48>"
				( objectStatus "@baseboard_fab2_lib.baseboard_fab2(sch_1):m_g_dq(48)" )
			)
			( signal "M_G_DQ<49>"
				( objectStatus "@baseboard_fab2_lib.baseboard_fab2(sch_1):m_g_dq(49)" )
			)
			( signal "M_G_DQ<50>"
				( objectStatus "@baseboard_fab2_lib.baseboard_fab2(sch_1):m_g_dq(50)" )
			)
			( signal "M_G_DQ<51>"
				( objectStatus "@baseboard_fab2_lib.baseboard_fab2(sch_1):m_g_dq(51)" )
			)
			( signal "M_G_DQ<52>"
				( objectStatus "@baseboard_fab2_lib.baseboard_fab2(sch_1):m_g_dq(52)" )
			)
			( signal "M_G_DQ<53>"
				( objectStatus "@baseboard_fab2_lib.baseboard_fab2(sch_1):m_g_dq(53)" )
			)
			( signal "M_G_DQ<54>"
				( objectStatus "@baseboard_fab2_lib.baseboard_fab2(sch_1):m_g_dq(54)" )
			)
			( signal "M_G_DQ<55>"
				( objectStatus "@baseboard_fab2_lib.baseboard_fab2(sch_1):m_g_dq(55)" )
			)
			( signal "M_G_DQ<56>"
				( objectStatus "@baseboard_fab2_lib.baseboard_fab2(sch_1):m_g_dq(56)" )
			)
			( signal "M_G_DQ<57>"
				( objectStatus "@baseboard_fab2_lib.baseboard_fab2(sch_1):m_g_dq(57)" )
			)
			( signal "M_G_DQ<58>"
				( objectStatus "@baseboard_fab2_lib.baseboard_fab2(sch_1):m_g_dq(58)" )
			)
			( signal "M_G_DQ<59>"
				( objectStatus "@baseboard_fab2_lib.baseboard_fab2(sch_1):m_g_dq(59)" )
			)
			( signal "M_G_DQ<60>"
				( objectStatus "@baseboard_fab2_lib.baseboard_fab2(sch_1):m_g_dq(60)" )
			)
			( signal "M_G_DQ<61>"
				( objectStatus "@baseboard_fab2_lib.baseboard_fab2(sch_1):m_g_dq(61)" )
			)
			( signal "M_G_DQ<62>"
				( objectStatus "@baseboard_fab2_lib.baseboard_fab2(sch_1):m_g_dq(62)" )
			)
			( signal "M_G_DQ<63>"
				( objectStatus "@baseboard_fab2_lib.baseboard_fab2(sch_1):m_g_dq(63)" )
			)
			( signal "M_G_DQS_DN<0>"
				( objectStatus "@baseboard_fab2_lib.baseboard_fab2(sch_1):m_g_dqs_dn(0)" )
			)
			( signal "M_G_DQS_DN<1>"
				( objectStatus "@baseboard_fab2_lib.baseboard_fab2(sch_1):m_g_dqs_dn(1)" )
			)
			( signal "M_G_DQS_DN<2>"
				( objectStatus "@baseboard_fab2_lib.baseboard_fab2(sch_1):m_g_dqs_dn(2)" )
			)
			( signal "M_G_DQS_DN<3>"
				( objectStatus "@baseboard_fab2_lib.baseboard_fab2(sch_1):m_g_dqs_dn(3)" )
			)
			( signal "M_G_DQS_DN<4>"
				( objectStatus "@baseboard_fab2_lib.baseboard_fab2(sch_1):m_g_dqs_dn(4)" )
			)
			( signal "M_G_DQS_DN<5>"
				( objectStatus "@baseboard_fab2_lib.baseboard_fab2(sch_1):m_g_dqs_dn(5)" )
			)
			( signal "M_G_DQS_DN<6>"
				( objectStatus "@baseboard_fab2_lib.baseboard_fab2(sch_1):m_g_dqs_dn(6)" )
			)
			( signal "M_G_DQS_DN<7>"
				( objectStatus "@baseboard_fab2_lib.baseboard_fab2(sch_1):m_g_dqs_dn(7)" )
			)
			( signal "M_G_DQS_DN<8>"
				( objectStatus "@baseboard_fab2_lib.baseboard_fab2(sch_1):m_g_dqs_dn(8)" )
			)
			( signal "M_G_DQS_DN<9>"
				( objectStatus "@baseboard_fab2_lib.baseboard_fab2(sch_1):m_g_dqs_dn(9)" )
			)
			( signal "M_G_DQS_DN<10>"
				( objectStatus "@baseboard_fab2_lib.baseboard_fab2(sch_1):m_g_dqs_dn(10)" )
			)
			( signal "M_G_DQS_DN<11>"
				( objectStatus "@baseboard_fab2_lib.baseboard_fab2(sch_1):m_g_dqs_dn(11)" )
			)
			( signal "M_G_DQS_DN<12>"
				( objectStatus "@baseboard_fab2_lib.baseboard_fab2(sch_1):m_g_dqs_dn(12)" )
			)
			( signal "M_G_DQS_DN<13>"
				( objectStatus "@baseboard_fab2_lib.baseboard_fab2(sch_1):m_g_dqs_dn(13)" )
			)
			( signal "M_G_DQS_DN<14>"
				( objectStatus "@baseboard_fab2_lib.baseboard_fab2(sch_1):m_g_dqs_dn(14)" )
			)
			( signal "M_G_DQS_DN<15>"
				( objectStatus "@baseboard_fab2_lib.baseboard_fab2(sch_1):m_g_dqs_dn(15)" )
			)
			( signal "M_G_DQS_DN<16>"
				( objectStatus "@baseboard_fab2_lib.baseboard_fab2(sch_1):m_g_dqs_dn(16)" )
			)
			( signal "M_G_DQS_DN<17>"
				( objectStatus "@baseboard_fab2_lib.baseboard_fab2(sch_1):m_g_dqs_dn(17)" )
			)
			( signal "M_G_DQS_DP<0>"
				( objectStatus "@baseboard_fab2_lib.baseboard_fab2(sch_1):m_g_dqs_dp(0)" )
			)
			( signal "M_G_DQS_DP<1>"
				( objectStatus "@baseboard_fab2_lib.baseboard_fab2(sch_1):m_g_dqs_dp(1)" )
			)
			( signal "M_G_DQS_DP<2>"
				( objectStatus "@baseboard_fab2_lib.baseboard_fab2(sch_1):m_g_dqs_dp(2)" )
			)
			( signal "M_G_DQS_DP<3>"
				( objectStatus "@baseboard_fab2_lib.baseboard_fab2(sch_1):m_g_dqs_dp(3)" )
			)
			( signal "M_G_DQS_DP<4>"
				( objectStatus "@baseboard_fab2_lib.baseboard_fab2(sch_1):m_g_dqs_dp(4)" )
			)
			( signal "M_G_DQS_DP<5>"
				( objectStatus "@baseboard_fab2_lib.baseboard_fab2(sch_1):m_g_dqs_dp(5)" )
			)
			( signal "M_G_DQS_DP<6>"
				( objectStatus "@baseboard_fab2_lib.baseboard_fab2(sch_1):m_g_dqs_dp(6)" )
			)
			( signal "M_G_DQS_DP<7>"
				( objectStatus "@baseboard_fab2_lib.baseboard_fab2(sch_1):m_g_dqs_dp(7)" )
			)
			( signal "M_G_DQS_DP<8>"
				( objectStatus "@baseboard_fab2_lib.baseboard_fab2(sch_1):m_g_dqs_dp(8)" )
			)
			( signal "M_G_DQS_DP<9>"
				( objectStatus "@baseboard_fab2_lib.baseboard_fab2(sch_1):m_g_dqs_dp(9)" )
			)
			( signal "M_G_DQS_DP<10>"
				( objectStatus "@baseboard_fab2_lib.baseboard_fab2(sch_1):m_g_dqs_dp(10)" )
			)
			( signal "M_G_DQS_DP<11>"
				( objectStatus "@baseboard_fab2_lib.baseboard_fab2(sch_1):m_g_dqs_dp(11)" )
			)
			( signal "M_G_DQS_DP<12>"
				( objectStatus "@baseboard_fab2_lib.baseboard_fab2(sch_1):m_g_dqs_dp(12)" )
			)
			( signal "M_G_DQS_DP<13>"
				( objectStatus "@baseboard_fab2_lib.baseboard_fab2(sch_1):m_g_dqs_dp(13)" )
			)
			( signal "M_G_DQS_DP<14>"
				( objectStatus "@baseboard_fab2_lib.baseboard_fab2(sch_1):m_g_dqs_dp(14)" )
			)
			( signal "M_G_DQS_DP<15>"
				( objectStatus "@baseboard_fab2_lib.baseboard_fab2(sch_1):m_g_dqs_dp(15)" )
			)
			( signal "M_G_DQS_DP<16>"
				( objectStatus "@baseboard_fab2_lib.baseboard_fab2(sch_1):m_g_dqs_dp(16)" )
			)
			( signal "M_G_DQS_DP<17>"
				( objectStatus "@baseboard_fab2_lib.baseboard_fab2(sch_1):m_g_dqs_dp(17)" )
			)
			( signal "M_G_ECC<0>"
				( objectStatus "@baseboard_fab2_lib.baseboard_fab2(sch_1):m_g_ecc(0)" )
			)
			( signal "M_G_ECC<1>"
				( objectStatus "@baseboard_fab2_lib.baseboard_fab2(sch_1):m_g_ecc(1)" )
			)
			( signal "M_G_ECC<2>"
				( objectStatus "@baseboard_fab2_lib.baseboard_fab2(sch_1):m_g_ecc(2)" )
			)
			( signal "M_G_ECC<3>"
				( objectStatus "@baseboard_fab2_lib.baseboard_fab2(sch_1):m_g_ecc(3)" )
			)
			( signal "M_G_ECC<4>"
				( objectStatus "@baseboard_fab2_lib.baseboard_fab2(sch_1):m_g_ecc(4)" )
			)
			( signal "M_G_ECC<5>"
				( objectStatus "@baseboard_fab2_lib.baseboard_fab2(sch_1):m_g_ecc(5)" )
			)
			( signal "M_G_ECC<6>"
				( objectStatus "@baseboard_fab2_lib.baseboard_fab2(sch_1):m_g_ecc(6)" )
			)
			( signal "M_G_ECC<7>"
				( objectStatus "@baseboard_fab2_lib.baseboard_fab2(sch_1):m_g_ecc(7)" )
			)
			( signal "M_G_MA<0>"
				( objectStatus "@baseboard_fab2_lib.baseboard_fab2(sch_1):m_g_ma(0)" )
			)
			( signal "M_G_MA<1>"
				( objectStatus "@baseboard_fab2_lib.baseboard_fab2(sch_1):m_g_ma(1)" )
			)
			( signal "M_G_MA<2>"
				( objectStatus "@baseboard_fab2_lib.baseboard_fab2(sch_1):m_g_ma(2)" )
			)
			( signal "M_G_MA<3>"
				( objectStatus "@baseboard_fab2_lib.baseboard_fab2(sch_1):m_g_ma(3)" )
			)
			( signal "M_G_MA<4>"
				( objectStatus "@baseboard_fab2_lib.baseboard_fab2(sch_1):m_g_ma(4)" )
			)
			( signal "M_G_MA<5>"
				( objectStatus "@baseboard_fab2_lib.baseboard_fab2(sch_1):m_g_ma(5)" )
			)
			( signal "M_G_MA<6>"
				( objectStatus "@baseboard_fab2_lib.baseboard_fab2(sch_1):m_g_ma(6)" )
			)
			( signal "M_G_MA<7>"
				( objectStatus "@baseboard_fab2_lib.baseboard_fab2(sch_1):m_g_ma(7)" )
			)
			( signal "M_G_MA<8>"
				( objectStatus "@baseboard_fab2_lib.baseboard_fab2(sch_1):m_g_ma(8)" )
			)
			( signal "M_G_MA<9>"
				( objectStatus "@baseboard_fab2_lib.baseboard_fab2(sch_1):m_g_ma(9)" )
			)
			( signal "M_G_MA<10>"
				( objectStatus "@baseboard_fab2_lib.baseboard_fab2(sch_1):m_g_ma(10)" )
			)
			( signal "M_G_MA<11>"
				( objectStatus "@baseboard_fab2_lib.baseboard_fab2(sch_1):m_g_ma(11)" )
			)
			( signal "M_G_MA<12>"
				( objectStatus "@baseboard_fab2_lib.baseboard_fab2(sch_1):m_g_ma(12)" )
			)
			( signal "M_G_MA<13>"
				( objectStatus "@baseboard_fab2_lib.baseboard_fab2(sch_1):m_g_ma(13)" )
			)
			( signal "M_G_MA<14>"
				( objectStatus "@baseboard_fab2_lib.baseboard_fab2(sch_1):m_g_ma(14)" )
			)
			( signal "M_G_MA<15>"
				( objectStatus "@baseboard_fab2_lib.baseboard_fab2(sch_1):m_g_ma(15)" )
			)
			( signal "M_G_MA<16>"
				( objectStatus "@baseboard_fab2_lib.baseboard_fab2(sch_1):m_g_ma(16)" )
			)
			( signal "M_G_MA<17>"
				( objectStatus "@baseboard_fab2_lib.baseboard_fab2(sch_1):m_g_ma(17)" )
			)
			( signal "M_G_ODT<0>"
				( objectStatus "@baseboard_fab2_lib.baseboard_fab2(sch_1):m_g_odt(0)" )
			)
			( signal "M_G_ODT<1>"
				( objectStatus "@baseboard_fab2_lib.baseboard_fab2(sch_1):m_g_odt(1)" )
			)
			( signal "M_G_ODT<2>"
				( objectStatus "@baseboard_fab2_lib.baseboard_fab2(sch_1):m_g_odt(2)" )
			)
			( signal "M_G_ODT<3>"
				( objectStatus "@baseboard_fab2_lib.baseboard_fab2(sch_1):m_g_odt(3)" )
			)
			( signal "M_G_PAR"
				( objectStatus "@baseboard_fab2_lib.baseboard_fab2(sch_1):m_g_par" )
			)
			( signal "M_H_ACT_N"
				( objectStatus "@baseboard_fab2_lib.baseboard_fab2(sch_1):m_h_act_n" )
			)
			( signal "M_H_ALERT_N"
				( objectStatus "@baseboard_fab2_lib.baseboard_fab2(sch_1):m_h_alert_n" )
			)
			( signal "M_H_BA<0>"
				( objectStatus "@baseboard_fab2_lib.baseboard_fab2(sch_1):m_h_ba(0)" )
			)
			( signal "M_H_BA<1>"
				( objectStatus "@baseboard_fab2_lib.baseboard_fab2(sch_1):m_h_ba(1)" )
			)
			( signal "M_H_BG<0>"
				( objectStatus "@baseboard_fab2_lib.baseboard_fab2(sch_1):m_h_bg(0)" )
			)
			( signal "M_H_BG<1>"
				( objectStatus "@baseboard_fab2_lib.baseboard_fab2(sch_1):m_h_bg(1)" )
			)
			( signal "M_H_C<2>"
				( objectStatus "@baseboard_fab2_lib.baseboard_fab2(sch_1):m_h_c(2)" )
			)
			( signal "M_H_CKE<0>"
				( objectStatus "@baseboard_fab2_lib.baseboard_fab2(sch_1):m_h_cke(0)" )
			)
			( signal "M_H_CKE<1>"
				( objectStatus "@baseboard_fab2_lib.baseboard_fab2(sch_1):m_h_cke(1)" )
			)
			( signal "M_H_CKE<2>"
				( objectStatus "@baseboard_fab2_lib.baseboard_fab2(sch_1):m_h_cke(2)" )
			)
			( signal "M_H_CKE<3>"
				( objectStatus "@baseboard_fab2_lib.baseboard_fab2(sch_1):m_h_cke(3)" )
			)
			( signal "M_H_CLK_DN<0>"
				( objectStatus "@baseboard_fab2_lib.baseboard_fab2(sch_1):m_h_clk_dn(0)" )
			)
			( signal "M_H_CLK_DN<1>"
				( objectStatus "@baseboard_fab2_lib.baseboard_fab2(sch_1):m_h_clk_dn(1)" )
			)
			( signal "M_H_CLK_DN<2>"
				( objectStatus "@baseboard_fab2_lib.baseboard_fab2(sch_1):m_h_clk_dn(2)" )
			)
			( signal "M_H_CLK_DN<3>"
				( objectStatus "@baseboard_fab2_lib.baseboard_fab2(sch_1):m_h_clk_dn(3)" )
			)
			( signal "M_H_CLK_DP<0>"
				( objectStatus "@baseboard_fab2_lib.baseboard_fab2(sch_1):m_h_clk_dp(0)" )
			)
			( signal "M_H_CLK_DP<1>"
				( objectStatus "@baseboard_fab2_lib.baseboard_fab2(sch_1):m_h_clk_dp(1)" )
			)
			( signal "M_H_CLK_DP<2>"
				( objectStatus "@baseboard_fab2_lib.baseboard_fab2(sch_1):m_h_clk_dp(2)" )
			)
			( signal "M_H_CLK_DP<3>"
				( objectStatus "@baseboard_fab2_lib.baseboard_fab2(sch_1):m_h_clk_dp(3)" )
			)
			( signal "M_H_CS_N<0>"
				( objectStatus "@baseboard_fab2_lib.baseboard_fab2(sch_1):m_h_cs_n(0)" )
			)
			( signal "M_H_CS_N<1>"
				( objectStatus "@baseboard_fab2_lib.baseboard_fab2(sch_1):m_h_cs_n(1)" )
			)
			( signal "M_H_CS_N<2>"
				( objectStatus "@baseboard_fab2_lib.baseboard_fab2(sch_1):m_h_cs_n(2)" )
			)
			( signal "M_H_CS_N<3>"
				( objectStatus "@baseboard_fab2_lib.baseboard_fab2(sch_1):m_h_cs_n(3)" )
			)
			( signal "M_H_CS_N<4>"
				( objectStatus "@baseboard_fab2_lib.baseboard_fab2(sch_1):m_h_cs_n(4)" )
			)
			( signal "M_H_CS_N<5>"
				( objectStatus "@baseboard_fab2_lib.baseboard_fab2(sch_1):m_h_cs_n(5)" )
			)
			( signal "M_H_CS_N<6>"
				( objectStatus "@baseboard_fab2_lib.baseboard_fab2(sch_1):m_h_cs_n(6)" )
			)
			( signal "M_H_CS_N<7>"
				( objectStatus "@baseboard_fab2_lib.baseboard_fab2(sch_1):m_h_cs_n(7)" )
			)
			( signal "M_H_DQ<0>"
				( objectStatus "@baseboard_fab2_lib.baseboard_fab2(sch_1):m_h_dq(0)" )
			)
			( signal "M_H_DQ<1>"
				( objectStatus "@baseboard_fab2_lib.baseboard_fab2(sch_1):m_h_dq(1)" )
			)
			( signal "M_H_DQ<2>"
				( objectStatus "@baseboard_fab2_lib.baseboard_fab2(sch_1):m_h_dq(2)" )
			)
			( signal "M_H_DQ<3>"
				( objectStatus "@baseboard_fab2_lib.baseboard_fab2(sch_1):m_h_dq(3)" )
			)
			( signal "M_H_DQ<4>"
				( objectStatus "@baseboard_fab2_lib.baseboard_fab2(sch_1):m_h_dq(4)" )
			)
			( signal "M_H_DQ<5>"
				( objectStatus "@baseboard_fab2_lib.baseboard_fab2(sch_1):m_h_dq(5)" )
			)
			( signal "M_H_DQ<6>"
				( objectStatus "@baseboard_fab2_lib.baseboard_fab2(sch_1):m_h_dq(6)" )
			)
			( signal "M_H_DQ<7>"
				( objectStatus "@baseboard_fab2_lib.baseboard_fab2(sch_1):m_h_dq(7)" )
			)
			( signal "M_H_DQ<8>"
				( objectStatus "@baseboard_fab2_lib.baseboard_fab2(sch_1):m_h_dq(8)" )
			)
			( signal "M_H_DQ<9>"
				( objectStatus "@baseboard_fab2_lib.baseboard_fab2(sch_1):m_h_dq(9)" )
			)
			( signal "M_H_DQ<10>"
				( objectStatus "@baseboard_fab2_lib.baseboard_fab2(sch_1):m_h_dq(10)" )
			)
			( signal "M_H_DQ<11>"
				( objectStatus "@baseboard_fab2_lib.baseboard_fab2(sch_1):m_h_dq(11)" )
			)
			( signal "M_H_DQ<12>"
				( objectStatus "@baseboard_fab2_lib.baseboard_fab2(sch_1):m_h_dq(12)" )
			)
			( signal "M_H_DQ<13>"
				( objectStatus "@baseboard_fab2_lib.baseboard_fab2(sch_1):m_h_dq(13)" )
			)
			( signal "M_H_DQ<14>"
				( objectStatus "@baseboard_fab2_lib.baseboard_fab2(sch_1):m_h_dq(14)" )
			)
			( signal "M_H_DQ<15>"
				( objectStatus "@baseboard_fab2_lib.baseboard_fab2(sch_1):m_h_dq(15)" )
			)
			( signal "M_H_DQ<16>"
				( objectStatus "@baseboard_fab2_lib.baseboard_fab2(sch_1):m_h_dq(16)" )
			)
			( signal "M_H_DQ<17>"
				( objectStatus "@baseboard_fab2_lib.baseboard_fab2(sch_1):m_h_dq(17)" )
			)
			( signal "M_H_DQ<18>"
				( objectStatus "@baseboard_fab2_lib.baseboard_fab2(sch_1):m_h_dq(18)" )
			)
			( signal "M_H_DQ<19>"
				( objectStatus "@baseboard_fab2_lib.baseboard_fab2(sch_1):m_h_dq(19)" )
			)
			( signal "M_H_DQ<20>"
				( objectStatus "@baseboard_fab2_lib.baseboard_fab2(sch_1):m_h_dq(20)" )
			)
			( signal "M_H_DQ<21>"
				( objectStatus "@baseboard_fab2_lib.baseboard_fab2(sch_1):m_h_dq(21)" )
			)
			( signal "M_H_DQ<22>"
				( objectStatus "@baseboard_fab2_lib.baseboard_fab2(sch_1):m_h_dq(22)" )
			)
			( signal "M_H_DQ<23>"
				( objectStatus "@baseboard_fab2_lib.baseboard_fab2(sch_1):m_h_dq(23)" )
			)
			( signal "M_H_DQ<24>"
				( objectStatus "@baseboard_fab2_lib.baseboard_fab2(sch_1):m_h_dq(24)" )
			)
			( signal "M_H_DQ<25>"
				( objectStatus "@baseboard_fab2_lib.baseboard_fab2(sch_1):m_h_dq(25)" )
			)
			( signal "M_H_DQ<26>"
				( objectStatus "@baseboard_fab2_lib.baseboard_fab2(sch_1):m_h_dq(26)" )
			)
			( signal "M_H_DQ<27>"
				( objectStatus "@baseboard_fab2_lib.baseboard_fab2(sch_1):m_h_dq(27)" )
			)
			( signal "M_H_DQ<28>"
				( objectStatus "@baseboard_fab2_lib.baseboard_fab2(sch_1):m_h_dq(28)" )
			)
			( signal "M_H_DQ<29>"
				( objectStatus "@baseboard_fab2_lib.baseboard_fab2(sch_1):m_h_dq(29)" )
			)
			( signal "M_H_DQ<30>"
				( objectStatus "@baseboard_fab2_lib.baseboard_fab2(sch_1):m_h_dq(30)" )
			)
			( signal "M_H_DQ<31>"
				( objectStatus "@baseboard_fab2_lib.baseboard_fab2(sch_1):m_h_dq(31)" )
			)
			( signal "M_H_DQ<32>"
				( objectStatus "@baseboard_fab2_lib.baseboard_fab2(sch_1):m_h_dq(32)" )
			)
			( signal "M_H_DQ<33>"
				( objectStatus "@baseboard_fab2_lib.baseboard_fab2(sch_1):m_h_dq(33)" )
			)
			( signal "M_H_DQ<34>"
				( objectStatus "@baseboard_fab2_lib.baseboard_fab2(sch_1):m_h_dq(34)" )
			)
			( signal "M_H_DQ<35>"
				( objectStatus "@baseboard_fab2_lib.baseboard_fab2(sch_1):m_h_dq(35)" )
			)
			( signal "M_H_DQ<36>"
				( objectStatus "@baseboard_fab2_lib.baseboard_fab2(sch_1):m_h_dq(36)" )
			)
			( signal "M_H_DQ<37>"
				( objectStatus "@baseboard_fab2_lib.baseboard_fab2(sch_1):m_h_dq(37)" )
			)
			( signal "M_H_DQ<38>"
				( objectStatus "@baseboard_fab2_lib.baseboard_fab2(sch_1):m_h_dq(38)" )
			)
			( signal "M_H_DQ<39>"
				( objectStatus "@baseboard_fab2_lib.baseboard_fab2(sch_1):m_h_dq(39)" )
			)
			( signal "M_H_DQ<40>"
				( objectStatus "@baseboard_fab2_lib.baseboard_fab2(sch_1):m_h_dq(40)" )
			)
			( signal "M_H_DQ<41>"
				( objectStatus "@baseboard_fab2_lib.baseboard_fab2(sch_1):m_h_dq(41)" )
			)
			( signal "M_H_DQ<42>"
				( objectStatus "@baseboard_fab2_lib.baseboard_fab2(sch_1):m_h_dq(42)" )
			)
			( signal "M_H_DQ<43>"
				( objectStatus "@baseboard_fab2_lib.baseboard_fab2(sch_1):m_h_dq(43)" )
			)
			( signal "M_H_DQ<44>"
				( objectStatus "@baseboard_fab2_lib.baseboard_fab2(sch_1):m_h_dq(44)" )
			)
			( signal "M_H_DQ<45>"
				( objectStatus "@baseboard_fab2_lib.baseboard_fab2(sch_1):m_h_dq(45)" )
			)
			( signal "M_H_DQ<46>"
				( objectStatus "@baseboard_fab2_lib.baseboard_fab2(sch_1):m_h_dq(46)" )
			)
			( signal "M_H_DQ<47>"
				( objectStatus "@baseboard_fab2_lib.baseboard_fab2(sch_1):m_h_dq(47)" )
			)
			( signal "M_H_DQ<48>"
				( objectStatus "@baseboard_fab2_lib.baseboard_fab2(sch_1):m_h_dq(48)" )
			)
			( signal "M_H_DQ<49>"
				( objectStatus "@baseboard_fab2_lib.baseboard_fab2(sch_1):m_h_dq(49)" )
			)
			( signal "M_H_DQ<50>"
				( objectStatus "@baseboard_fab2_lib.baseboard_fab2(sch_1):m_h_dq(50)" )
			)
			( signal "M_H_DQ<51>"
				( objectStatus "@baseboard_fab2_lib.baseboard_fab2(sch_1):m_h_dq(51)" )
			)
			( signal "M_H_DQ<52>"
				( objectStatus "@baseboard_fab2_lib.baseboard_fab2(sch_1):m_h_dq(52)" )
			)
			( signal "M_H_DQ<53>"
				( objectStatus "@baseboard_fab2_lib.baseboard_fab2(sch_1):m_h_dq(53)" )
			)
			( signal "M_H_DQ<54>"
				( objectStatus "@baseboard_fab2_lib.baseboard_fab2(sch_1):m_h_dq(54)" )
			)
			( signal "M_H_DQ<55>"
				( objectStatus "@baseboard_fab2_lib.baseboard_fab2(sch_1):m_h_dq(55)" )
			)
			( signal "M_H_DQ<56>"
				( objectStatus "@baseboard_fab2_lib.baseboard_fab2(sch_1):m_h_dq(56)" )
			)
			( signal "M_H_DQ<57>"
				( objectStatus "@baseboard_fab2_lib.baseboard_fab2(sch_1):m_h_dq(57)" )
			)
			( signal "M_H_DQ<58>"
				( objectStatus "@baseboard_fab2_lib.baseboard_fab2(sch_1):m_h_dq(58)" )
			)
			( signal "M_H_DQ<59>"
				( objectStatus "@baseboard_fab2_lib.baseboard_fab2(sch_1):m_h_dq(59)" )
			)
			( signal "M_H_DQ<60>"
				( objectStatus "@baseboard_fab2_lib.baseboard_fab2(sch_1):m_h_dq(60)" )
			)
			( signal "M_H_DQ<61>"
				( objectStatus "@baseboard_fab2_lib.baseboard_fab2(sch_1):m_h_dq(61)" )
			)
			( signal "M_H_DQ<62>"
				( objectStatus "@baseboard_fab2_lib.baseboard_fab2(sch_1):m_h_dq(62)" )
			)
			( signal "M_H_DQ<63>"
				( objectStatus "@baseboard_fab2_lib.baseboard_fab2(sch_1):m_h_dq(63)" )
			)
			( signal "M_H_DQS_DN<0>"
				( objectStatus "@baseboard_fab2_lib.baseboard_fab2(sch_1):m_h_dqs_dn(0)" )
			)
			( signal "M_H_DQS_DN<1>"
				( objectStatus "@baseboard_fab2_lib.baseboard_fab2(sch_1):m_h_dqs_dn(1)" )
			)
			( signal "M_H_DQS_DN<2>"
				( objectStatus "@baseboard_fab2_lib.baseboard_fab2(sch_1):m_h_dqs_dn(2)" )
			)
			( signal "M_H_DQS_DN<3>"
				( objectStatus "@baseboard_fab2_lib.baseboard_fab2(sch_1):m_h_dqs_dn(3)" )
			)
			( signal "M_H_DQS_DN<4>"
				( objectStatus "@baseboard_fab2_lib.baseboard_fab2(sch_1):m_h_dqs_dn(4)" )
			)
			( signal "M_H_DQS_DN<5>"
				( objectStatus "@baseboard_fab2_lib.baseboard_fab2(sch_1):m_h_dqs_dn(5)" )
			)
			( signal "M_H_DQS_DN<6>"
				( objectStatus "@baseboard_fab2_lib.baseboard_fab2(sch_1):m_h_dqs_dn(6)" )
			)
			( signal "M_H_DQS_DN<7>"
				( objectStatus "@baseboard_fab2_lib.baseboard_fab2(sch_1):m_h_dqs_dn(7)" )
			)
			( signal "M_H_DQS_DN<8>"
				( objectStatus "@baseboard_fab2_lib.baseboard_fab2(sch_1):m_h_dqs_dn(8)" )
			)
			( signal "M_H_DQS_DN<9>"
				( objectStatus "@baseboard_fab2_lib.baseboard_fab2(sch_1):m_h_dqs_dn(9)" )
			)
			( signal "M_H_DQS_DN<10>"
				( objectStatus "@baseboard_fab2_lib.baseboard_fab2(sch_1):m_h_dqs_dn(10)" )
			)
			( signal "M_H_DQS_DN<11>"
				( objectStatus "@baseboard_fab2_lib.baseboard_fab2(sch_1):m_h_dqs_dn(11)" )
			)
			( signal "M_H_DQS_DN<12>"
				( objectStatus "@baseboard_fab2_lib.baseboard_fab2(sch_1):m_h_dqs_dn(12)" )
			)
			( signal "M_H_DQS_DN<13>"
				( objectStatus "@baseboard_fab2_lib.baseboard_fab2(sch_1):m_h_dqs_dn(13)" )
			)
			( signal "M_H_DQS_DN<14>"
				( objectStatus "@baseboard_fab2_lib.baseboard_fab2(sch_1):m_h_dqs_dn(14)" )
			)
			( signal "M_H_DQS_DN<15>"
				( objectStatus "@baseboard_fab2_lib.baseboard_fab2(sch_1):m_h_dqs_dn(15)" )
			)
			( signal "M_H_DQS_DN<16>"
				( objectStatus "@baseboard_fab2_lib.baseboard_fab2(sch_1):m_h_dqs_dn(16)" )
			)
			( signal "M_H_DQS_DN<17>"
				( objectStatus "@baseboard_fab2_lib.baseboard_fab2(sch_1):m_h_dqs_dn(17)" )
			)
			( signal "M_H_DQS_DP<0>"
				( objectStatus "@baseboard_fab2_lib.baseboard_fab2(sch_1):m_h_dqs_dp(0)" )
			)
			( signal "M_H_DQS_DP<1>"
				( objectStatus "@baseboard_fab2_lib.baseboard_fab2(sch_1):m_h_dqs_dp(1)" )
			)
			( signal "M_H_DQS_DP<2>"
				( objectStatus "@baseboard_fab2_lib.baseboard_fab2(sch_1):m_h_dqs_dp(2)" )
			)
			( signal "M_H_DQS_DP<3>"
				( objectStatus "@baseboard_fab2_lib.baseboard_fab2(sch_1):m_h_dqs_dp(3)" )
			)
			( signal "M_H_DQS_DP<4>"
				( objectStatus "@baseboard_fab2_lib.baseboard_fab2(sch_1):m_h_dqs_dp(4)" )
			)
			( signal "M_H_DQS_DP<5>"
				( objectStatus "@baseboard_fab2_lib.baseboard_fab2(sch_1):m_h_dqs_dp(5)" )
			)
			( signal "M_H_DQS_DP<6>"
				( objectStatus "@baseboard_fab2_lib.baseboard_fab2(sch_1):m_h_dqs_dp(6)" )
			)
			( signal "M_H_DQS_DP<7>"
				( objectStatus "@baseboard_fab2_lib.baseboard_fab2(sch_1):m_h_dqs_dp(7)" )
			)
			( signal "M_H_DQS_DP<8>"
				( objectStatus "@baseboard_fab2_lib.baseboard_fab2(sch_1):m_h_dqs_dp(8)" )
			)
			( signal "M_H_DQS_DP<9>"
				( objectStatus "@baseboard_fab2_lib.baseboard_fab2(sch_1):m_h_dqs_dp(9)" )
			)
			( signal "M_H_DQS_DP<10>"
				( objectStatus "@baseboard_fab2_lib.baseboard_fab2(sch_1):m_h_dqs_dp(10)" )
			)
			( signal "M_H_DQS_DP<11>"
				( objectStatus "@baseboard_fab2_lib.baseboard_fab2(sch_1):m_h_dqs_dp(11)" )
			)
			( signal "M_H_DQS_DP<12>"
				( objectStatus "@baseboard_fab2_lib.baseboard_fab2(sch_1):m_h_dqs_dp(12)" )
			)
			( signal "M_H_DQS_DP<13>"
				( objectStatus "@baseboard_fab2_lib.baseboard_fab2(sch_1):m_h_dqs_dp(13)" )
			)
			( signal "M_H_DQS_DP<14>"
				( objectStatus "@baseboard_fab2_lib.baseboard_fab2(sch_1):m_h_dqs_dp(14)" )
			)
			( signal "M_H_DQS_DP<15>"
				( objectStatus "@baseboard_fab2_lib.baseboard_fab2(sch_1):m_h_dqs_dp(15)" )
			)
			( signal "M_H_DQS_DP<16>"
				( objectStatus "@baseboard_fab2_lib.baseboard_fab2(sch_1):m_h_dqs_dp(16)" )
			)
			( signal "M_H_DQS_DP<17>"
				( objectStatus "@baseboard_fab2_lib.baseboard_fab2(sch_1):m_h_dqs_dp(17)" )
			)
			( signal "M_H_ECC<0>"
				( objectStatus "@baseboard_fab2_lib.baseboard_fab2(sch_1):m_h_ecc(0)" )
			)
			( signal "M_H_ECC<1>"
				( objectStatus "@baseboard_fab2_lib.baseboard_fab2(sch_1):m_h_ecc(1)" )
			)
			( signal "M_H_ECC<2>"
				( objectStatus "@baseboard_fab2_lib.baseboard_fab2(sch_1):m_h_ecc(2)" )
			)
			( signal "M_H_ECC<3>"
				( objectStatus "@baseboard_fab2_lib.baseboard_fab2(sch_1):m_h_ecc(3)" )
			)
			( signal "M_H_ECC<4>"
				( objectStatus "@baseboard_fab2_lib.baseboard_fab2(sch_1):m_h_ecc(4)" )
			)
			( signal "M_H_ECC<5>"
				( objectStatus "@baseboard_fab2_lib.baseboard_fab2(sch_1):m_h_ecc(5)" )
			)
			( signal "M_H_ECC<6>"
				( objectStatus "@baseboard_fab2_lib.baseboard_fab2(sch_1):m_h_ecc(6)" )
			)
			( signal "M_H_ECC<7>"
				( objectStatus "@baseboard_fab2_lib.baseboard_fab2(sch_1):m_h_ecc(7)" )
			)
			( signal "M_H_MA<0>"
				( objectStatus "@baseboard_fab2_lib.baseboard_fab2(sch_1):m_h_ma(0)" )
			)
			( signal "M_H_MA<1>"
				( objectStatus "@baseboard_fab2_lib.baseboard_fab2(sch_1):m_h_ma(1)" )
			)
			( signal "M_H_MA<2>"
				( objectStatus "@baseboard_fab2_lib.baseboard_fab2(sch_1):m_h_ma(2)" )
			)
			( signal "M_H_MA<3>"
				( objectStatus "@baseboard_fab2_lib.baseboard_fab2(sch_1):m_h_ma(3)" )
			)
			( signal "M_H_MA<4>"
				( objectStatus "@baseboard_fab2_lib.baseboard_fab2(sch_1):m_h_ma(4)" )
			)
			( signal "M_H_MA<5>"
				( objectStatus "@baseboard_fab2_lib.baseboard_fab2(sch_1):m_h_ma(5)" )
			)
			( signal "M_H_MA<6>"
				( objectStatus "@baseboard_fab2_lib.baseboard_fab2(sch_1):m_h_ma(6)" )
			)
			( signal "M_H_MA<7>"
				( objectStatus "@baseboard_fab2_lib.baseboard_fab2(sch_1):m_h_ma(7)" )
			)
			( signal "M_H_MA<8>"
				( objectStatus "@baseboard_fab2_lib.baseboard_fab2(sch_1):m_h_ma(8)" )
			)
			( signal "M_H_MA<9>"
				( objectStatus "@baseboard_fab2_lib.baseboard_fab2(sch_1):m_h_ma(9)" )
			)
			( signal "M_H_MA<10>"
				( objectStatus "@baseboard_fab2_lib.baseboard_fab2(sch_1):m_h_ma(10)" )
			)
			( signal "M_H_MA<11>"
				( objectStatus "@baseboard_fab2_lib.baseboard_fab2(sch_1):m_h_ma(11)" )
			)
			( signal "M_H_MA<12>"
				( objectStatus "@baseboard_fab2_lib.baseboard_fab2(sch_1):m_h_ma(12)" )
			)
			( signal "M_H_MA<13>"
				( objectStatus "@baseboard_fab2_lib.baseboard_fab2(sch_1):m_h_ma(13)" )
			)
			( signal "M_H_MA<14>"
				( objectStatus "@baseboard_fab2_lib.baseboard_fab2(sch_1):m_h_ma(14)" )
			)
			( signal "M_H_MA<15>"
				( objectStatus "@baseboard_fab2_lib.baseboard_fab2(sch_1):m_h_ma(15)" )
			)
			( signal "M_H_MA<16>"
				( objectStatus "@baseboard_fab2_lib.baseboard_fab2(sch_1):m_h_ma(16)" )
			)
			( signal "M_H_MA<17>"
				( objectStatus "@baseboard_fab2_lib.baseboard_fab2(sch_1):m_h_ma(17)" )
			)
			( signal "M_H_ODT<0>"
				( objectStatus "@baseboard_fab2_lib.baseboard_fab2(sch_1):m_h_odt(0)" )
			)
			( signal "M_H_ODT<1>"
				( objectStatus "@baseboard_fab2_lib.baseboard_fab2(sch_1):m_h_odt(1)" )
			)
			( signal "M_H_ODT<2>"
				( objectStatus "@baseboard_fab2_lib.baseboard_fab2(sch_1):m_h_odt(2)" )
			)
			( signal "M_H_ODT<3>"
				( objectStatus "@baseboard_fab2_lib.baseboard_fab2(sch_1):m_h_odt(3)" )
			)
			( signal "M_H_PAR"
				( objectStatus "@baseboard_fab2_lib.baseboard_fab2(sch_1):m_h_par" )
			)
			( signal "M_J_ACT_N"
				( objectStatus "@baseboard_fab2_lib.baseboard_fab2(sch_1):m_j_act_n" )
			)
			( signal "M_J_ALERT_N"
				( objectStatus "@baseboard_fab2_lib.baseboard_fab2(sch_1):m_j_alert_n" )
			)
			( signal "M_J_BA<0>"
				( objectStatus "@baseboard_fab2_lib.baseboard_fab2(sch_1):m_j_ba(0)" )
			)
			( signal "M_J_BA<1>"
				( objectStatus "@baseboard_fab2_lib.baseboard_fab2(sch_1):m_j_ba(1)" )
			)
			( signal "M_J_BG<0>"
				( objectStatus "@baseboard_fab2_lib.baseboard_fab2(sch_1):m_j_bg(0)" )
			)
			( signal "M_J_BG<1>"
				( objectStatus "@baseboard_fab2_lib.baseboard_fab2(sch_1):m_j_bg(1)" )
			)
			( signal "M_J_C<2>"
				( objectStatus "@baseboard_fab2_lib.baseboard_fab2(sch_1):m_j_c(2)" )
			)
			( signal "M_J_CKE<0>"
				( objectStatus "@baseboard_fab2_lib.baseboard_fab2(sch_1):m_j_cke(0)" )
			)
			( signal "M_J_CKE<1>"
				( objectStatus "@baseboard_fab2_lib.baseboard_fab2(sch_1):m_j_cke(1)" )
			)
			( signal "M_J_CKE<2>"
				( objectStatus "@baseboard_fab2_lib.baseboard_fab2(sch_1):m_j_cke(2)" )
			)
			( signal "M_J_CKE<3>"
				( objectStatus "@baseboard_fab2_lib.baseboard_fab2(sch_1):m_j_cke(3)" )
			)
			( signal "M_J_CLK_DN<0>"
				( objectStatus "@baseboard_fab2_lib.baseboard_fab2(sch_1):m_j_clk_dn(0)" )
			)
			( signal "M_J_CLK_DN<1>"
				( objectStatus "@baseboard_fab2_lib.baseboard_fab2(sch_1):m_j_clk_dn(1)" )
			)
			( signal "M_J_CLK_DN<2>"
				( objectStatus "@baseboard_fab2_lib.baseboard_fab2(sch_1):m_j_clk_dn(2)" )
			)
			( signal "M_J_CLK_DN<3>"
				( objectStatus "@baseboard_fab2_lib.baseboard_fab2(sch_1):m_j_clk_dn(3)" )
			)
			( signal "M_J_CLK_DP<0>"
				( objectStatus "@baseboard_fab2_lib.baseboard_fab2(sch_1):m_j_clk_dp(0)" )
			)
			( signal "M_J_CLK_DP<1>"
				( objectStatus "@baseboard_fab2_lib.baseboard_fab2(sch_1):m_j_clk_dp(1)" )
			)
			( signal "M_J_CLK_DP<2>"
				( objectStatus "@baseboard_fab2_lib.baseboard_fab2(sch_1):m_j_clk_dp(2)" )
			)
			( signal "M_J_CLK_DP<3>"
				( objectStatus "@baseboard_fab2_lib.baseboard_fab2(sch_1):m_j_clk_dp(3)" )
			)
			( signal "M_J_CS_N<0>"
				( objectStatus "@baseboard_fab2_lib.baseboard_fab2(sch_1):m_j_cs_n(0)" )
			)
			( signal "M_J_CS_N<1>"
				( objectStatus "@baseboard_fab2_lib.baseboard_fab2(sch_1):m_j_cs_n(1)" )
			)
			( signal "M_J_CS_N<2>"
				( objectStatus "@baseboard_fab2_lib.baseboard_fab2(sch_1):m_j_cs_n(2)" )
			)
			( signal "M_J_CS_N<3>"
				( objectStatus "@baseboard_fab2_lib.baseboard_fab2(sch_1):m_j_cs_n(3)" )
			)
			( signal "M_J_CS_N<4>"
				( objectStatus "@baseboard_fab2_lib.baseboard_fab2(sch_1):m_j_cs_n(4)" )
			)
			( signal "M_J_CS_N<5>"
				( objectStatus "@baseboard_fab2_lib.baseboard_fab2(sch_1):m_j_cs_n(5)" )
			)
			( signal "M_J_CS_N<6>"
				( objectStatus "@baseboard_fab2_lib.baseboard_fab2(sch_1):m_j_cs_n(6)" )
			)
			( signal "M_J_CS_N<7>"
				( objectStatus "@baseboard_fab2_lib.baseboard_fab2(sch_1):m_j_cs_n(7)" )
			)
			( signal "M_J_DQ<0>"
				( objectStatus "@baseboard_fab2_lib.baseboard_fab2(sch_1):m_j_dq(0)" )
			)
			( signal "M_J_DQ<1>"
				( objectStatus "@baseboard_fab2_lib.baseboard_fab2(sch_1):m_j_dq(1)" )
			)
			( signal "M_J_DQ<2>"
				( objectStatus "@baseboard_fab2_lib.baseboard_fab2(sch_1):m_j_dq(2)" )
			)
			( signal "M_J_DQ<3>"
				( objectStatus "@baseboard_fab2_lib.baseboard_fab2(sch_1):m_j_dq(3)" )
			)
			( signal "M_J_DQ<4>"
				( objectStatus "@baseboard_fab2_lib.baseboard_fab2(sch_1):m_j_dq(4)" )
			)
			( signal "M_J_DQ<5>"
				( objectStatus "@baseboard_fab2_lib.baseboard_fab2(sch_1):m_j_dq(5)" )
			)
			( signal "M_J_DQ<6>"
				( objectStatus "@baseboard_fab2_lib.baseboard_fab2(sch_1):m_j_dq(6)" )
			)
			( signal "M_J_DQ<7>"
				( objectStatus "@baseboard_fab2_lib.baseboard_fab2(sch_1):m_j_dq(7)" )
			)
			( signal "M_J_DQ<8>"
				( objectStatus "@baseboard_fab2_lib.baseboard_fab2(sch_1):m_j_dq(8)" )
			)
			( signal "M_J_DQ<9>"
				( objectStatus "@baseboard_fab2_lib.baseboard_fab2(sch_1):m_j_dq(9)" )
			)
			( signal "M_J_DQ<10>"
				( objectStatus "@baseboard_fab2_lib.baseboard_fab2(sch_1):m_j_dq(10)" )
			)
			( signal "M_J_DQ<11>"
				( objectStatus "@baseboard_fab2_lib.baseboard_fab2(sch_1):m_j_dq(11)" )
			)
			( signal "M_J_DQ<12>"
				( objectStatus "@baseboard_fab2_lib.baseboard_fab2(sch_1):m_j_dq(12)" )
			)
			( signal "M_J_DQ<13>"
				( objectStatus "@baseboard_fab2_lib.baseboard_fab2(sch_1):m_j_dq(13)" )
			)
			( signal "M_J_DQ<14>"
				( objectStatus "@baseboard_fab2_lib.baseboard_fab2(sch_1):m_j_dq(14)" )
			)
			( signal "M_J_DQ<15>"
				( objectStatus "@baseboard_fab2_lib.baseboard_fab2(sch_1):m_j_dq(15)" )
			)
			( signal "M_J_DQ<16>"
				( objectStatus "@baseboard_fab2_lib.baseboard_fab2(sch_1):m_j_dq(16)" )
			)
			( signal "M_J_DQ<17>"
				( objectStatus "@baseboard_fab2_lib.baseboard_fab2(sch_1):m_j_dq(17)" )
			)
			( signal "M_J_DQ<18>"
				( objectStatus "@baseboard_fab2_lib.baseboard_fab2(sch_1):m_j_dq(18)" )
			)
			( signal "M_J_DQ<19>"
				( objectStatus "@baseboard_fab2_lib.baseboard_fab2(sch_1):m_j_dq(19)" )
			)
			( signal "M_J_DQ<20>"
				( objectStatus "@baseboard_fab2_lib.baseboard_fab2(sch_1):m_j_dq(20)" )
			)
			( signal "M_J_DQ<21>"
				( objectStatus "@baseboard_fab2_lib.baseboard_fab2(sch_1):m_j_dq(21)" )
			)
			( signal "M_J_DQ<22>"
				( objectStatus "@baseboard_fab2_lib.baseboard_fab2(sch_1):m_j_dq(22)" )
			)
			( signal "M_J_DQ<23>"
				( objectStatus "@baseboard_fab2_lib.baseboard_fab2(sch_1):m_j_dq(23)" )
			)
			( signal "M_J_DQ<24>"
				( objectStatus "@baseboard_fab2_lib.baseboard_fab2(sch_1):m_j_dq(24)" )
			)
			( signal "M_J_DQ<25>"
				( objectStatus "@baseboard_fab2_lib.baseboard_fab2(sch_1):m_j_dq(25)" )
			)
			( signal "M_J_DQ<26>"
				( objectStatus "@baseboard_fab2_lib.baseboard_fab2(sch_1):m_j_dq(26)" )
			)
			( signal "M_J_DQ<27>"
				( objectStatus "@baseboard_fab2_lib.baseboard_fab2(sch_1):m_j_dq(27)" )
			)
			( signal "M_J_DQ<28>"
				( objectStatus "@baseboard_fab2_lib.baseboard_fab2(sch_1):m_j_dq(28)" )
			)
			( signal "M_J_DQ<29>"
				( objectStatus "@baseboard_fab2_lib.baseboard_fab2(sch_1):m_j_dq(29)" )
			)
			( signal "M_J_DQ<30>"
				( objectStatus "@baseboard_fab2_lib.baseboard_fab2(sch_1):m_j_dq(30)" )
			)
			( signal "M_J_DQ<31>"
				( objectStatus "@baseboard_fab2_lib.baseboard_fab2(sch_1):m_j_dq(31)" )
			)
			( signal "M_J_DQ<32>"
				( objectStatus "@baseboard_fab2_lib.baseboard_fab2(sch_1):m_j_dq(32)" )
			)
			( signal "M_J_DQ<33>"
				( objectStatus "@baseboard_fab2_lib.baseboard_fab2(sch_1):m_j_dq(33)" )
			)
			( signal "M_J_DQ<34>"
				( objectStatus "@baseboard_fab2_lib.baseboard_fab2(sch_1):m_j_dq(34)" )
			)
			( signal "M_J_DQ<35>"
				( objectStatus "@baseboard_fab2_lib.baseboard_fab2(sch_1):m_j_dq(35)" )
			)
			( signal "M_J_DQ<36>"
				( objectStatus "@baseboard_fab2_lib.baseboard_fab2(sch_1):m_j_dq(36)" )
			)
			( signal "M_J_DQ<37>"
				( objectStatus "@baseboard_fab2_lib.baseboard_fab2(sch_1):m_j_dq(37)" )
			)
			( signal "M_J_DQ<38>"
				( objectStatus "@baseboard_fab2_lib.baseboard_fab2(sch_1):m_j_dq(38)" )
			)
			( signal "M_J_DQ<39>"
				( objectStatus "@baseboard_fab2_lib.baseboard_fab2(sch_1):m_j_dq(39)" )
			)
			( signal "M_J_DQ<40>"
				( objectStatus "@baseboard_fab2_lib.baseboard_fab2(sch_1):m_j_dq(40)" )
			)
			( signal "M_J_DQ<41>"
				( objectStatus "@baseboard_fab2_lib.baseboard_fab2(sch_1):m_j_dq(41)" )
			)
			( signal "M_J_DQ<42>"
				( objectStatus "@baseboard_fab2_lib.baseboard_fab2(sch_1):m_j_dq(42)" )
			)
			( signal "M_J_DQ<43>"
				( objectStatus "@baseboard_fab2_lib.baseboard_fab2(sch_1):m_j_dq(43)" )
			)
			( signal "M_J_DQ<44>"
				( objectStatus "@baseboard_fab2_lib.baseboard_fab2(sch_1):m_j_dq(44)" )
			)
			( signal "M_J_DQ<45>"
				( objectStatus "@baseboard_fab2_lib.baseboard_fab2(sch_1):m_j_dq(45)" )
			)
			( signal "M_J_DQ<46>"
				( objectStatus "@baseboard_fab2_lib.baseboard_fab2(sch_1):m_j_dq(46)" )
			)
			( signal "M_J_DQ<47>"
				( objectStatus "@baseboard_fab2_lib.baseboard_fab2(sch_1):m_j_dq(47)" )
			)
			( signal "M_J_DQ<48>"
				( objectStatus "@baseboard_fab2_lib.baseboard_fab2(sch_1):m_j_dq(48)" )
			)
			( signal "M_J_DQ<49>"
				( objectStatus "@baseboard_fab2_lib.baseboard_fab2(sch_1):m_j_dq(49)" )
			)
			( signal "M_J_DQ<50>"
				( objectStatus "@baseboard_fab2_lib.baseboard_fab2(sch_1):m_j_dq(50)" )
			)
			( signal "M_J_DQ<51>"
				( objectStatus "@baseboard_fab2_lib.baseboard_fab2(sch_1):m_j_dq(51)" )
			)
			( signal "M_J_DQ<52>"
				( objectStatus "@baseboard_fab2_lib.baseboard_fab2(sch_1):m_j_dq(52)" )
			)
			( signal "M_J_DQ<53>"
				( objectStatus "@baseboard_fab2_lib.baseboard_fab2(sch_1):m_j_dq(53)" )
			)
			( signal "M_J_DQ<54>"
				( objectStatus "@baseboard_fab2_lib.baseboard_fab2(sch_1):m_j_dq(54)" )
			)
			( signal "M_J_DQ<55>"
				( objectStatus "@baseboard_fab2_lib.baseboard_fab2(sch_1):m_j_dq(55)" )
			)
			( signal "M_J_DQ<56>"
				( objectStatus "@baseboard_fab2_lib.baseboard_fab2(sch_1):m_j_dq(56)" )
			)
			( signal "M_J_DQ<57>"
				( objectStatus "@baseboard_fab2_lib.baseboard_fab2(sch_1):m_j_dq(57)" )
			)
			( signal "M_J_DQ<58>"
				( objectStatus "@baseboard_fab2_lib.baseboard_fab2(sch_1):m_j_dq(58)" )
			)
			( signal "M_J_DQ<59>"
				( objectStatus "@baseboard_fab2_lib.baseboard_fab2(sch_1):m_j_dq(59)" )
			)
			( signal "M_J_DQ<60>"
				( objectStatus "@baseboard_fab2_lib.baseboard_fab2(sch_1):m_j_dq(60)" )
			)
			( signal "M_J_DQ<61>"
				( objectStatus "@baseboard_fab2_lib.baseboard_fab2(sch_1):m_j_dq(61)" )
			)
			( signal "M_J_DQ<62>"
				( objectStatus "@baseboard_fab2_lib.baseboard_fab2(sch_1):m_j_dq(62)" )
			)
			( signal "M_J_DQ<63>"
				( objectStatus "@baseboard_fab2_lib.baseboard_fab2(sch_1):m_j_dq(63)" )
			)
			( signal "M_J_DQS_DN<0>"
				( objectStatus "@baseboard_fab2_lib.baseboard_fab2(sch_1):m_j_dqs_dn(0)" )
			)
			( signal "M_J_DQS_DN<1>"
				( objectStatus "@baseboard_fab2_lib.baseboard_fab2(sch_1):m_j_dqs_dn(1)" )
			)
			( signal "M_J_DQS_DN<2>"
				( objectStatus "@baseboard_fab2_lib.baseboard_fab2(sch_1):m_j_dqs_dn(2)" )
			)
			( signal "M_J_DQS_DN<3>"
				( objectStatus "@baseboard_fab2_lib.baseboard_fab2(sch_1):m_j_dqs_dn(3)" )
			)
			( signal "M_J_DQS_DN<4>"
				( objectStatus "@baseboard_fab2_lib.baseboard_fab2(sch_1):m_j_dqs_dn(4)" )
			)
			( signal "M_J_DQS_DN<5>"
				( objectStatus "@baseboard_fab2_lib.baseboard_fab2(sch_1):m_j_dqs_dn(5)" )
			)
			( signal "M_J_DQS_DN<6>"
				( objectStatus "@baseboard_fab2_lib.baseboard_fab2(sch_1):m_j_dqs_dn(6)" )
			)
			( signal "M_J_DQS_DN<7>"
				( objectStatus "@baseboard_fab2_lib.baseboard_fab2(sch_1):m_j_dqs_dn(7)" )
			)
			( signal "M_J_DQS_DN<8>"
				( objectStatus "@baseboard_fab2_lib.baseboard_fab2(sch_1):m_j_dqs_dn(8)" )
			)
			( signal "M_J_DQS_DN<9>"
				( objectStatus "@baseboard_fab2_lib.baseboard_fab2(sch_1):m_j_dqs_dn(9)" )
			)
			( signal "M_J_DQS_DN<10>"
				( objectStatus "@baseboard_fab2_lib.baseboard_fab2(sch_1):m_j_dqs_dn(10)" )
			)
			( signal "M_J_DQS_DN<11>"
				( objectStatus "@baseboard_fab2_lib.baseboard_fab2(sch_1):m_j_dqs_dn(11)" )
			)
			( signal "M_J_DQS_DN<12>"
				( objectStatus "@baseboard_fab2_lib.baseboard_fab2(sch_1):m_j_dqs_dn(12)" )
			)
			( signal "M_J_DQS_DN<13>"
				( objectStatus "@baseboard_fab2_lib.baseboard_fab2(sch_1):m_j_dqs_dn(13)" )
			)
			( signal "M_J_DQS_DN<14>"
				( objectStatus "@baseboard_fab2_lib.baseboard_fab2(sch_1):m_j_dqs_dn(14)" )
			)
			( signal "M_J_DQS_DN<15>"
				( objectStatus "@baseboard_fab2_lib.baseboard_fab2(sch_1):m_j_dqs_dn(15)" )
			)
			( signal "M_J_DQS_DN<16>"
				( objectStatus "@baseboard_fab2_lib.baseboard_fab2(sch_1):m_j_dqs_dn(16)" )
			)
			( signal "M_J_DQS_DN<17>"
				( objectStatus "@baseboard_fab2_lib.baseboard_fab2(sch_1):m_j_dqs_dn(17)" )
			)
			( signal "M_J_DQS_DP<0>"
				( objectStatus "@baseboard_fab2_lib.baseboard_fab2(sch_1):m_j_dqs_dp(0)" )
			)
			( signal "M_J_DQS_DP<1>"
				( objectStatus "@baseboard_fab2_lib.baseboard_fab2(sch_1):m_j_dqs_dp(1)" )
			)
			( signal "M_J_DQS_DP<2>"
				( objectStatus "@baseboard_fab2_lib.baseboard_fab2(sch_1):m_j_dqs_dp(2)" )
			)
			( signal "M_J_DQS_DP<3>"
				( objectStatus "@baseboard_fab2_lib.baseboard_fab2(sch_1):m_j_dqs_dp(3)" )
			)
			( signal "M_J_DQS_DP<4>"
				( objectStatus "@baseboard_fab2_lib.baseboard_fab2(sch_1):m_j_dqs_dp(4)" )
			)
			( signal "M_J_DQS_DP<5>"
				( objectStatus "@baseboard_fab2_lib.baseboard_fab2(sch_1):m_j_dqs_dp(5)" )
			)
			( signal "M_J_DQS_DP<6>"
				( objectStatus "@baseboard_fab2_lib.baseboard_fab2(sch_1):m_j_dqs_dp(6)" )
			)
			( signal "M_J_DQS_DP<7>"
				( objectStatus "@baseboard_fab2_lib.baseboard_fab2(sch_1):m_j_dqs_dp(7)" )
			)
			( signal "M_J_DQS_DP<8>"
				( objectStatus "@baseboard_fab2_lib.baseboard_fab2(sch_1):m_j_dqs_dp(8)" )
			)
			( signal "M_J_DQS_DP<9>"
				( objectStatus "@baseboard_fab2_lib.baseboard_fab2(sch_1):m_j_dqs_dp(9)" )
			)
			( signal "M_J_DQS_DP<10>"
				( objectStatus "@baseboard_fab2_lib.baseboard_fab2(sch_1):m_j_dqs_dp(10)" )
			)
			( signal "M_J_DQS_DP<11>"
				( objectStatus "@baseboard_fab2_lib.baseboard_fab2(sch_1):m_j_dqs_dp(11)" )
			)
			( signal "M_J_DQS_DP<12>"
				( objectStatus "@baseboard_fab2_lib.baseboard_fab2(sch_1):m_j_dqs_dp(12)" )
			)
			( signal "M_J_DQS_DP<13>"
				( objectStatus "@baseboard_fab2_lib.baseboard_fab2(sch_1):m_j_dqs_dp(13)" )
			)
			( signal "M_J_DQS_DP<14>"
				( objectStatus "@baseboard_fab2_lib.baseboard_fab2(sch_1):m_j_dqs_dp(14)" )
			)
			( signal "M_J_DQS_DP<15>"
				( objectStatus "@baseboard_fab2_lib.baseboard_fab2(sch_1):m_j_dqs_dp(15)" )
			)
			( signal "M_J_DQS_DP<16>"
				( objectStatus "@baseboard_fab2_lib.baseboard_fab2(sch_1):m_j_dqs_dp(16)" )
			)
			( signal "M_J_DQS_DP<17>"
				( objectStatus "@baseboard_fab2_lib.baseboard_fab2(sch_1):m_j_dqs_dp(17)" )
			)
			( signal "M_J_ECC<0>"
				( objectStatus "@baseboard_fab2_lib.baseboard_fab2(sch_1):m_j_ecc(0)" )
			)
			( signal "M_J_ECC<1>"
				( objectStatus "@baseboard_fab2_lib.baseboard_fab2(sch_1):m_j_ecc(1)" )
			)
			( signal "M_J_ECC<2>"
				( objectStatus "@baseboard_fab2_lib.baseboard_fab2(sch_1):m_j_ecc(2)" )
			)
			( signal "M_J_ECC<3>"
				( objectStatus "@baseboard_fab2_lib.baseboard_fab2(sch_1):m_j_ecc(3)" )
			)
			( signal "M_J_ECC<4>"
				( objectStatus "@baseboard_fab2_lib.baseboard_fab2(sch_1):m_j_ecc(4)" )
			)
			( signal "M_J_ECC<5>"
				( objectStatus "@baseboard_fab2_lib.baseboard_fab2(sch_1):m_j_ecc(5)" )
			)
			( signal "M_J_ECC<6>"
				( objectStatus "@baseboard_fab2_lib.baseboard_fab2(sch_1):m_j_ecc(6)" )
			)
			( signal "M_J_ECC<7>"
				( objectStatus "@baseboard_fab2_lib.baseboard_fab2(sch_1):m_j_ecc(7)" )
			)
			( signal "M_J_MA<0>"
				( objectStatus "@baseboard_fab2_lib.baseboard_fab2(sch_1):m_j_ma(0)" )
			)
			( signal "M_J_MA<1>"
				( objectStatus "@baseboard_fab2_lib.baseboard_fab2(sch_1):m_j_ma(1)" )
			)
			( signal "M_J_MA<2>"
				( objectStatus "@baseboard_fab2_lib.baseboard_fab2(sch_1):m_j_ma(2)" )
			)
			( signal "M_J_MA<3>"
				( objectStatus "@baseboard_fab2_lib.baseboard_fab2(sch_1):m_j_ma(3)" )
			)
			( signal "M_J_MA<4>"
				( objectStatus "@baseboard_fab2_lib.baseboard_fab2(sch_1):m_j_ma(4)" )
			)
			( signal "M_J_MA<5>"
				( objectStatus "@baseboard_fab2_lib.baseboard_fab2(sch_1):m_j_ma(5)" )
			)
			( signal "M_J_MA<6>"
				( objectStatus "@baseboard_fab2_lib.baseboard_fab2(sch_1):m_j_ma(6)" )
			)
			( signal "M_J_MA<7>"
				( objectStatus "@baseboard_fab2_lib.baseboard_fab2(sch_1):m_j_ma(7)" )
			)
			( signal "M_J_MA<8>"
				( objectStatus "@baseboard_fab2_lib.baseboard_fab2(sch_1):m_j_ma(8)" )
			)
			( signal "M_J_MA<9>"
				( objectStatus "@baseboard_fab2_lib.baseboard_fab2(sch_1):m_j_ma(9)" )
			)
			( signal "M_J_MA<10>"
				( objectStatus "@baseboard_fab2_lib.baseboard_fab2(sch_1):m_j_ma(10)" )
			)
			( signal "M_J_MA<11>"
				( objectStatus "@baseboard_fab2_lib.baseboard_fab2(sch_1):m_j_ma(11)" )
			)
			( signal "M_J_MA<12>"
				( objectStatus "@baseboard_fab2_lib.baseboard_fab2(sch_1):m_j_ma(12)" )
			)
			( signal "M_J_MA<13>"
				( objectStatus "@baseboard_fab2_lib.baseboard_fab2(sch_1):m_j_ma(13)" )
			)
			( signal "M_J_MA<14>"
				( objectStatus "@baseboard_fab2_lib.baseboard_fab2(sch_1):m_j_ma(14)" )
			)
			( signal "M_J_MA<15>"
				( objectStatus "@baseboard_fab2_lib.baseboard_fab2(sch_1):m_j_ma(15)" )
			)
			( signal "M_J_MA<16>"
				( objectStatus "@baseboard_fab2_lib.baseboard_fab2(sch_1):m_j_ma(16)" )
			)
			( signal "M_J_MA<17>"
				( objectStatus "@baseboard_fab2_lib.baseboard_fab2(sch_1):m_j_ma(17)" )
			)
			( signal "M_J_ODT<0>"
				( objectStatus "@baseboard_fab2_lib.baseboard_fab2(sch_1):m_j_odt(0)" )
			)
			( signal "M_J_ODT<1>"
				( objectStatus "@baseboard_fab2_lib.baseboard_fab2(sch_1):m_j_odt(1)" )
			)
			( signal "M_J_ODT<2>"
				( objectStatus "@baseboard_fab2_lib.baseboard_fab2(sch_1):m_j_odt(2)" )
			)
			( signal "M_J_ODT<3>"
				( objectStatus "@baseboard_fab2_lib.baseboard_fab2(sch_1):m_j_odt(3)" )
			)
			( signal "M_J_PAR"
				( objectStatus "@baseboard_fab2_lib.baseboard_fab2(sch_1):m_j_par" )
			)
			( signal "M_K_ACT_N"
				( objectStatus "@baseboard_fab2_lib.baseboard_fab2(sch_1):m_k_act_n" )
			)
			( signal "M_K_ALERT_N"
				( objectStatus "@baseboard_fab2_lib.baseboard_fab2(sch_1):m_k_alert_n" )
			)
			( signal "M_K_BA<0>"
				( objectStatus "@baseboard_fab2_lib.baseboard_fab2(sch_1):m_k_ba(0)" )
			)
			( signal "M_K_BA<1>"
				( objectStatus "@baseboard_fab2_lib.baseboard_fab2(sch_1):m_k_ba(1)" )
			)
			( signal "M_K_BG<0>"
				( objectStatus "@baseboard_fab2_lib.baseboard_fab2(sch_1):m_k_bg(0)" )
			)
			( signal "M_K_BG<1>"
				( objectStatus "@baseboard_fab2_lib.baseboard_fab2(sch_1):m_k_bg(1)" )
			)
			( signal "M_K_C<2>"
				( objectStatus "@baseboard_fab2_lib.baseboard_fab2(sch_1):m_k_c(2)" )
			)
			( signal "M_K_CKE<0>"
				( objectStatus "@baseboard_fab2_lib.baseboard_fab2(sch_1):m_k_cke(0)" )
			)
			( signal "M_K_CKE<1>"
				( objectStatus "@baseboard_fab2_lib.baseboard_fab2(sch_1):m_k_cke(1)" )
			)
			( signal "M_K_CKE<2>"
				( objectStatus "@baseboard_fab2_lib.baseboard_fab2(sch_1):m_k_cke(2)" )
			)
			( signal "M_K_CKE<3>"
				( objectStatus "@baseboard_fab2_lib.baseboard_fab2(sch_1):m_k_cke(3)" )
			)
			( signal "M_K_CLK_DN<0>"
				( objectStatus "@baseboard_fab2_lib.baseboard_fab2(sch_1):m_k_clk_dn(0)" )
			)
			( signal "M_K_CLK_DN<1>"
				( objectStatus "@baseboard_fab2_lib.baseboard_fab2(sch_1):m_k_clk_dn(1)" )
			)
			( signal "M_K_CLK_DN<2>"
				( objectStatus "@baseboard_fab2_lib.baseboard_fab2(sch_1):m_k_clk_dn(2)" )
			)
			( signal "M_K_CLK_DN<3>"
				( objectStatus "@baseboard_fab2_lib.baseboard_fab2(sch_1):m_k_clk_dn(3)" )
			)
			( signal "M_K_CLK_DP<0>"
				( objectStatus "@baseboard_fab2_lib.baseboard_fab2(sch_1):m_k_clk_dp(0)" )
			)
			( signal "M_K_CLK_DP<1>"
				( objectStatus "@baseboard_fab2_lib.baseboard_fab2(sch_1):m_k_clk_dp(1)" )
			)
			( signal "M_K_CLK_DP<2>"
				( objectStatus "@baseboard_fab2_lib.baseboard_fab2(sch_1):m_k_clk_dp(2)" )
			)
			( signal "M_K_CLK_DP<3>"
				( objectStatus "@baseboard_fab2_lib.baseboard_fab2(sch_1):m_k_clk_dp(3)" )
			)
			( signal "M_K_CS_N<0>"
				( objectStatus "@baseboard_fab2_lib.baseboard_fab2(sch_1):m_k_cs_n(0)" )
			)
			( signal "M_K_CS_N<1>"
				( objectStatus "@baseboard_fab2_lib.baseboard_fab2(sch_1):m_k_cs_n(1)" )
			)
			( signal "M_K_CS_N<2>"
				( objectStatus "@baseboard_fab2_lib.baseboard_fab2(sch_1):m_k_cs_n(2)" )
			)
			( signal "M_K_CS_N<3>"
				( objectStatus "@baseboard_fab2_lib.baseboard_fab2(sch_1):m_k_cs_n(3)" )
			)
			( signal "M_K_CS_N<4>"
				( objectStatus "@baseboard_fab2_lib.baseboard_fab2(sch_1):m_k_cs_n(4)" )
			)
			( signal "M_K_CS_N<5>"
				( objectStatus "@baseboard_fab2_lib.baseboard_fab2(sch_1):m_k_cs_n(5)" )
			)
			( signal "M_K_CS_N<6>"
				( objectStatus "@baseboard_fab2_lib.baseboard_fab2(sch_1):m_k_cs_n(6)" )
			)
			( signal "M_K_CS_N<7>"
				( objectStatus "@baseboard_fab2_lib.baseboard_fab2(sch_1):m_k_cs_n(7)" )
			)
			( signal "M_K_DQ<0>"
				( objectStatus "@baseboard_fab2_lib.baseboard_fab2(sch_1):m_k_dq(0)" )
			)
			( signal "M_K_DQ<1>"
				( objectStatus "@baseboard_fab2_lib.baseboard_fab2(sch_1):m_k_dq(1)" )
			)
			( signal "M_K_DQ<2>"
				( objectStatus "@baseboard_fab2_lib.baseboard_fab2(sch_1):m_k_dq(2)" )
			)
			( signal "M_K_DQ<3>"
				( objectStatus "@baseboard_fab2_lib.baseboard_fab2(sch_1):m_k_dq(3)" )
			)
			( signal "M_K_DQ<4>"
				( objectStatus "@baseboard_fab2_lib.baseboard_fab2(sch_1):m_k_dq(4)" )
			)
			( signal "M_K_DQ<5>"
				( objectStatus "@baseboard_fab2_lib.baseboard_fab2(sch_1):m_k_dq(5)" )
			)
			( signal "M_K_DQ<6>"
				( objectStatus "@baseboard_fab2_lib.baseboard_fab2(sch_1):m_k_dq(6)" )
			)
			( signal "M_K_DQ<7>"
				( objectStatus "@baseboard_fab2_lib.baseboard_fab2(sch_1):m_k_dq(7)" )
			)
			( signal "M_K_DQ<8>"
				( objectStatus "@baseboard_fab2_lib.baseboard_fab2(sch_1):m_k_dq(8)" )
			)
			( signal "M_K_DQ<9>"
				( objectStatus "@baseboard_fab2_lib.baseboard_fab2(sch_1):m_k_dq(9)" )
			)
			( signal "M_K_DQ<10>"
				( objectStatus "@baseboard_fab2_lib.baseboard_fab2(sch_1):m_k_dq(10)" )
			)
			( signal "M_K_DQ<11>"
				( objectStatus "@baseboard_fab2_lib.baseboard_fab2(sch_1):m_k_dq(11)" )
			)
			( signal "M_K_DQ<12>"
				( objectStatus "@baseboard_fab2_lib.baseboard_fab2(sch_1):m_k_dq(12)" )
			)
			( signal "M_K_DQ<13>"
				( objectStatus "@baseboard_fab2_lib.baseboard_fab2(sch_1):m_k_dq(13)" )
			)
			( signal "M_K_DQ<14>"
				( objectStatus "@baseboard_fab2_lib.baseboard_fab2(sch_1):m_k_dq(14)" )
			)
			( signal "M_K_DQ<15>"
				( objectStatus "@baseboard_fab2_lib.baseboard_fab2(sch_1):m_k_dq(15)" )
			)
			( signal "M_K_DQ<16>"
				( objectStatus "@baseboard_fab2_lib.baseboard_fab2(sch_1):m_k_dq(16)" )
			)
			( signal "M_K_DQ<17>"
				( objectStatus "@baseboard_fab2_lib.baseboard_fab2(sch_1):m_k_dq(17)" )
			)
			( signal "M_K_DQ<18>"
				( objectStatus "@baseboard_fab2_lib.baseboard_fab2(sch_1):m_k_dq(18)" )
			)
			( signal "M_K_DQ<19>"
				( objectStatus "@baseboard_fab2_lib.baseboard_fab2(sch_1):m_k_dq(19)" )
			)
			( signal "M_K_DQ<20>"
				( objectStatus "@baseboard_fab2_lib.baseboard_fab2(sch_1):m_k_dq(20)" )
			)
			( signal "M_K_DQ<21>"
				( objectStatus "@baseboard_fab2_lib.baseboard_fab2(sch_1):m_k_dq(21)" )
			)
			( signal "M_K_DQ<22>"
				( objectStatus "@baseboard_fab2_lib.baseboard_fab2(sch_1):m_k_dq(22)" )
			)
			( signal "M_K_DQ<23>"
				( objectStatus "@baseboard_fab2_lib.baseboard_fab2(sch_1):m_k_dq(23)" )
			)
			( signal "M_K_DQ<24>"
				( objectStatus "@baseboard_fab2_lib.baseboard_fab2(sch_1):m_k_dq(24)" )
			)
			( signal "M_K_DQ<25>"
				( objectStatus "@baseboard_fab2_lib.baseboard_fab2(sch_1):m_k_dq(25)" )
			)
			( signal "M_K_DQ<26>"
				( objectStatus "@baseboard_fab2_lib.baseboard_fab2(sch_1):m_k_dq(26)" )
			)
			( signal "M_K_DQ<27>"
				( objectStatus "@baseboard_fab2_lib.baseboard_fab2(sch_1):m_k_dq(27)" )
			)
			( signal "M_K_DQ<28>"
				( objectStatus "@baseboard_fab2_lib.baseboard_fab2(sch_1):m_k_dq(28)" )
			)
			( signal "M_K_DQ<29>"
				( objectStatus "@baseboard_fab2_lib.baseboard_fab2(sch_1):m_k_dq(29)" )
			)
			( signal "M_K_DQ<30>"
				( objectStatus "@baseboard_fab2_lib.baseboard_fab2(sch_1):m_k_dq(30)" )
			)
			( signal "M_K_DQ<31>"
				( objectStatus "@baseboard_fab2_lib.baseboard_fab2(sch_1):m_k_dq(31)" )
			)
			( signal "M_K_DQ<32>"
				( objectStatus "@baseboard_fab2_lib.baseboard_fab2(sch_1):m_k_dq(32)" )
			)
			( signal "M_K_DQ<33>"
				( objectStatus "@baseboard_fab2_lib.baseboard_fab2(sch_1):m_k_dq(33)" )
			)
			( signal "M_K_DQ<34>"
				( objectStatus "@baseboard_fab2_lib.baseboard_fab2(sch_1):m_k_dq(34)" )
			)
			( signal "M_K_DQ<35>"
				( objectStatus "@baseboard_fab2_lib.baseboard_fab2(sch_1):m_k_dq(35)" )
			)
			( signal "M_K_DQ<36>"
				( objectStatus "@baseboard_fab2_lib.baseboard_fab2(sch_1):m_k_dq(36)" )
			)
			( signal "M_K_DQ<37>"
				( objectStatus "@baseboard_fab2_lib.baseboard_fab2(sch_1):m_k_dq(37)" )
			)
			( signal "M_K_DQ<38>"
				( objectStatus "@baseboard_fab2_lib.baseboard_fab2(sch_1):m_k_dq(38)" )
			)
			( signal "M_K_DQ<39>"
				( objectStatus "@baseboard_fab2_lib.baseboard_fab2(sch_1):m_k_dq(39)" )
			)
			( signal "M_K_DQ<40>"
				( objectStatus "@baseboard_fab2_lib.baseboard_fab2(sch_1):m_k_dq(40)" )
			)
			( signal "M_K_DQ<41>"
				( objectStatus "@baseboard_fab2_lib.baseboard_fab2(sch_1):m_k_dq(41)" )
			)
			( signal "M_K_DQ<42>"
				( objectStatus "@baseboard_fab2_lib.baseboard_fab2(sch_1):m_k_dq(42)" )
			)
			( signal "M_K_DQ<43>"
				( objectStatus "@baseboard_fab2_lib.baseboard_fab2(sch_1):m_k_dq(43)" )
			)
			( signal "M_K_DQ<44>"
				( objectStatus "@baseboard_fab2_lib.baseboard_fab2(sch_1):m_k_dq(44)" )
			)
			( signal "M_K_DQ<45>"
				( objectStatus "@baseboard_fab2_lib.baseboard_fab2(sch_1):m_k_dq(45)" )
			)
			( signal "M_K_DQ<46>"
				( objectStatus "@baseboard_fab2_lib.baseboard_fab2(sch_1):m_k_dq(46)" )
			)
			( signal "M_K_DQ<47>"
				( objectStatus "@baseboard_fab2_lib.baseboard_fab2(sch_1):m_k_dq(47)" )
			)
			( signal "M_K_DQ<48>"
				( objectStatus "@baseboard_fab2_lib.baseboard_fab2(sch_1):m_k_dq(48)" )
			)
			( signal "M_K_DQ<49>"
				( objectStatus "@baseboard_fab2_lib.baseboard_fab2(sch_1):m_k_dq(49)" )
			)
			( signal "M_K_DQ<50>"
				( objectStatus "@baseboard_fab2_lib.baseboard_fab2(sch_1):m_k_dq(50)" )
			)
			( signal "M_K_DQ<51>"
				( objectStatus "@baseboard_fab2_lib.baseboard_fab2(sch_1):m_k_dq(51)" )
			)
			( signal "M_K_DQ<52>"
				( objectStatus "@baseboard_fab2_lib.baseboard_fab2(sch_1):m_k_dq(52)" )
			)
			( signal "M_K_DQ<53>"
				( objectStatus "@baseboard_fab2_lib.baseboard_fab2(sch_1):m_k_dq(53)" )
			)
			( signal "M_K_DQ<54>"
				( objectStatus "@baseboard_fab2_lib.baseboard_fab2(sch_1):m_k_dq(54)" )
			)
			( signal "M_K_DQ<55>"
				( objectStatus "@baseboard_fab2_lib.baseboard_fab2(sch_1):m_k_dq(55)" )
			)
			( signal "M_K_DQ<56>"
				( objectStatus "@baseboard_fab2_lib.baseboard_fab2(sch_1):m_k_dq(56)" )
			)
			( signal "M_K_DQ<57>"
				( objectStatus "@baseboard_fab2_lib.baseboard_fab2(sch_1):m_k_dq(57)" )
			)
			( signal "M_K_DQ<58>"
				( objectStatus "@baseboard_fab2_lib.baseboard_fab2(sch_1):m_k_dq(58)" )
			)
			( signal "M_K_DQ<59>"
				( objectStatus "@baseboard_fab2_lib.baseboard_fab2(sch_1):m_k_dq(59)" )
			)
			( signal "M_K_DQ<60>"
				( objectStatus "@baseboard_fab2_lib.baseboard_fab2(sch_1):m_k_dq(60)" )
			)
			( signal "M_K_DQ<61>"
				( objectStatus "@baseboard_fab2_lib.baseboard_fab2(sch_1):m_k_dq(61)" )
			)
			( signal "M_K_DQ<62>"
				( objectStatus "@baseboard_fab2_lib.baseboard_fab2(sch_1):m_k_dq(62)" )
			)
			( signal "M_K_DQ<63>"
				( objectStatus "@baseboard_fab2_lib.baseboard_fab2(sch_1):m_k_dq(63)" )
			)
			( signal "M_K_DQS_DN<0>"
				( objectStatus "@baseboard_fab2_lib.baseboard_fab2(sch_1):m_k_dqs_dn(0)" )
			)
			( signal "M_K_DQS_DN<1>"
				( objectStatus "@baseboard_fab2_lib.baseboard_fab2(sch_1):m_k_dqs_dn(1)" )
			)
			( signal "M_K_DQS_DN<2>"
				( objectStatus "@baseboard_fab2_lib.baseboard_fab2(sch_1):m_k_dqs_dn(2)" )
			)
			( signal "M_K_DQS_DN<3>"
				( objectStatus "@baseboard_fab2_lib.baseboard_fab2(sch_1):m_k_dqs_dn(3)" )
			)
			( signal "M_K_DQS_DN<4>"
				( objectStatus "@baseboard_fab2_lib.baseboard_fab2(sch_1):m_k_dqs_dn(4)" )
			)
			( signal "M_K_DQS_DN<5>"
				( objectStatus "@baseboard_fab2_lib.baseboard_fab2(sch_1):m_k_dqs_dn(5)" )
			)
			( signal "M_K_DQS_DN<6>"
				( objectStatus "@baseboard_fab2_lib.baseboard_fab2(sch_1):m_k_dqs_dn(6)" )
			)
			( signal "M_K_DQS_DN<7>"
				( objectStatus "@baseboard_fab2_lib.baseboard_fab2(sch_1):m_k_dqs_dn(7)" )
			)
			( signal "M_K_DQS_DN<8>"
				( objectStatus "@baseboard_fab2_lib.baseboard_fab2(sch_1):m_k_dqs_dn(8)" )
			)
			( signal "M_K_DQS_DN<9>"
				( objectStatus "@baseboard_fab2_lib.baseboard_fab2(sch_1):m_k_dqs_dn(9)" )
			)
			( signal "M_K_DQS_DN<10>"
				( objectStatus "@baseboard_fab2_lib.baseboard_fab2(sch_1):m_k_dqs_dn(10)" )
			)
			( signal "M_K_DQS_DN<11>"
				( objectStatus "@baseboard_fab2_lib.baseboard_fab2(sch_1):m_k_dqs_dn(11)" )
			)
			( signal "M_K_DQS_DN<12>"
				( objectStatus "@baseboard_fab2_lib.baseboard_fab2(sch_1):m_k_dqs_dn(12)" )
			)
			( signal "M_K_DQS_DN<13>"
				( objectStatus "@baseboard_fab2_lib.baseboard_fab2(sch_1):m_k_dqs_dn(13)" )
			)
			( signal "M_K_DQS_DN<14>"
				( objectStatus "@baseboard_fab2_lib.baseboard_fab2(sch_1):m_k_dqs_dn(14)" )
			)
			( signal "M_K_DQS_DN<15>"
				( objectStatus "@baseboard_fab2_lib.baseboard_fab2(sch_1):m_k_dqs_dn(15)" )
			)
			( signal "M_K_DQS_DN<16>"
				( objectStatus "@baseboard_fab2_lib.baseboard_fab2(sch_1):m_k_dqs_dn(16)" )
			)
			( signal "M_K_DQS_DN<17>"
				( objectStatus "@baseboard_fab2_lib.baseboard_fab2(sch_1):m_k_dqs_dn(17)" )
			)
			( signal "M_K_DQS_DP<0>"
				( objectStatus "@baseboard_fab2_lib.baseboard_fab2(sch_1):m_k_dqs_dp(0)" )
			)
			( signal "M_K_DQS_DP<1>"
				( objectStatus "@baseboard_fab2_lib.baseboard_fab2(sch_1):m_k_dqs_dp(1)" )
			)
			( signal "M_K_DQS_DP<2>"
				( objectStatus "@baseboard_fab2_lib.baseboard_fab2(sch_1):m_k_dqs_dp(2)" )
			)
			( signal "M_K_DQS_DP<3>"
				( objectStatus "@baseboard_fab2_lib.baseboard_fab2(sch_1):m_k_dqs_dp(3)" )
			)
			( signal "M_K_DQS_DP<4>"
				( objectStatus "@baseboard_fab2_lib.baseboard_fab2(sch_1):m_k_dqs_dp(4)" )
			)
			( signal "M_K_DQS_DP<5>"
				( objectStatus "@baseboard_fab2_lib.baseboard_fab2(sch_1):m_k_dqs_dp(5)" )
			)
			( signal "M_K_DQS_DP<6>"
				( objectStatus "@baseboard_fab2_lib.baseboard_fab2(sch_1):m_k_dqs_dp(6)" )
			)
			( signal "M_K_DQS_DP<7>"
				( objectStatus "@baseboard_fab2_lib.baseboard_fab2(sch_1):m_k_dqs_dp(7)" )
			)
			( signal "M_K_DQS_DP<8>"
				( objectStatus "@baseboard_fab2_lib.baseboard_fab2(sch_1):m_k_dqs_dp(8)" )
			)
			( signal "M_K_DQS_DP<9>"
				( objectStatus "@baseboard_fab2_lib.baseboard_fab2(sch_1):m_k_dqs_dp(9)" )
			)
			( signal "M_K_DQS_DP<10>"
				( objectStatus "@baseboard_fab2_lib.baseboard_fab2(sch_1):m_k_dqs_dp(10)" )
			)
			( signal "M_K_DQS_DP<11>"
				( objectStatus "@baseboard_fab2_lib.baseboard_fab2(sch_1):m_k_dqs_dp(11)" )
			)
			( signal "M_K_DQS_DP<12>"
				( objectStatus "@baseboard_fab2_lib.baseboard_fab2(sch_1):m_k_dqs_dp(12)" )
			)
			( signal "M_K_DQS_DP<13>"
				( objectStatus "@baseboard_fab2_lib.baseboard_fab2(sch_1):m_k_dqs_dp(13)" )
			)
			( signal "M_K_DQS_DP<14>"
				( objectStatus "@baseboard_fab2_lib.baseboard_fab2(sch_1):m_k_dqs_dp(14)" )
			)
			( signal "M_K_DQS_DP<15>"
				( objectStatus "@baseboard_fab2_lib.baseboard_fab2(sch_1):m_k_dqs_dp(15)" )
			)
			( signal "M_K_DQS_DP<16>"
				( objectStatus "@baseboard_fab2_lib.baseboard_fab2(sch_1):m_k_dqs_dp(16)" )
			)
			( signal "M_K_DQS_DP<17>"
				( objectStatus "@baseboard_fab2_lib.baseboard_fab2(sch_1):m_k_dqs_dp(17)" )
			)
			( signal "M_K_ECC<0>"
				( objectStatus "@baseboard_fab2_lib.baseboard_fab2(sch_1):m_k_ecc(0)" )
			)
			( signal "M_K_ECC<1>"
				( objectStatus "@baseboard_fab2_lib.baseboard_fab2(sch_1):m_k_ecc(1)" )
			)
			( signal "M_K_ECC<2>"
				( objectStatus "@baseboard_fab2_lib.baseboard_fab2(sch_1):m_k_ecc(2)" )
			)
			( signal "M_K_ECC<3>"
				( objectStatus "@baseboard_fab2_lib.baseboard_fab2(sch_1):m_k_ecc(3)" )
			)
			( signal "M_K_ECC<4>"
				( objectStatus "@baseboard_fab2_lib.baseboard_fab2(sch_1):m_k_ecc(4)" )
			)
			( signal "M_K_ECC<5>"
				( objectStatus "@baseboard_fab2_lib.baseboard_fab2(sch_1):m_k_ecc(5)" )
			)
			( signal "M_K_ECC<6>"
				( objectStatus "@baseboard_fab2_lib.baseboard_fab2(sch_1):m_k_ecc(6)" )
			)
			( signal "M_K_ECC<7>"
				( objectStatus "@baseboard_fab2_lib.baseboard_fab2(sch_1):m_k_ecc(7)" )
			)
			( signal "M_K_MA<0>"
				( objectStatus "@baseboard_fab2_lib.baseboard_fab2(sch_1):m_k_ma(0)" )
			)
			( signal "M_K_MA<1>"
				( objectStatus "@baseboard_fab2_lib.baseboard_fab2(sch_1):m_k_ma(1)" )
			)
			( signal "M_K_MA<2>"
				( objectStatus "@baseboard_fab2_lib.baseboard_fab2(sch_1):m_k_ma(2)" )
			)
			( signal "M_K_MA<3>"
				( objectStatus "@baseboard_fab2_lib.baseboard_fab2(sch_1):m_k_ma(3)" )
			)
			( signal "M_K_MA<4>"
				( objectStatus "@baseboard_fab2_lib.baseboard_fab2(sch_1):m_k_ma(4)" )
			)
			( signal "M_K_MA<5>"
				( objectStatus "@baseboard_fab2_lib.baseboard_fab2(sch_1):m_k_ma(5)" )
			)
			( signal "M_K_MA<6>"
				( objectStatus "@baseboard_fab2_lib.baseboard_fab2(sch_1):m_k_ma(6)" )
			)
			( signal "M_K_MA<7>"
				( objectStatus "@baseboard_fab2_lib.baseboard_fab2(sch_1):m_k_ma(7)" )
			)
			( signal "M_K_MA<8>"
				( objectStatus "@baseboard_fab2_lib.baseboard_fab2(sch_1):m_k_ma(8)" )
			)
			( signal "M_K_MA<9>"
				( objectStatus "@baseboard_fab2_lib.baseboard_fab2(sch_1):m_k_ma(9)" )
			)
			( signal "M_K_MA<10>"
				( objectStatus "@baseboard_fab2_lib.baseboard_fab2(sch_1):m_k_ma(10)" )
			)
			( signal "M_K_MA<11>"
				( objectStatus "@baseboard_fab2_lib.baseboard_fab2(sch_1):m_k_ma(11)" )
			)
			( signal "M_K_MA<12>"
				( objectStatus "@baseboard_fab2_lib.baseboard_fab2(sch_1):m_k_ma(12)" )
			)
			( signal "M_K_MA<13>"
				( objectStatus "@baseboard_fab2_lib.baseboard_fab2(sch_1):m_k_ma(13)" )
			)
			( signal "M_K_MA<14>"
				( objectStatus "@baseboard_fab2_lib.baseboard_fab2(sch_1):m_k_ma(14)" )
			)
			( signal "M_K_MA<15>"
				( objectStatus "@baseboard_fab2_lib.baseboard_fab2(sch_1):m_k_ma(15)" )
			)
			( signal "M_K_MA<16>"
				( objectStatus "@baseboard_fab2_lib.baseboard_fab2(sch_1):m_k_ma(16)" )
			)
			( signal "M_K_MA<17>"
				( objectStatus "@baseboard_fab2_lib.baseboard_fab2(sch_1):m_k_ma(17)" )
			)
			( signal "M_K_ODT<0>"
				( objectStatus "@baseboard_fab2_lib.baseboard_fab2(sch_1):m_k_odt(0)" )
			)
			( signal "M_K_ODT<1>"
				( objectStatus "@baseboard_fab2_lib.baseboard_fab2(sch_1):m_k_odt(1)" )
			)
			( signal "M_K_ODT<2>"
				( objectStatus "@baseboard_fab2_lib.baseboard_fab2(sch_1):m_k_odt(2)" )
			)
			( signal "M_K_ODT<3>"
				( objectStatus "@baseboard_fab2_lib.baseboard_fab2(sch_1):m_k_odt(3)" )
			)
			( signal "M_K_PAR"
				( objectStatus "@baseboard_fab2_lib.baseboard_fab2(sch_1):m_k_par" )
			)
			( signal "M_L_ACT_N"
				( objectStatus "@baseboard_fab2_lib.baseboard_fab2(sch_1):m_l_act_n" )
			)
			( signal "M_L_ALERT_N"
				( objectStatus "@baseboard_fab2_lib.baseboard_fab2(sch_1):m_l_alert_n" )
			)
			( signal "M_L_BA<0>"
				( objectStatus "@baseboard_fab2_lib.baseboard_fab2(sch_1):m_l_ba(0)" )
			)
			( signal "M_L_BA<1>"
				( objectStatus "@baseboard_fab2_lib.baseboard_fab2(sch_1):m_l_ba(1)" )
			)
			( signal "M_L_BG<0>"
				( objectStatus "@baseboard_fab2_lib.baseboard_fab2(sch_1):m_l_bg(0)" )
			)
			( signal "M_L_BG<1>"
				( objectStatus "@baseboard_fab2_lib.baseboard_fab2(sch_1):m_l_bg(1)" )
			)
			( signal "M_L_C<2>"
				( objectStatus "@baseboard_fab2_lib.baseboard_fab2(sch_1):m_l_c(2)" )
			)
			( signal "M_L_CKE<0>"
				( objectStatus "@baseboard_fab2_lib.baseboard_fab2(sch_1):m_l_cke(0)" )
			)
			( signal "M_L_CKE<1>"
				( objectStatus "@baseboard_fab2_lib.baseboard_fab2(sch_1):m_l_cke(1)" )
			)
			( signal "M_L_CKE<2>"
				( objectStatus "@baseboard_fab2_lib.baseboard_fab2(sch_1):m_l_cke(2)" )
			)
			( signal "M_L_CKE<3>"
				( objectStatus "@baseboard_fab2_lib.baseboard_fab2(sch_1):m_l_cke(3)" )
			)
			( signal "M_L_CLK_DN<0>"
				( objectStatus "@baseboard_fab2_lib.baseboard_fab2(sch_1):m_l_clk_dn(0)" )
			)
			( signal "M_L_CLK_DN<1>"
				( objectStatus "@baseboard_fab2_lib.baseboard_fab2(sch_1):m_l_clk_dn(1)" )
			)
			( signal "M_L_CLK_DN<2>"
				( objectStatus "@baseboard_fab2_lib.baseboard_fab2(sch_1):m_l_clk_dn(2)" )
			)
			( signal "M_L_CLK_DN<3>"
				( objectStatus "@baseboard_fab2_lib.baseboard_fab2(sch_1):m_l_clk_dn(3)" )
			)
			( signal "M_L_CLK_DP<0>"
				( objectStatus "@baseboard_fab2_lib.baseboard_fab2(sch_1):m_l_clk_dp(0)" )
			)
			( signal "M_L_CLK_DP<1>"
				( objectStatus "@baseboard_fab2_lib.baseboard_fab2(sch_1):m_l_clk_dp(1)" )
			)
			( signal "M_L_CLK_DP<2>"
				( objectStatus "@baseboard_fab2_lib.baseboard_fab2(sch_1):m_l_clk_dp(2)" )
			)
			( signal "M_L_CLK_DP<3>"
				( objectStatus "@baseboard_fab2_lib.baseboard_fab2(sch_1):m_l_clk_dp(3)" )
			)
			( signal "M_L_CS_N<0>"
				( objectStatus "@baseboard_fab2_lib.baseboard_fab2(sch_1):m_l_cs_n(0)" )
			)
			( signal "M_L_CS_N<1>"
				( objectStatus "@baseboard_fab2_lib.baseboard_fab2(sch_1):m_l_cs_n(1)" )
			)
			( signal "M_L_CS_N<2>"
				( objectStatus "@baseboard_fab2_lib.baseboard_fab2(sch_1):m_l_cs_n(2)" )
			)
			( signal "M_L_CS_N<3>"
				( objectStatus "@baseboard_fab2_lib.baseboard_fab2(sch_1):m_l_cs_n(3)" )
			)
			( signal "M_L_CS_N<4>"
				( objectStatus "@baseboard_fab2_lib.baseboard_fab2(sch_1):m_l_cs_n(4)" )
			)
			( signal "M_L_CS_N<5>"
				( objectStatus "@baseboard_fab2_lib.baseboard_fab2(sch_1):m_l_cs_n(5)" )
			)
			( signal "M_L_CS_N<6>"
				( objectStatus "@baseboard_fab2_lib.baseboard_fab2(sch_1):m_l_cs_n(6)" )
			)
			( signal "M_L_CS_N<7>"
				( objectStatus "@baseboard_fab2_lib.baseboard_fab2(sch_1):m_l_cs_n(7)" )
			)
			( signal "M_L_DQ<0>"
				( objectStatus "@baseboard_fab2_lib.baseboard_fab2(sch_1):m_l_dq(0)" )
			)
			( signal "M_L_DQ<1>"
				( objectStatus "@baseboard_fab2_lib.baseboard_fab2(sch_1):m_l_dq(1)" )
			)
			( signal "M_L_DQ<2>"
				( objectStatus "@baseboard_fab2_lib.baseboard_fab2(sch_1):m_l_dq(2)" )
			)
			( signal "M_L_DQ<3>"
				( objectStatus "@baseboard_fab2_lib.baseboard_fab2(sch_1):m_l_dq(3)" )
			)
			( signal "M_L_DQ<4>"
				( objectStatus "@baseboard_fab2_lib.baseboard_fab2(sch_1):m_l_dq(4)" )
			)
			( signal "M_L_DQ<5>"
				( objectStatus "@baseboard_fab2_lib.baseboard_fab2(sch_1):m_l_dq(5)" )
			)
			( signal "M_L_DQ<6>"
				( objectStatus "@baseboard_fab2_lib.baseboard_fab2(sch_1):m_l_dq(6)" )
			)
			( signal "M_L_DQ<7>"
				( objectStatus "@baseboard_fab2_lib.baseboard_fab2(sch_1):m_l_dq(7)" )
			)
			( signal "M_L_DQ<8>"
				( objectStatus "@baseboard_fab2_lib.baseboard_fab2(sch_1):m_l_dq(8)" )
			)
			( signal "M_L_DQ<9>"
				( objectStatus "@baseboard_fab2_lib.baseboard_fab2(sch_1):m_l_dq(9)" )
			)
			( signal "M_L_DQ<10>"
				( objectStatus "@baseboard_fab2_lib.baseboard_fab2(sch_1):m_l_dq(10)" )
			)
			( signal "M_L_DQ<11>"
				( objectStatus "@baseboard_fab2_lib.baseboard_fab2(sch_1):m_l_dq(11)" )
			)
			( signal "M_L_DQ<12>"
				( objectStatus "@baseboard_fab2_lib.baseboard_fab2(sch_1):m_l_dq(12)" )
			)
			( signal "M_L_DQ<13>"
				( objectStatus "@baseboard_fab2_lib.baseboard_fab2(sch_1):m_l_dq(13)" )
			)
			( signal "M_L_DQ<14>"
				( objectStatus "@baseboard_fab2_lib.baseboard_fab2(sch_1):m_l_dq(14)" )
			)
			( signal "M_L_DQ<15>"
				( objectStatus "@baseboard_fab2_lib.baseboard_fab2(sch_1):m_l_dq(15)" )
			)
			( signal "M_L_DQ<16>"
				( objectStatus "@baseboard_fab2_lib.baseboard_fab2(sch_1):m_l_dq(16)" )
			)
			( signal "M_L_DQ<17>"
				( objectStatus "@baseboard_fab2_lib.baseboard_fab2(sch_1):m_l_dq(17)" )
			)
			( signal "M_L_DQ<18>"
				( objectStatus "@baseboard_fab2_lib.baseboard_fab2(sch_1):m_l_dq(18)" )
			)
			( signal "M_L_DQ<19>"
				( objectStatus "@baseboard_fab2_lib.baseboard_fab2(sch_1):m_l_dq(19)" )
			)
			( signal "M_L_DQ<20>"
				( objectStatus "@baseboard_fab2_lib.baseboard_fab2(sch_1):m_l_dq(20)" )
			)
			( signal "M_L_DQ<21>"
				( objectStatus "@baseboard_fab2_lib.baseboard_fab2(sch_1):m_l_dq(21)" )
			)
			( signal "M_L_DQ<22>"
				( objectStatus "@baseboard_fab2_lib.baseboard_fab2(sch_1):m_l_dq(22)" )
			)
			( signal "M_L_DQ<23>"
				( objectStatus "@baseboard_fab2_lib.baseboard_fab2(sch_1):m_l_dq(23)" )
			)
			( signal "M_L_DQ<24>"
				( objectStatus "@baseboard_fab2_lib.baseboard_fab2(sch_1):m_l_dq(24)" )
			)
			( signal "M_L_DQ<25>"
				( objectStatus "@baseboard_fab2_lib.baseboard_fab2(sch_1):m_l_dq(25)" )
			)
			( signal "M_L_DQ<26>"
				( objectStatus "@baseboard_fab2_lib.baseboard_fab2(sch_1):m_l_dq(26)" )
			)
			( signal "M_L_DQ<27>"
				( objectStatus "@baseboard_fab2_lib.baseboard_fab2(sch_1):m_l_dq(27)" )
			)
			( signal "M_L_DQ<28>"
				( objectStatus "@baseboard_fab2_lib.baseboard_fab2(sch_1):m_l_dq(28)" )
			)
			( signal "M_L_DQ<29>"
				( objectStatus "@baseboard_fab2_lib.baseboard_fab2(sch_1):m_l_dq(29)" )
			)
			( signal "M_L_DQ<30>"
				( objectStatus "@baseboard_fab2_lib.baseboard_fab2(sch_1):m_l_dq(30)" )
			)
			( signal "M_L_DQ<31>"
				( objectStatus "@baseboard_fab2_lib.baseboard_fab2(sch_1):m_l_dq(31)" )
			)
			( signal "M_L_DQ<32>"
				( objectStatus "@baseboard_fab2_lib.baseboard_fab2(sch_1):m_l_dq(32)" )
			)
			( signal "M_L_DQ<33>"
				( objectStatus "@baseboard_fab2_lib.baseboard_fab2(sch_1):m_l_dq(33)" )
			)
			( signal "M_L_DQ<34>"
				( objectStatus "@baseboard_fab2_lib.baseboard_fab2(sch_1):m_l_dq(34)" )
			)
			( signal "M_L_DQ<35>"
				( objectStatus "@baseboard_fab2_lib.baseboard_fab2(sch_1):m_l_dq(35)" )
			)
			( signal "M_L_DQ<36>"
				( objectStatus "@baseboard_fab2_lib.baseboard_fab2(sch_1):m_l_dq(36)" )
			)
			( signal "M_L_DQ<37>"
				( objectStatus "@baseboard_fab2_lib.baseboard_fab2(sch_1):m_l_dq(37)" )
			)
			( signal "M_L_DQ<38>"
				( objectStatus "@baseboard_fab2_lib.baseboard_fab2(sch_1):m_l_dq(38)" )
			)
			( signal "M_L_DQ<39>"
				( objectStatus "@baseboard_fab2_lib.baseboard_fab2(sch_1):m_l_dq(39)" )
			)
			( signal "M_L_DQ<40>"
				( objectStatus "@baseboard_fab2_lib.baseboard_fab2(sch_1):m_l_dq(40)" )
			)
			( signal "M_L_DQ<41>"
				( objectStatus "@baseboard_fab2_lib.baseboard_fab2(sch_1):m_l_dq(41)" )
			)
			( signal "M_L_DQ<42>"
				( objectStatus "@baseboard_fab2_lib.baseboard_fab2(sch_1):m_l_dq(42)" )
			)
			( signal "M_L_DQ<43>"
				( objectStatus "@baseboard_fab2_lib.baseboard_fab2(sch_1):m_l_dq(43)" )
			)
			( signal "M_L_DQ<44>"
				( objectStatus "@baseboard_fab2_lib.baseboard_fab2(sch_1):m_l_dq(44)" )
			)
			( signal "M_L_DQ<45>"
				( objectStatus "@baseboard_fab2_lib.baseboard_fab2(sch_1):m_l_dq(45)" )
			)
			( signal "M_L_DQ<46>"
				( objectStatus "@baseboard_fab2_lib.baseboard_fab2(sch_1):m_l_dq(46)" )
			)
			( signal "M_L_DQ<47>"
				( objectStatus "@baseboard_fab2_lib.baseboard_fab2(sch_1):m_l_dq(47)" )
			)
			( signal "M_L_DQ<48>"
				( objectStatus "@baseboard_fab2_lib.baseboard_fab2(sch_1):m_l_dq(48)" )
			)
			( signal "M_L_DQ<49>"
				( objectStatus "@baseboard_fab2_lib.baseboard_fab2(sch_1):m_l_dq(49)" )
			)
			( signal "M_L_DQ<50>"
				( objectStatus "@baseboard_fab2_lib.baseboard_fab2(sch_1):m_l_dq(50)" )
			)
			( signal "M_L_DQ<51>"
				( objectStatus "@baseboard_fab2_lib.baseboard_fab2(sch_1):m_l_dq(51)" )
			)
			( signal "M_L_DQ<52>"
				( objectStatus "@baseboard_fab2_lib.baseboard_fab2(sch_1):m_l_dq(52)" )
			)
			( signal "M_L_DQ<53>"
				( objectStatus "@baseboard_fab2_lib.baseboard_fab2(sch_1):m_l_dq(53)" )
			)
			( signal "M_L_DQ<54>"
				( objectStatus "@baseboard_fab2_lib.baseboard_fab2(sch_1):m_l_dq(54)" )
			)
			( signal "M_L_DQ<55>"
				( objectStatus "@baseboard_fab2_lib.baseboard_fab2(sch_1):m_l_dq(55)" )
			)
			( signal "M_L_DQ<56>"
				( objectStatus "@baseboard_fab2_lib.baseboard_fab2(sch_1):m_l_dq(56)" )
			)
			( signal "M_L_DQ<57>"
				( objectStatus "@baseboard_fab2_lib.baseboard_fab2(sch_1):m_l_dq(57)" )
			)
			( signal "M_L_DQ<58>"
				( objectStatus "@baseboard_fab2_lib.baseboard_fab2(sch_1):m_l_dq(58)" )
			)
			( signal "M_L_DQ<59>"
				( objectStatus "@baseboard_fab2_lib.baseboard_fab2(sch_1):m_l_dq(59)" )
			)
			( signal "M_L_DQ<60>"
				( objectStatus "@baseboard_fab2_lib.baseboard_fab2(sch_1):m_l_dq(60)" )
			)
			( signal "M_L_DQ<61>"
				( objectStatus "@baseboard_fab2_lib.baseboard_fab2(sch_1):m_l_dq(61)" )
			)
			( signal "M_L_DQ<62>"
				( objectStatus "@baseboard_fab2_lib.baseboard_fab2(sch_1):m_l_dq(62)" )
			)
			( signal "M_L_DQ<63>"
				( objectStatus "@baseboard_fab2_lib.baseboard_fab2(sch_1):m_l_dq(63)" )
			)
			( signal "M_L_DQS_DN<0>"
				( objectStatus "@baseboard_fab2_lib.baseboard_fab2(sch_1):m_l_dqs_dn(0)" )
			)
			( signal "M_L_DQS_DN<1>"
				( objectStatus "@baseboard_fab2_lib.baseboard_fab2(sch_1):m_l_dqs_dn(1)" )
			)
			( signal "M_L_DQS_DN<2>"
				( objectStatus "@baseboard_fab2_lib.baseboard_fab2(sch_1):m_l_dqs_dn(2)" )
			)
			( signal "M_L_DQS_DN<3>"
				( objectStatus "@baseboard_fab2_lib.baseboard_fab2(sch_1):m_l_dqs_dn(3)" )
			)
			( signal "M_L_DQS_DN<4>"
				( objectStatus "@baseboard_fab2_lib.baseboard_fab2(sch_1):m_l_dqs_dn(4)" )
			)
			( signal "M_L_DQS_DN<5>"
				( objectStatus "@baseboard_fab2_lib.baseboard_fab2(sch_1):m_l_dqs_dn(5)" )
			)
			( signal "M_L_DQS_DN<6>"
				( objectStatus "@baseboard_fab2_lib.baseboard_fab2(sch_1):m_l_dqs_dn(6)" )
			)
			( signal "M_L_DQS_DN<7>"
				( objectStatus "@baseboard_fab2_lib.baseboard_fab2(sch_1):m_l_dqs_dn(7)" )
			)
			( signal "M_L_DQS_DN<8>"
				( objectStatus "@baseboard_fab2_lib.baseboard_fab2(sch_1):m_l_dqs_dn(8)" )
			)
			( signal "M_L_DQS_DN<9>"
				( objectStatus "@baseboard_fab2_lib.baseboard_fab2(sch_1):m_l_dqs_dn(9)" )
			)
			( signal "M_L_DQS_DN<10>"
				( objectStatus "@baseboard_fab2_lib.baseboard_fab2(sch_1):m_l_dqs_dn(10)" )
			)
			( signal "M_L_DQS_DN<11>"
				( objectStatus "@baseboard_fab2_lib.baseboard_fab2(sch_1):m_l_dqs_dn(11)" )
			)
			( signal "M_L_DQS_DN<12>"
				( objectStatus "@baseboard_fab2_lib.baseboard_fab2(sch_1):m_l_dqs_dn(12)" )
			)
			( signal "M_L_DQS_DN<13>"
				( objectStatus "@baseboard_fab2_lib.baseboard_fab2(sch_1):m_l_dqs_dn(13)" )
			)
			( signal "M_L_DQS_DN<14>"
				( objectStatus "@baseboard_fab2_lib.baseboard_fab2(sch_1):m_l_dqs_dn(14)" )
			)
			( signal "M_L_DQS_DN<15>"
				( objectStatus "@baseboard_fab2_lib.baseboard_fab2(sch_1):m_l_dqs_dn(15)" )
			)
			( signal "M_L_DQS_DN<16>"
				( objectStatus "@baseboard_fab2_lib.baseboard_fab2(sch_1):m_l_dqs_dn(16)" )
			)
			( signal "M_L_DQS_DN<17>"
				( objectStatus "@baseboard_fab2_lib.baseboard_fab2(sch_1):m_l_dqs_dn(17)" )
			)
			( signal "M_L_DQS_DP<0>"
				( objectStatus "@baseboard_fab2_lib.baseboard_fab2(sch_1):m_l_dqs_dp(0)" )
			)
			( signal "M_L_DQS_DP<1>"
				( objectStatus "@baseboard_fab2_lib.baseboard_fab2(sch_1):m_l_dqs_dp(1)" )
			)
			( signal "M_L_DQS_DP<2>"
				( objectStatus "@baseboard_fab2_lib.baseboard_fab2(sch_1):m_l_dqs_dp(2)" )
			)
			( signal "M_L_DQS_DP<3>"
				( objectStatus "@baseboard_fab2_lib.baseboard_fab2(sch_1):m_l_dqs_dp(3)" )
			)
			( signal "M_L_DQS_DP<4>"
				( objectStatus "@baseboard_fab2_lib.baseboard_fab2(sch_1):m_l_dqs_dp(4)" )
			)
			( signal "M_L_DQS_DP<5>"
				( objectStatus "@baseboard_fab2_lib.baseboard_fab2(sch_1):m_l_dqs_dp(5)" )
			)
			( signal "M_L_DQS_DP<6>"
				( objectStatus "@baseboard_fab2_lib.baseboard_fab2(sch_1):m_l_dqs_dp(6)" )
			)
			( signal "M_L_DQS_DP<7>"
				( objectStatus "@baseboard_fab2_lib.baseboard_fab2(sch_1):m_l_dqs_dp(7)" )
			)
			( signal "M_L_DQS_DP<8>"
				( objectStatus "@baseboard_fab2_lib.baseboard_fab2(sch_1):m_l_dqs_dp(8)" )
			)
			( signal "M_L_DQS_DP<9>"
				( objectStatus "@baseboard_fab2_lib.baseboard_fab2(sch_1):m_l_dqs_dp(9)" )
			)
			( signal "M_L_DQS_DP<10>"
				( objectStatus "@baseboard_fab2_lib.baseboard_fab2(sch_1):m_l_dqs_dp(10)" )
			)
			( signal "M_L_DQS_DP<11>"
				( objectStatus "@baseboard_fab2_lib.baseboard_fab2(sch_1):m_l_dqs_dp(11)" )
			)
			( signal "M_L_DQS_DP<12>"
				( objectStatus "@baseboard_fab2_lib.baseboard_fab2(sch_1):m_l_dqs_dp(12)" )
			)
			( signal "M_L_DQS_DP<13>"
				( objectStatus "@baseboard_fab2_lib.baseboard_fab2(sch_1):m_l_dqs_dp(13)" )
			)
			( signal "M_L_DQS_DP<14>"
				( objectStatus "@baseboard_fab2_lib.baseboard_fab2(sch_1):m_l_dqs_dp(14)" )
			)
			( signal "M_L_DQS_DP<15>"
				( objectStatus "@baseboard_fab2_lib.baseboard_fab2(sch_1):m_l_dqs_dp(15)" )
			)
			( signal "M_L_DQS_DP<16>"
				( objectStatus "@baseboard_fab2_lib.baseboard_fab2(sch_1):m_l_dqs_dp(16)" )
			)
			( signal "M_L_DQS_DP<17>"
				( objectStatus "@baseboard_fab2_lib.baseboard_fab2(sch_1):m_l_dqs_dp(17)" )
			)
			( signal "M_L_ECC<0>"
				( objectStatus "@baseboard_fab2_lib.baseboard_fab2(sch_1):m_l_ecc(0)" )
			)
			( signal "M_L_ECC<1>"
				( objectStatus "@baseboard_fab2_lib.baseboard_fab2(sch_1):m_l_ecc(1)" )
			)
			( signal "M_L_ECC<2>"
				( objectStatus "@baseboard_fab2_lib.baseboard_fab2(sch_1):m_l_ecc(2)" )
			)
			( signal "M_L_ECC<3>"
				( objectStatus "@baseboard_fab2_lib.baseboard_fab2(sch_1):m_l_ecc(3)" )
			)
			( signal "M_L_ECC<4>"
				( objectStatus "@baseboard_fab2_lib.baseboard_fab2(sch_1):m_l_ecc(4)" )
			)
			( signal "M_L_ECC<5>"
				( objectStatus "@baseboard_fab2_lib.baseboard_fab2(sch_1):m_l_ecc(5)" )
			)
			( signal "M_L_ECC<6>"
				( objectStatus "@baseboard_fab2_lib.baseboard_fab2(sch_1):m_l_ecc(6)" )
			)
			( signal "M_L_ECC<7>"
				( objectStatus "@baseboard_fab2_lib.baseboard_fab2(sch_1):m_l_ecc(7)" )
			)
			( signal "M_L_MA<0>"
				( objectStatus "@baseboard_fab2_lib.baseboard_fab2(sch_1):m_l_ma(0)" )
			)
			( signal "M_L_MA<1>"
				( objectStatus "@baseboard_fab2_lib.baseboard_fab2(sch_1):m_l_ma(1)" )
			)
			( signal "M_L_MA<2>"
				( objectStatus "@baseboard_fab2_lib.baseboard_fab2(sch_1):m_l_ma(2)" )
			)
			( signal "M_L_MA<3>"
				( objectStatus "@baseboard_fab2_lib.baseboard_fab2(sch_1):m_l_ma(3)" )
			)
			( signal "M_L_MA<4>"
				( objectStatus "@baseboard_fab2_lib.baseboard_fab2(sch_1):m_l_ma(4)" )
			)
			( signal "M_L_MA<5>"
				( objectStatus "@baseboard_fab2_lib.baseboard_fab2(sch_1):m_l_ma(5)" )
			)
			( signal "M_L_MA<6>"
				( objectStatus "@baseboard_fab2_lib.baseboard_fab2(sch_1):m_l_ma(6)" )
			)
			( signal "M_L_MA<7>"
				( objectStatus "@baseboard_fab2_lib.baseboard_fab2(sch_1):m_l_ma(7)" )
			)
			( signal "M_L_MA<8>"
				( objectStatus "@baseboard_fab2_lib.baseboard_fab2(sch_1):m_l_ma(8)" )
			)
			( signal "M_L_MA<9>"
				( objectStatus "@baseboard_fab2_lib.baseboard_fab2(sch_1):m_l_ma(9)" )
			)
			( signal "M_L_MA<10>"
				( objectStatus "@baseboard_fab2_lib.baseboard_fab2(sch_1):m_l_ma(10)" )
			)
			( signal "M_L_MA<11>"
				( objectStatus "@baseboard_fab2_lib.baseboard_fab2(sch_1):m_l_ma(11)" )
			)
			( signal "M_L_MA<12>"
				( objectStatus "@baseboard_fab2_lib.baseboard_fab2(sch_1):m_l_ma(12)" )
			)
			( signal "M_L_MA<13>"
				( objectStatus "@baseboard_fab2_lib.baseboard_fab2(sch_1):m_l_ma(13)" )
			)
			( signal "M_L_MA<14>"
				( objectStatus "@baseboard_fab2_lib.baseboard_fab2(sch_1):m_l_ma(14)" )
			)
			( signal "M_L_MA<15>"
				( objectStatus "@baseboard_fab2_lib.baseboard_fab2(sch_1):m_l_ma(15)" )
			)
			( signal "M_L_MA<16>"
				( objectStatus "@baseboard_fab2_lib.baseboard_fab2(sch_1):m_l_ma(16)" )
			)
			( signal "M_L_MA<17>"
				( objectStatus "@baseboard_fab2_lib.baseboard_fab2(sch_1):m_l_ma(17)" )
			)
			( signal "M_L_ODT<0>"
				( objectStatus "@baseboard_fab2_lib.baseboard_fab2(sch_1):m_l_odt(0)" )
			)
			( signal "M_L_ODT<1>"
				( objectStatus "@baseboard_fab2_lib.baseboard_fab2(sch_1):m_l_odt(1)" )
			)
			( signal "M_L_ODT<2>"
				( objectStatus "@baseboard_fab2_lib.baseboard_fab2(sch_1):m_l_odt(2)" )
			)
			( signal "M_L_ODT<3>"
				( objectStatus "@baseboard_fab2_lib.baseboard_fab2(sch_1):m_l_odt(3)" )
			)
			( signal "M_L_PAR"
				( objectStatus "@baseboard_fab2_lib.baseboard_fab2(sch_1):m_l_par" )
			)
			( signal "M_M_ACT_N"
				( objectStatus "@baseboard_fab2_lib.baseboard_fab2(sch_1):m_m_act_n" )
			)
			( signal "M_M_ALERT_N"
				( objectStatus "@baseboard_fab2_lib.baseboard_fab2(sch_1):m_m_alert_n" )
			)
			( signal "M_M_BA<0>"
				( objectStatus "@baseboard_fab2_lib.baseboard_fab2(sch_1):m_m_ba(0)" )
			)
			( signal "M_M_BA<1>"
				( objectStatus "@baseboard_fab2_lib.baseboard_fab2(sch_1):m_m_ba(1)" )
			)
			( signal "M_M_BG<0>"
				( objectStatus "@baseboard_fab2_lib.baseboard_fab2(sch_1):m_m_bg(0)" )
			)
			( signal "M_M_BG<1>"
				( objectStatus "@baseboard_fab2_lib.baseboard_fab2(sch_1):m_m_bg(1)" )
			)
			( signal "M_M_C<2>"
				( objectStatus "@baseboard_fab2_lib.baseboard_fab2(sch_1):m_m_c(2)" )
			)
			( signal "M_M_CKE<0>"
				( objectStatus "@baseboard_fab2_lib.baseboard_fab2(sch_1):m_m_cke(0)" )
			)
			( signal "M_M_CKE<1>"
				( objectStatus "@baseboard_fab2_lib.baseboard_fab2(sch_1):m_m_cke(1)" )
			)
			( signal "M_M_CKE<2>"
				( objectStatus "@baseboard_fab2_lib.baseboard_fab2(sch_1):m_m_cke(2)" )
			)
			( signal "M_M_CKE<3>"
				( objectStatus "@baseboard_fab2_lib.baseboard_fab2(sch_1):m_m_cke(3)" )
			)
			( signal "M_M_CLK_DN<0>"
				( objectStatus "@baseboard_fab2_lib.baseboard_fab2(sch_1):m_m_clk_dn(0)" )
			)
			( signal "M_M_CLK_DN<1>"
				( objectStatus "@baseboard_fab2_lib.baseboard_fab2(sch_1):m_m_clk_dn(1)" )
			)
			( signal "M_M_CLK_DN<2>"
				( objectStatus "@baseboard_fab2_lib.baseboard_fab2(sch_1):m_m_clk_dn(2)" )
			)
			( signal "M_M_CLK_DN<3>"
				( objectStatus "@baseboard_fab2_lib.baseboard_fab2(sch_1):m_m_clk_dn(3)" )
			)
			( signal "M_M_CLK_DP<0>"
				( objectStatus "@baseboard_fab2_lib.baseboard_fab2(sch_1):m_m_clk_dp(0)" )
			)
			( signal "M_M_CLK_DP<1>"
				( objectStatus "@baseboard_fab2_lib.baseboard_fab2(sch_1):m_m_clk_dp(1)" )
			)
			( signal "M_M_CLK_DP<2>"
				( objectStatus "@baseboard_fab2_lib.baseboard_fab2(sch_1):m_m_clk_dp(2)" )
			)
			( signal "M_M_CLK_DP<3>"
				( objectStatus "@baseboard_fab2_lib.baseboard_fab2(sch_1):m_m_clk_dp(3)" )
			)
			( signal "M_M_CS_N<0>"
				( objectStatus "@baseboard_fab2_lib.baseboard_fab2(sch_1):m_m_cs_n(0)" )
			)
			( signal "M_M_CS_N<1>"
				( objectStatus "@baseboard_fab2_lib.baseboard_fab2(sch_1):m_m_cs_n(1)" )
			)
			( signal "M_M_CS_N<2>"
				( objectStatus "@baseboard_fab2_lib.baseboard_fab2(sch_1):m_m_cs_n(2)" )
			)
			( signal "M_M_CS_N<3>"
				( objectStatus "@baseboard_fab2_lib.baseboard_fab2(sch_1):m_m_cs_n(3)" )
			)
			( signal "M_M_CS_N<4>"
				( objectStatus "@baseboard_fab2_lib.baseboard_fab2(sch_1):m_m_cs_n(4)" )
			)
			( signal "M_M_CS_N<5>"
				( objectStatus "@baseboard_fab2_lib.baseboard_fab2(sch_1):m_m_cs_n(5)" )
			)
			( signal "M_M_CS_N<6>"
				( objectStatus "@baseboard_fab2_lib.baseboard_fab2(sch_1):m_m_cs_n(6)" )
			)
			( signal "M_M_CS_N<7>"
				( objectStatus "@baseboard_fab2_lib.baseboard_fab2(sch_1):m_m_cs_n(7)" )
			)
			( signal "M_M_DQ<0>"
				( objectStatus "@baseboard_fab2_lib.baseboard_fab2(sch_1):m_m_dq(0)" )
			)
			( signal "M_M_DQ<1>"
				( objectStatus "@baseboard_fab2_lib.baseboard_fab2(sch_1):m_m_dq(1)" )
			)
			( signal "M_M_DQ<2>"
				( objectStatus "@baseboard_fab2_lib.baseboard_fab2(sch_1):m_m_dq(2)" )
			)
			( signal "M_M_DQ<3>"
				( objectStatus "@baseboard_fab2_lib.baseboard_fab2(sch_1):m_m_dq(3)" )
			)
			( signal "M_M_DQ<4>"
				( objectStatus "@baseboard_fab2_lib.baseboard_fab2(sch_1):m_m_dq(4)" )
			)
			( signal "M_M_DQ<5>"
				( objectStatus "@baseboard_fab2_lib.baseboard_fab2(sch_1):m_m_dq(5)" )
			)
			( signal "M_M_DQ<6>"
				( objectStatus "@baseboard_fab2_lib.baseboard_fab2(sch_1):m_m_dq(6)" )
			)
			( signal "M_M_DQ<7>"
				( objectStatus "@baseboard_fab2_lib.baseboard_fab2(sch_1):m_m_dq(7)" )
			)
			( signal "M_M_DQ<8>"
				( objectStatus "@baseboard_fab2_lib.baseboard_fab2(sch_1):m_m_dq(8)" )
			)
			( signal "M_M_DQ<9>"
				( objectStatus "@baseboard_fab2_lib.baseboard_fab2(sch_1):m_m_dq(9)" )
			)
			( signal "M_M_DQ<10>"
				( objectStatus "@baseboard_fab2_lib.baseboard_fab2(sch_1):m_m_dq(10)" )
			)
			( signal "M_M_DQ<11>"
				( objectStatus "@baseboard_fab2_lib.baseboard_fab2(sch_1):m_m_dq(11)" )
			)
			( signal "M_M_DQ<12>"
				( objectStatus "@baseboard_fab2_lib.baseboard_fab2(sch_1):m_m_dq(12)" )
			)
			( signal "M_M_DQ<13>"
				( objectStatus "@baseboard_fab2_lib.baseboard_fab2(sch_1):m_m_dq(13)" )
			)
			( signal "M_M_DQ<14>"
				( objectStatus "@baseboard_fab2_lib.baseboard_fab2(sch_1):m_m_dq(14)" )
			)
			( signal "M_M_DQ<15>"
				( objectStatus "@baseboard_fab2_lib.baseboard_fab2(sch_1):m_m_dq(15)" )
			)
			( signal "M_M_DQ<16>"
				( objectStatus "@baseboard_fab2_lib.baseboard_fab2(sch_1):m_m_dq(16)" )
			)
			( signal "M_M_DQ<17>"
				( objectStatus "@baseboard_fab2_lib.baseboard_fab2(sch_1):m_m_dq(17)" )
			)
			( signal "M_M_DQ<18>"
				( objectStatus "@baseboard_fab2_lib.baseboard_fab2(sch_1):m_m_dq(18)" )
			)
			( signal "M_M_DQ<19>"
				( objectStatus "@baseboard_fab2_lib.baseboard_fab2(sch_1):m_m_dq(19)" )
			)
			( signal "M_M_DQ<20>"
				( objectStatus "@baseboard_fab2_lib.baseboard_fab2(sch_1):m_m_dq(20)" )
			)
			( signal "M_M_DQ<21>"
				( objectStatus "@baseboard_fab2_lib.baseboard_fab2(sch_1):m_m_dq(21)" )
			)
			( signal "M_M_DQ<22>"
				( objectStatus "@baseboard_fab2_lib.baseboard_fab2(sch_1):m_m_dq(22)" )
			)
			( signal "M_M_DQ<23>"
				( objectStatus "@baseboard_fab2_lib.baseboard_fab2(sch_1):m_m_dq(23)" )
			)
			( signal "M_M_DQ<24>"
				( objectStatus "@baseboard_fab2_lib.baseboard_fab2(sch_1):m_m_dq(24)" )
			)
			( signal "M_M_DQ<25>"
				( objectStatus "@baseboard_fab2_lib.baseboard_fab2(sch_1):m_m_dq(25)" )
			)
			( signal "M_M_DQ<26>"
				( objectStatus "@baseboard_fab2_lib.baseboard_fab2(sch_1):m_m_dq(26)" )
			)
			( signal "M_M_DQ<27>"
				( objectStatus "@baseboard_fab2_lib.baseboard_fab2(sch_1):m_m_dq(27)" )
			)
			( signal "M_M_DQ<28>"
				( objectStatus "@baseboard_fab2_lib.baseboard_fab2(sch_1):m_m_dq(28)" )
			)
			( signal "M_M_DQ<29>"
				( objectStatus "@baseboard_fab2_lib.baseboard_fab2(sch_1):m_m_dq(29)" )
			)
			( signal "M_M_DQ<30>"
				( objectStatus "@baseboard_fab2_lib.baseboard_fab2(sch_1):m_m_dq(30)" )
			)
			( signal "M_M_DQ<31>"
				( objectStatus "@baseboard_fab2_lib.baseboard_fab2(sch_1):m_m_dq(31)" )
			)
			( signal "M_M_DQ<32>"
				( objectStatus "@baseboard_fab2_lib.baseboard_fab2(sch_1):m_m_dq(32)" )
			)
			( signal "M_M_DQ<33>"
				( objectStatus "@baseboard_fab2_lib.baseboard_fab2(sch_1):m_m_dq(33)" )
			)
			( signal "M_M_DQ<34>"
				( objectStatus "@baseboard_fab2_lib.baseboard_fab2(sch_1):m_m_dq(34)" )
			)
			( signal "M_M_DQ<35>"
				( objectStatus "@baseboard_fab2_lib.baseboard_fab2(sch_1):m_m_dq(35)" )
			)
			( signal "M_M_DQ<36>"
				( objectStatus "@baseboard_fab2_lib.baseboard_fab2(sch_1):m_m_dq(36)" )
			)
			( signal "M_M_DQ<37>"
				( objectStatus "@baseboard_fab2_lib.baseboard_fab2(sch_1):m_m_dq(37)" )
			)
			( signal "M_M_DQ<38>"
				( objectStatus "@baseboard_fab2_lib.baseboard_fab2(sch_1):m_m_dq(38)" )
			)
			( signal "M_M_DQ<39>"
				( objectStatus "@baseboard_fab2_lib.baseboard_fab2(sch_1):m_m_dq(39)" )
			)
			( signal "M_M_DQ<40>"
				( objectStatus "@baseboard_fab2_lib.baseboard_fab2(sch_1):m_m_dq(40)" )
			)
			( signal "M_M_DQ<41>"
				( objectStatus "@baseboard_fab2_lib.baseboard_fab2(sch_1):m_m_dq(41)" )
			)
			( signal "M_M_DQ<42>"
				( objectStatus "@baseboard_fab2_lib.baseboard_fab2(sch_1):m_m_dq(42)" )
			)
			( signal "M_M_DQ<43>"
				( objectStatus "@baseboard_fab2_lib.baseboard_fab2(sch_1):m_m_dq(43)" )
			)
			( signal "M_M_DQ<44>"
				( objectStatus "@baseboard_fab2_lib.baseboard_fab2(sch_1):m_m_dq(44)" )
			)
			( signal "M_M_DQ<45>"
				( objectStatus "@baseboard_fab2_lib.baseboard_fab2(sch_1):m_m_dq(45)" )
			)
			( signal "M_M_DQ<46>"
				( objectStatus "@baseboard_fab2_lib.baseboard_fab2(sch_1):m_m_dq(46)" )
			)
			( signal "M_M_DQ<47>"
				( objectStatus "@baseboard_fab2_lib.baseboard_fab2(sch_1):m_m_dq(47)" )
			)
			( signal "M_M_DQ<48>"
				( objectStatus "@baseboard_fab2_lib.baseboard_fab2(sch_1):m_m_dq(48)" )
			)
			( signal "M_M_DQ<49>"
				( objectStatus "@baseboard_fab2_lib.baseboard_fab2(sch_1):m_m_dq(49)" )
			)
			( signal "M_M_DQ<50>"
				( objectStatus "@baseboard_fab2_lib.baseboard_fab2(sch_1):m_m_dq(50)" )
			)
			( signal "M_M_DQ<51>"
				( objectStatus "@baseboard_fab2_lib.baseboard_fab2(sch_1):m_m_dq(51)" )
			)
			( signal "M_M_DQ<52>"
				( objectStatus "@baseboard_fab2_lib.baseboard_fab2(sch_1):m_m_dq(52)" )
			)
			( signal "M_M_DQ<53>"
				( objectStatus "@baseboard_fab2_lib.baseboard_fab2(sch_1):m_m_dq(53)" )
			)
			( signal "M_M_DQ<54>"
				( objectStatus "@baseboard_fab2_lib.baseboard_fab2(sch_1):m_m_dq(54)" )
			)
			( signal "M_M_DQ<55>"
				( objectStatus "@baseboard_fab2_lib.baseboard_fab2(sch_1):m_m_dq(55)" )
			)
			( signal "M_M_DQ<56>"
				( objectStatus "@baseboard_fab2_lib.baseboard_fab2(sch_1):m_m_dq(56)" )
			)
			( signal "M_M_DQ<57>"
				( objectStatus "@baseboard_fab2_lib.baseboard_fab2(sch_1):m_m_dq(57)" )
			)
			( signal "M_M_DQ<58>"
				( objectStatus "@baseboard_fab2_lib.baseboard_fab2(sch_1):m_m_dq(58)" )
			)
			( signal "M_M_DQ<59>"
				( objectStatus "@baseboard_fab2_lib.baseboard_fab2(sch_1):m_m_dq(59)" )
			)
			( signal "M_M_DQ<60>"
				( objectStatus "@baseboard_fab2_lib.baseboard_fab2(sch_1):m_m_dq(60)" )
			)
			( signal "M_M_DQ<61>"
				( objectStatus "@baseboard_fab2_lib.baseboard_fab2(sch_1):m_m_dq(61)" )
			)
			( signal "M_M_DQ<62>"
				( objectStatus "@baseboard_fab2_lib.baseboard_fab2(sch_1):m_m_dq(62)" )
			)
			( signal "M_M_DQ<63>"
				( objectStatus "@baseboard_fab2_lib.baseboard_fab2(sch_1):m_m_dq(63)" )
			)
			( signal "M_M_DQS_DN<0>"
				( objectStatus "@baseboard_fab2_lib.baseboard_fab2(sch_1):m_m_dqs_dn(0)" )
			)
			( signal "M_M_DQS_DN<1>"
				( objectStatus "@baseboard_fab2_lib.baseboard_fab2(sch_1):m_m_dqs_dn(1)" )
			)
			( signal "M_M_DQS_DN<2>"
				( objectStatus "@baseboard_fab2_lib.baseboard_fab2(sch_1):m_m_dqs_dn(2)" )
			)
			( signal "M_M_DQS_DN<3>"
				( objectStatus "@baseboard_fab2_lib.baseboard_fab2(sch_1):m_m_dqs_dn(3)" )
			)
			( signal "M_M_DQS_DN<4>"
				( objectStatus "@baseboard_fab2_lib.baseboard_fab2(sch_1):m_m_dqs_dn(4)" )
			)
			( signal "M_M_DQS_DN<5>"
				( objectStatus "@baseboard_fab2_lib.baseboard_fab2(sch_1):m_m_dqs_dn(5)" )
			)
			( signal "M_M_DQS_DN<6>"
				( objectStatus "@baseboard_fab2_lib.baseboard_fab2(sch_1):m_m_dqs_dn(6)" )
			)
			( signal "M_M_DQS_DN<7>"
				( objectStatus "@baseboard_fab2_lib.baseboard_fab2(sch_1):m_m_dqs_dn(7)" )
			)
			( signal "M_M_DQS_DN<8>"
				( objectStatus "@baseboard_fab2_lib.baseboard_fab2(sch_1):m_m_dqs_dn(8)" )
			)
			( signal "M_M_DQS_DN<9>"
				( objectStatus "@baseboard_fab2_lib.baseboard_fab2(sch_1):m_m_dqs_dn(9)" )
			)
			( signal "M_M_DQS_DN<10>"
				( objectStatus "@baseboard_fab2_lib.baseboard_fab2(sch_1):m_m_dqs_dn(10)" )
			)
			( signal "M_M_DQS_DN<11>"
				( objectStatus "@baseboard_fab2_lib.baseboard_fab2(sch_1):m_m_dqs_dn(11)" )
			)
			( signal "M_M_DQS_DN<12>"
				( objectStatus "@baseboard_fab2_lib.baseboard_fab2(sch_1):m_m_dqs_dn(12)" )
			)
			( signal "M_M_DQS_DN<13>"
				( objectStatus "@baseboard_fab2_lib.baseboard_fab2(sch_1):m_m_dqs_dn(13)" )
			)
			( signal "M_M_DQS_DN<14>"
				( objectStatus "@baseboard_fab2_lib.baseboard_fab2(sch_1):m_m_dqs_dn(14)" )
			)
			( signal "M_M_DQS_DN<15>"
				( objectStatus "@baseboard_fab2_lib.baseboard_fab2(sch_1):m_m_dqs_dn(15)" )
			)
			( signal "M_M_DQS_DN<16>"
				( objectStatus "@baseboard_fab2_lib.baseboard_fab2(sch_1):m_m_dqs_dn(16)" )
			)
			( signal "M_M_DQS_DN<17>"
				( objectStatus "@baseboard_fab2_lib.baseboard_fab2(sch_1):m_m_dqs_dn(17)" )
			)
			( signal "M_M_DQS_DP<0>"
				( objectStatus "@baseboard_fab2_lib.baseboard_fab2(sch_1):m_m_dqs_dp(0)" )
			)
			( signal "M_M_DQS_DP<1>"
				( objectStatus "@baseboard_fab2_lib.baseboard_fab2(sch_1):m_m_dqs_dp(1)" )
			)
			( signal "M_M_DQS_DP<2>"
				( objectStatus "@baseboard_fab2_lib.baseboard_fab2(sch_1):m_m_dqs_dp(2)" )
			)
			( signal "M_M_DQS_DP<3>"
				( objectStatus "@baseboard_fab2_lib.baseboard_fab2(sch_1):m_m_dqs_dp(3)" )
			)
			( signal "M_M_DQS_DP<4>"
				( objectStatus "@baseboard_fab2_lib.baseboard_fab2(sch_1):m_m_dqs_dp(4)" )
			)
			( signal "M_M_DQS_DP<5>"
				( objectStatus "@baseboard_fab2_lib.baseboard_fab2(sch_1):m_m_dqs_dp(5)" )
			)
			( signal "M_M_DQS_DP<6>"
				( objectStatus "@baseboard_fab2_lib.baseboard_fab2(sch_1):m_m_dqs_dp(6)" )
			)
			( signal "M_M_DQS_DP<7>"
				( objectStatus "@baseboard_fab2_lib.baseboard_fab2(sch_1):m_m_dqs_dp(7)" )
			)
			( signal "M_M_DQS_DP<8>"
				( objectStatus "@baseboard_fab2_lib.baseboard_fab2(sch_1):m_m_dqs_dp(8)" )
			)
			( signal "M_M_DQS_DP<9>"
				( objectStatus "@baseboard_fab2_lib.baseboard_fab2(sch_1):m_m_dqs_dp(9)" )
			)
			( signal "M_M_DQS_DP<10>"
				( objectStatus "@baseboard_fab2_lib.baseboard_fab2(sch_1):m_m_dqs_dp(10)" )
			)
			( signal "M_M_DQS_DP<11>"
				( objectStatus "@baseboard_fab2_lib.baseboard_fab2(sch_1):m_m_dqs_dp(11)" )
			)
			( signal "M_M_DQS_DP<12>"
				( objectStatus "@baseboard_fab2_lib.baseboard_fab2(sch_1):m_m_dqs_dp(12)" )
			)
			( signal "M_M_DQS_DP<13>"
				( objectStatus "@baseboard_fab2_lib.baseboard_fab2(sch_1):m_m_dqs_dp(13)" )
			)
			( signal "M_M_DQS_DP<14>"
				( objectStatus "@baseboard_fab2_lib.baseboard_fab2(sch_1):m_m_dqs_dp(14)" )
			)
			( signal "M_M_DQS_DP<15>"
				( objectStatus "@baseboard_fab2_lib.baseboard_fab2(sch_1):m_m_dqs_dp(15)" )
			)
			( signal "M_M_DQS_DP<16>"
				( objectStatus "@baseboard_fab2_lib.baseboard_fab2(sch_1):m_m_dqs_dp(16)" )
			)
			( signal "M_M_DQS_DP<17>"
				( objectStatus "@baseboard_fab2_lib.baseboard_fab2(sch_1):m_m_dqs_dp(17)" )
			)
			( signal "M_M_ECC<0>"
				( objectStatus "@baseboard_fab2_lib.baseboard_fab2(sch_1):m_m_ecc(0)" )
			)
			( signal "M_M_ECC<1>"
				( objectStatus "@baseboard_fab2_lib.baseboard_fab2(sch_1):m_m_ecc(1)" )
			)
			( signal "M_M_ECC<2>"
				( objectStatus "@baseboard_fab2_lib.baseboard_fab2(sch_1):m_m_ecc(2)" )
			)
			( signal "M_M_ECC<3>"
				( objectStatus "@baseboard_fab2_lib.baseboard_fab2(sch_1):m_m_ecc(3)" )
			)
			( signal "M_M_ECC<4>"
				( objectStatus "@baseboard_fab2_lib.baseboard_fab2(sch_1):m_m_ecc(4)" )
			)
			( signal "M_M_ECC<5>"
				( objectStatus "@baseboard_fab2_lib.baseboard_fab2(sch_1):m_m_ecc(5)" )
			)
			( signal "M_M_ECC<6>"
				( objectStatus "@baseboard_fab2_lib.baseboard_fab2(sch_1):m_m_ecc(6)" )
			)
			( signal "M_M_ECC<7>"
				( objectStatus "@baseboard_fab2_lib.baseboard_fab2(sch_1):m_m_ecc(7)" )
			)
			( signal "M_M_MA<0>"
				( objectStatus "@baseboard_fab2_lib.baseboard_fab2(sch_1):m_m_ma(0)" )
			)
			( signal "M_M_MA<1>"
				( objectStatus "@baseboard_fab2_lib.baseboard_fab2(sch_1):m_m_ma(1)" )
			)
			( signal "M_M_MA<2>"
				( objectStatus "@baseboard_fab2_lib.baseboard_fab2(sch_1):m_m_ma(2)" )
			)
			( signal "M_M_MA<3>"
				( objectStatus "@baseboard_fab2_lib.baseboard_fab2(sch_1):m_m_ma(3)" )
			)
			( signal "M_M_MA<4>"
				( objectStatus "@baseboard_fab2_lib.baseboard_fab2(sch_1):m_m_ma(4)" )
			)
			( signal "M_M_MA<5>"
				( objectStatus "@baseboard_fab2_lib.baseboard_fab2(sch_1):m_m_ma(5)" )
			)
			( signal "M_M_MA<6>"
				( objectStatus "@baseboard_fab2_lib.baseboard_fab2(sch_1):m_m_ma(6)" )
			)
			( signal "M_M_MA<7>"
				( objectStatus "@baseboard_fab2_lib.baseboard_fab2(sch_1):m_m_ma(7)" )
			)
			( signal "M_M_MA<8>"
				( objectStatus "@baseboard_fab2_lib.baseboard_fab2(sch_1):m_m_ma(8)" )
			)
			( signal "M_M_MA<9>"
				( objectStatus "@baseboard_fab2_lib.baseboard_fab2(sch_1):m_m_ma(9)" )
			)
			( signal "M_M_MA<10>"
				( objectStatus "@baseboard_fab2_lib.baseboard_fab2(sch_1):m_m_ma(10)" )
			)
			( signal "M_M_MA<11>"
				( objectStatus "@baseboard_fab2_lib.baseboard_fab2(sch_1):m_m_ma(11)" )
			)
			( signal "M_M_MA<12>"
				( objectStatus "@baseboard_fab2_lib.baseboard_fab2(sch_1):m_m_ma(12)" )
			)
			( signal "M_M_MA<13>"
				( objectStatus "@baseboard_fab2_lib.baseboard_fab2(sch_1):m_m_ma(13)" )
			)
			( signal "M_M_MA<14>"
				( objectStatus "@baseboard_fab2_lib.baseboard_fab2(sch_1):m_m_ma(14)" )
			)
			( signal "M_M_MA<15>"
				( objectStatus "@baseboard_fab2_lib.baseboard_fab2(sch_1):m_m_ma(15)" )
			)
			( signal "M_M_MA<16>"
				( objectStatus "@baseboard_fab2_lib.baseboard_fab2(sch_1):m_m_ma(16)" )
			)
			( signal "M_M_MA<17>"
				( objectStatus "@baseboard_fab2_lib.baseboard_fab2(sch_1):m_m_ma(17)" )
			)
			( signal "M_M_ODT<0>"
				( objectStatus "@baseboard_fab2_lib.baseboard_fab2(sch_1):m_m_odt(0)" )
			)
			( signal "M_M_ODT<1>"
				( objectStatus "@baseboard_fab2_lib.baseboard_fab2(sch_1):m_m_odt(1)" )
			)
			( signal "M_M_ODT<2>"
				( objectStatus "@baseboard_fab2_lib.baseboard_fab2(sch_1):m_m_odt(2)" )
			)
			( signal "M_M_ODT<3>"
				( objectStatus "@baseboard_fab2_lib.baseboard_fab2(sch_1):m_m_odt(3)" )
			)
			( signal "M_M_PAR"
				( objectStatus "@baseboard_fab2_lib.baseboard_fab2(sch_1):m_m_par" )
			)
			( signal "CLK_100M_CPU1_PE_REFCLK_DN"
				( objectStatus "@baseboard_fab2_lib.baseboard_fab2(sch_1):clk_100m_cpu1_pe_refclk_dn" )
			)
			( signal "CLK_100M_CPU1_PE_REFCLK_DP"
				( objectStatus "@baseboard_fab2_lib.baseboard_fab2(sch_1):clk_100m_cpu1_pe_refclk_dp" )
			)
			( signal "CLK_156M_OSC_CPU1_HFI_DN"
				( objectStatus "@baseboard_fab2_lib.baseboard_fab2(sch_1):clk_156m_osc_cpu1_hfi_dn" )
			)
			( signal "CLK_156M_OSC_CPU1_HFI_DP"
				( objectStatus "@baseboard_fab2_lib.baseboard_fab2(sch_1):clk_156m_osc_cpu1_hfi_dp" )
			)
			( signal "JTAG_MCP_CPU1_TDI"
				( objectStatus "@baseboard_fab2_lib.baseboard_fab2(sch_1):jtag_mcp_cpu1_tdi" )
			)
			( signal "JTAG_MCP_CPU1_TDO"
				( objectStatus "@baseboard_fab2_lib.baseboard_fab2(sch_1):jtag_mcp_cpu1_tdo" )
			)
			( signal "RST_CD_CPU1_POR_N"
				( objectStatus "@baseboard_fab2_lib.baseboard_fab2(sch_1):rst_cd_cpu1_por_n" )
			)
			( signal "TP_CD_HFI1_CPU1_I2CDAT"
				( objectStatus "@baseboard_fab2_lib.baseboard_fab2(sch_1):tp_cd_hfi1_cpu1_i2cdat" )
			)
			( signal "TP_CD_HFI1_CPU1_I2CLK"
				( objectStatus "@baseboard_fab2_lib.baseboard_fab2(sch_1):tp_cd_hfi1_cpu1_i2clk" )
			)
			( signal "TP_CD_HFI1_CPU1_INT_N"
				( objectStatus "@baseboard_fab2_lib.baseboard_fab2(sch_1):tp_cd_hfi1_cpu1_int_n" )
			)
			( signal "TP_CD_HFI1_CPU1_LED_N"
				( objectStatus "@baseboard_fab2_lib.baseboard_fab2(sch_1):tp_cd_hfi1_cpu1_led_n" )
			)
			( signal "TP_CD_HFI1_CPU1_MODPRST_N"
				( objectStatus "@baseboard_fab2_lib.baseboard_fab2(sch_1):tp_cd_hfi1_cpu1_modprst_n" )
			)
			( signal "TP_CD_HFI1_CPU1_RESET_N"
				( objectStatus "@baseboard_fab2_lib.baseboard_fab2(sch_1):tp_cd_hfi1_cpu1_reset_n" )
			)
			( signal "TP_CPU1_DMI_RX_DN0"
				( objectStatus "@baseboard_fab2_lib.baseboard_fab2(sch_1):tp_cpu1_dmi_rx_dn0" )
			)
			( signal "TP_CPU1_DMI_RX_DN1"
				( objectStatus "@baseboard_fab2_lib.baseboard_fab2(sch_1):tp_cpu1_dmi_rx_dn1" )
			)
			( signal "TP_CPU1_DMI_RX_DN2"
				( objectStatus "@baseboard_fab2_lib.baseboard_fab2(sch_1):tp_cpu1_dmi_rx_dn2" )
			)
			( signal "TP_CPU1_DMI_RX_DN3"
				( objectStatus "@baseboard_fab2_lib.baseboard_fab2(sch_1):tp_cpu1_dmi_rx_dn3" )
			)
			( signal "TP_CPU1_DMI_RX_DP0"
				( objectStatus "@baseboard_fab2_lib.baseboard_fab2(sch_1):tp_cpu1_dmi_rx_dp0" )
			)
			( signal "TP_CPU1_DMI_RX_DP1"
				( objectStatus "@baseboard_fab2_lib.baseboard_fab2(sch_1):tp_cpu1_dmi_rx_dp1" )
			)
			( signal "TP_CPU1_DMI_RX_DP2"
				( objectStatus "@baseboard_fab2_lib.baseboard_fab2(sch_1):tp_cpu1_dmi_rx_dp2" )
			)
			( signal "TP_CPU1_DMI_RX_DP3"
				( objectStatus "@baseboard_fab2_lib.baseboard_fab2(sch_1):tp_cpu1_dmi_rx_dp3" )
			)
			( signal "TP_CPU1_DMI_TX_DN0"
				( objectStatus "@baseboard_fab2_lib.baseboard_fab2(sch_1):tp_cpu1_dmi_tx_dn0" )
			)
			( signal "TP_CPU1_DMI_TX_DN1"
				( objectStatus "@baseboard_fab2_lib.baseboard_fab2(sch_1):tp_cpu1_dmi_tx_dn1" )
			)
			( signal "TP_CPU1_DMI_TX_DN2"
				( objectStatus "@baseboard_fab2_lib.baseboard_fab2(sch_1):tp_cpu1_dmi_tx_dn2" )
			)
			( signal "TP_CPU1_DMI_TX_DN3"
				( objectStatus "@baseboard_fab2_lib.baseboard_fab2(sch_1):tp_cpu1_dmi_tx_dn3" )
			)
			( signal "TP_CPU1_DMI_TX_DP0"
				( objectStatus "@baseboard_fab2_lib.baseboard_fab2(sch_1):tp_cpu1_dmi_tx_dp0" )
			)
			( signal "TP_CPU1_DMI_TX_DP1"
				( objectStatus "@baseboard_fab2_lib.baseboard_fab2(sch_1):tp_cpu1_dmi_tx_dp1" )
			)
			( signal "TP_CPU1_DMI_TX_DP2"
				( objectStatus "@baseboard_fab2_lib.baseboard_fab2(sch_1):tp_cpu1_dmi_tx_dp2" )
			)
			( signal "TP_CPU1_DMI_TX_DP3"
				( objectStatus "@baseboard_fab2_lib.baseboard_fab2(sch_1):tp_cpu1_dmi_tx_dp3" )
			)
			( signal "TP_CPU1_RSVD_172"
				( objectStatus "@baseboard_fab2_lib.baseboard_fab2(sch_1):tp_cpu1_rsvd_172" )
			)
			( signal "TP_CPU1_RSVD_173"
				( objectStatus "@baseboard_fab2_lib.baseboard_fab2(sch_1):tp_cpu1_rsvd_173" )
			)
			( signal "TP_CPU1_RSVD_174"
				( objectStatus "@baseboard_fab2_lib.baseboard_fab2(sch_1):tp_cpu1_rsvd_174" )
			)
			( signal "TP_CPU1_RSVD_175"
				( objectStatus "@baseboard_fab2_lib.baseboard_fab2(sch_1):tp_cpu1_rsvd_175" )
			)
			( signal "TP_CPU1_RSVD_176"
				( objectStatus "@baseboard_fab2_lib.baseboard_fab2(sch_1):tp_cpu1_rsvd_176" )
			)
			( signal "TP_CPU1_RSVD_177"
				( objectStatus "@baseboard_fab2_lib.baseboard_fab2(sch_1):tp_cpu1_rsvd_177" )
			)
			( signal "TP_CPU1_RSVD_178"
				( objectStatus "@baseboard_fab2_lib.baseboard_fab2(sch_1):tp_cpu1_rsvd_178" )
			)
			( signal "TP_CPU1_RSVD_179"
				( objectStatus "@baseboard_fab2_lib.baseboard_fab2(sch_1):tp_cpu1_rsvd_179" )
			)
			( signal "TP_CPU1_RSVD_180"
				( objectStatus "@baseboard_fab2_lib.baseboard_fab2(sch_1):tp_cpu1_rsvd_180" )
			)
			( signal "TP_CPU1_RSVD_181"
				( objectStatus "@baseboard_fab2_lib.baseboard_fab2(sch_1):tp_cpu1_rsvd_181" )
			)
			( signal "TP_CPU1_RSVD_182"
				( objectStatus "@baseboard_fab2_lib.baseboard_fab2(sch_1):tp_cpu1_rsvd_182" )
			)
			( signal "TP_CPU1_RSVD_183"
				( objectStatus "@baseboard_fab2_lib.baseboard_fab2(sch_1):tp_cpu1_rsvd_183" )
			)
			( signal "TP_CPU1_RSVD_184"
				( objectStatus "@baseboard_fab2_lib.baseboard_fab2(sch_1):tp_cpu1_rsvd_184" )
			)
			( signal "TP_CPU1_RSVD_186"
				( objectStatus "@baseboard_fab2_lib.baseboard_fab2(sch_1):tp_cpu1_rsvd_186" )
			)
			( signal "TP_CPU1_RSVD_189"
				( objectStatus "@baseboard_fab2_lib.baseboard_fab2(sch_1):tp_cpu1_rsvd_189" )
			)
			( signal "TP_CPU1_RSVD_190"
				( objectStatus "@baseboard_fab2_lib.baseboard_fab2(sch_1):tp_cpu1_rsvd_190" )
			)
			( signal "TP_FM_CPU1_CD_HFI0_MODPRST_N"
				( objectStatus "@baseboard_fab2_lib.baseboard_fab2(sch_1):tp_fm_cpu1_cd_hfi0_modprst_n" )
			)
			( signal "TP_IRQ_CPU1_CD_HFI0_N"
				( objectStatus "@baseboard_fab2_lib.baseboard_fab2(sch_1):tp_irq_cpu1_cd_hfi0_n" )
			)
			( signal "TP_LED_CPU1_CD_HFI0_N"
				( objectStatus "@baseboard_fab2_lib.baseboard_fab2(sch_1):tp_led_cpu1_cd_hfi0_n" )
			)
			( signal "TP_RST_CPU1_CD_HFI0_N"
				( objectStatus "@baseboard_fab2_lib.baseboard_fab2(sch_1):tp_rst_cpu1_cd_hfi0_n" )
			)
			( signal "TP_SMB_CPU1_CD_HFI0_I2CCLK"
				( objectStatus "@baseboard_fab2_lib.baseboard_fab2(sch_1):tp_smb_cpu1_cd_hfi0_i2cclk" )
			)
			( signal "TP_SMB_CPU1_CD_HFI0_I2CDAT"
				( objectStatus "@baseboard_fab2_lib.baseboard_fab2(sch_1):tp_smb_cpu1_cd_hfi0_i2cdat" )
			)
			( signal "TP_P3E_CPU1_PE1_MP_RXN<0>"
				( objectStatus "@baseboard_fab2_lib.baseboard_fab2(sch_1):tp_p3e_cpu1_pe1_mp_rxn(0)" )
			)
			( signal "TP_P3E_CPU1_PE1_MP_RXN<1>"
				( objectStatus "@baseboard_fab2_lib.baseboard_fab2(sch_1):tp_p3e_cpu1_pe1_mp_rxn(1)" )
			)
			( signal "TP_P3E_CPU1_PE1_MP_RXN<2>"
				( objectStatus "@baseboard_fab2_lib.baseboard_fab2(sch_1):tp_p3e_cpu1_pe1_mp_rxn(2)" )
			)
			( signal "TP_P3E_CPU1_PE1_MP_RXN<3>"
				( objectStatus "@baseboard_fab2_lib.baseboard_fab2(sch_1):tp_p3e_cpu1_pe1_mp_rxn(3)" )
			)
			( signal "TP_P3E_CPU1_PE1_MP_RXN<4>"
				( objectStatus "@baseboard_fab2_lib.baseboard_fab2(sch_1):tp_p3e_cpu1_pe1_mp_rxn(4)" )
			)
			( signal "TP_P3E_CPU1_PE1_MP_RXN<5>"
				( objectStatus "@baseboard_fab2_lib.baseboard_fab2(sch_1):tp_p3e_cpu1_pe1_mp_rxn(5)" )
			)
			( signal "TP_P3E_CPU1_PE1_MP_RXN<6>"
				( objectStatus "@baseboard_fab2_lib.baseboard_fab2(sch_1):tp_p3e_cpu1_pe1_mp_rxn(6)" )
			)
			( signal "TP_P3E_CPU1_PE1_MP_RXN<7>"
				( objectStatus "@baseboard_fab2_lib.baseboard_fab2(sch_1):tp_p3e_cpu1_pe1_mp_rxn(7)" )
			)
			( signal "TP_P3E_CPU1_PE1_MP_RXP<0>"
				( objectStatus "@baseboard_fab2_lib.baseboard_fab2(sch_1):tp_p3e_cpu1_pe1_mp_rxp(0)" )
			)
			( signal "TP_P3E_CPU1_PE1_MP_RXP<1>"
				( objectStatus "@baseboard_fab2_lib.baseboard_fab2(sch_1):tp_p3e_cpu1_pe1_mp_rxp(1)" )
			)
			( signal "TP_P3E_CPU1_PE1_MP_RXP<2>"
				( objectStatus "@baseboard_fab2_lib.baseboard_fab2(sch_1):tp_p3e_cpu1_pe1_mp_rxp(2)" )
			)
			( signal "TP_P3E_CPU1_PE1_MP_RXP<3>"
				( objectStatus "@baseboard_fab2_lib.baseboard_fab2(sch_1):tp_p3e_cpu1_pe1_mp_rxp(3)" )
			)
			( signal "TP_P3E_CPU1_PE1_MP_RXP<4>"
				( objectStatus "@baseboard_fab2_lib.baseboard_fab2(sch_1):tp_p3e_cpu1_pe1_mp_rxp(4)" )
			)
			( signal "TP_P3E_CPU1_PE1_MP_RXP<5>"
				( objectStatus "@baseboard_fab2_lib.baseboard_fab2(sch_1):tp_p3e_cpu1_pe1_mp_rxp(5)" )
			)
			( signal "TP_P3E_CPU1_PE1_MP_RXP<6>"
				( objectStatus "@baseboard_fab2_lib.baseboard_fab2(sch_1):tp_p3e_cpu1_pe1_mp_rxp(6)" )
			)
			( signal "TP_P3E_CPU1_PE1_MP_RXP<7>"
				( objectStatus "@baseboard_fab2_lib.baseboard_fab2(sch_1):tp_p3e_cpu1_pe1_mp_rxp(7)" )
			)
			( signal "TP_P3E_CPU1_PE1_MP_TXN<0>"
				( objectStatus "@baseboard_fab2_lib.baseboard_fab2(sch_1):tp_p3e_cpu1_pe1_mp_txn(0)" )
			)
			( signal "TP_P3E_CPU1_PE1_MP_TXN<1>"
				( objectStatus "@baseboard_fab2_lib.baseboard_fab2(sch_1):tp_p3e_cpu1_pe1_mp_txn(1)" )
			)
			( signal "TP_P3E_CPU1_PE1_MP_TXN<2>"
				( objectStatus "@baseboard_fab2_lib.baseboard_fab2(sch_1):tp_p3e_cpu1_pe1_mp_txn(2)" )
			)
			( signal "TP_P3E_CPU1_PE1_MP_TXN<3>"
				( objectStatus "@baseboard_fab2_lib.baseboard_fab2(sch_1):tp_p3e_cpu1_pe1_mp_txn(3)" )
			)
			( signal "TP_P3E_CPU1_PE1_MP_TXN<4>"
				( objectStatus "@baseboard_fab2_lib.baseboard_fab2(sch_1):tp_p3e_cpu1_pe1_mp_txn(4)" )
			)
			( signal "TP_P3E_CPU1_PE1_MP_TXN<5>"
				( objectStatus "@baseboard_fab2_lib.baseboard_fab2(sch_1):tp_p3e_cpu1_pe1_mp_txn(5)" )
			)
			( signal "TP_P3E_CPU1_PE1_MP_TXN<6>"
				( objectStatus "@baseboard_fab2_lib.baseboard_fab2(sch_1):tp_p3e_cpu1_pe1_mp_txn(6)" )
			)
			( signal "TP_P3E_CPU1_PE1_MP_TXN<7>"
				( objectStatus "@baseboard_fab2_lib.baseboard_fab2(sch_1):tp_p3e_cpu1_pe1_mp_txn(7)" )
			)
			( signal "TP_P3E_CPU1_PE1_MP_TXP<0>"
				( objectStatus "@baseboard_fab2_lib.baseboard_fab2(sch_1):tp_p3e_cpu1_pe1_mp_txp(0)" )
			)
			( signal "TP_P3E_CPU1_PE1_MP_TXP<1>"
				( objectStatus "@baseboard_fab2_lib.baseboard_fab2(sch_1):tp_p3e_cpu1_pe1_mp_txp(1)" )
			)
			( signal "TP_P3E_CPU1_PE1_MP_TXP<2>"
				( objectStatus "@baseboard_fab2_lib.baseboard_fab2(sch_1):tp_p3e_cpu1_pe1_mp_txp(2)" )
			)
			( signal "TP_P3E_CPU1_PE1_MP_TXP<3>"
				( objectStatus "@baseboard_fab2_lib.baseboard_fab2(sch_1):tp_p3e_cpu1_pe1_mp_txp(3)" )
			)
			( signal "TP_P3E_CPU1_PE1_MP_TXP<4>"
				( objectStatus "@baseboard_fab2_lib.baseboard_fab2(sch_1):tp_p3e_cpu1_pe1_mp_txp(4)" )
			)
			( signal "TP_P3E_CPU1_PE1_MP_TXP<5>"
				( objectStatus "@baseboard_fab2_lib.baseboard_fab2(sch_1):tp_p3e_cpu1_pe1_mp_txp(5)" )
			)
			( signal "TP_P3E_CPU1_PE1_MP_TXP<6>"
				( objectStatus "@baseboard_fab2_lib.baseboard_fab2(sch_1):tp_p3e_cpu1_pe1_mp_txp(6)" )
			)
			( signal "TP_P3E_CPU1_PE1_MP_TXP<7>"
				( objectStatus "@baseboard_fab2_lib.baseboard_fab2(sch_1):tp_p3e_cpu1_pe1_mp_txp(7)" )
			)
			( signal "TP_P3E_CPU1_PE1_RSR3_RXN<8>"
				( objectStatus "@baseboard_fab2_lib.baseboard_fab2(sch_1):tp_p3e_cpu1_pe1_rsr3_rxn(8)" )
			)
			( signal "TP_P3E_CPU1_PE1_RSR3_RXN<9>"
				( objectStatus "@baseboard_fab2_lib.baseboard_fab2(sch_1):tp_p3e_cpu1_pe1_rsr3_rxn(9)" )
			)
			( signal "TP_P3E_CPU1_PE1_RSR3_RXN<10>"
				( objectStatus "@baseboard_fab2_lib.baseboard_fab2(sch_1):tp_p3e_cpu1_pe1_rsr3_rxn(10)" )
			)
			( signal "TP_P3E_CPU1_PE1_RSR3_RXN<11>"
				( objectStatus "@baseboard_fab2_lib.baseboard_fab2(sch_1):tp_p3e_cpu1_pe1_rsr3_rxn(11)" )
			)
			( signal "TP_P3E_CPU1_PE1_RSR3_RXN<12>"
				( objectStatus "@baseboard_fab2_lib.baseboard_fab2(sch_1):tp_p3e_cpu1_pe1_rsr3_rxn(12)" )
			)
			( signal "TP_P3E_CPU1_PE1_RSR3_RXN<13>"
				( objectStatus "@baseboard_fab2_lib.baseboard_fab2(sch_1):tp_p3e_cpu1_pe1_rsr3_rxn(13)" )
			)
			( signal "TP_P3E_CPU1_PE1_RSR3_RXN<14>"
				( objectStatus "@baseboard_fab2_lib.baseboard_fab2(sch_1):tp_p3e_cpu1_pe1_rsr3_rxn(14)" )
			)
			( signal "TP_P3E_CPU1_PE1_RSR3_RXN<15>"
				( objectStatus "@baseboard_fab2_lib.baseboard_fab2(sch_1):tp_p3e_cpu1_pe1_rsr3_rxn(15)" )
			)
			( signal "TP_P3E_CPU1_PE1_RSR3_RXP<8>"
				( objectStatus "@baseboard_fab2_lib.baseboard_fab2(sch_1):tp_p3e_cpu1_pe1_rsr3_rxp(8)" )
			)
			( signal "TP_P3E_CPU1_PE1_RSR3_RXP<9>"
				( objectStatus "@baseboard_fab2_lib.baseboard_fab2(sch_1):tp_p3e_cpu1_pe1_rsr3_rxp(9)" )
			)
			( signal "TP_P3E_CPU1_PE1_RSR3_RXP<10>"
				( objectStatus "@baseboard_fab2_lib.baseboard_fab2(sch_1):tp_p3e_cpu1_pe1_rsr3_rxp(10)" )
			)
			( signal "TP_P3E_CPU1_PE1_RSR3_RXP<11>"
				( objectStatus "@baseboard_fab2_lib.baseboard_fab2(sch_1):tp_p3e_cpu1_pe1_rsr3_rxp(11)" )
			)
			( signal "TP_P3E_CPU1_PE1_RSR3_RXP<12>"
				( objectStatus "@baseboard_fab2_lib.baseboard_fab2(sch_1):tp_p3e_cpu1_pe1_rsr3_rxp(12)" )
			)
			( signal "TP_P3E_CPU1_PE1_RSR3_RXP<13>"
				( objectStatus "@baseboard_fab2_lib.baseboard_fab2(sch_1):tp_p3e_cpu1_pe1_rsr3_rxp(13)" )
			)
			( signal "TP_P3E_CPU1_PE1_RSR3_RXP<14>"
				( objectStatus "@baseboard_fab2_lib.baseboard_fab2(sch_1):tp_p3e_cpu1_pe1_rsr3_rxp(14)" )
			)
			( signal "TP_P3E_CPU1_PE1_RSR3_RXP<15>"
				( objectStatus "@baseboard_fab2_lib.baseboard_fab2(sch_1):tp_p3e_cpu1_pe1_rsr3_rxp(15)" )
			)
			( signal "TP_P3E_CPU1_PE1_RSR3_TXN<8>"
				( objectStatus "@baseboard_fab2_lib.baseboard_fab2(sch_1):tp_p3e_cpu1_pe1_rsr3_txn(8)" )
			)
			( signal "TP_P3E_CPU1_PE1_RSR3_TXN<9>"
				( objectStatus "@baseboard_fab2_lib.baseboard_fab2(sch_1):tp_p3e_cpu1_pe1_rsr3_txn(9)" )
			)
			( signal "TP_P3E_CPU1_PE1_RSR3_TXN<10>"
				( objectStatus "@baseboard_fab2_lib.baseboard_fab2(sch_1):tp_p3e_cpu1_pe1_rsr3_txn(10)" )
			)
			( signal "TP_P3E_CPU1_PE1_RSR3_TXN<11>"
				( objectStatus "@baseboard_fab2_lib.baseboard_fab2(sch_1):tp_p3e_cpu1_pe1_rsr3_txn(11)" )
			)
			( signal "TP_P3E_CPU1_PE1_RSR3_TXN<12>"
				( objectStatus "@baseboard_fab2_lib.baseboard_fab2(sch_1):tp_p3e_cpu1_pe1_rsr3_txn(12)" )
			)
			( signal "TP_P3E_CPU1_PE1_RSR3_TXN<13>"
				( objectStatus "@baseboard_fab2_lib.baseboard_fab2(sch_1):tp_p3e_cpu1_pe1_rsr3_txn(13)" )
			)
			( signal "TP_P3E_CPU1_PE1_RSR3_TXN<14>"
				( objectStatus "@baseboard_fab2_lib.baseboard_fab2(sch_1):tp_p3e_cpu1_pe1_rsr3_txn(14)" )
			)
			( signal "TP_P3E_CPU1_PE1_RSR3_TXN<15>"
				( objectStatus "@baseboard_fab2_lib.baseboard_fab2(sch_1):tp_p3e_cpu1_pe1_rsr3_txn(15)" )
			)
			( signal "TP_P3E_CPU1_PE1_RSR3_TXP<8>"
				( objectStatus "@baseboard_fab2_lib.baseboard_fab2(sch_1):tp_p3e_cpu1_pe1_rsr3_txp(8)" )
			)
			( signal "TP_P3E_CPU1_PE1_RSR3_TXP<9>"
				( objectStatus "@baseboard_fab2_lib.baseboard_fab2(sch_1):tp_p3e_cpu1_pe1_rsr3_txp(9)" )
			)
			( signal "TP_P3E_CPU1_PE1_RSR3_TXP<10>"
				( objectStatus "@baseboard_fab2_lib.baseboard_fab2(sch_1):tp_p3e_cpu1_pe1_rsr3_txp(10)" )
			)
			( signal "TP_P3E_CPU1_PE1_RSR3_TXP<11>"
				( objectStatus "@baseboard_fab2_lib.baseboard_fab2(sch_1):tp_p3e_cpu1_pe1_rsr3_txp(11)" )
			)
			( signal "TP_P3E_CPU1_PE1_RSR3_TXP<12>"
				( objectStatus "@baseboard_fab2_lib.baseboard_fab2(sch_1):tp_p3e_cpu1_pe1_rsr3_txp(12)" )
			)
			( signal "TP_P3E_CPU1_PE1_RSR3_TXP<13>"
				( objectStatus "@baseboard_fab2_lib.baseboard_fab2(sch_1):tp_p3e_cpu1_pe1_rsr3_txp(13)" )
			)
			( signal "TP_P3E_CPU1_PE1_RSR3_TXP<14>"
				( objectStatus "@baseboard_fab2_lib.baseboard_fab2(sch_1):tp_p3e_cpu1_pe1_rsr3_txp(14)" )
			)
			( signal "TP_P3E_CPU1_PE1_RSR3_TXP<15>"
				( objectStatus "@baseboard_fab2_lib.baseboard_fab2(sch_1):tp_p3e_cpu1_pe1_rsr3_txp(15)" )
			)
			( signal "TP_P3E_CPU1_PE2_RSR_RXN<0>"
				( objectStatus "@baseboard_fab2_lib.baseboard_fab2(sch_1):tp_p3e_cpu1_pe2_rsr_rxn(0)" )
			)
			( signal "TP_P3E_CPU1_PE2_RSR_RXN<1>"
				( objectStatus "@baseboard_fab2_lib.baseboard_fab2(sch_1):tp_p3e_cpu1_pe2_rsr_rxn(1)" )
			)
			( signal "TP_P3E_CPU1_PE2_RSR_RXN<2>"
				( objectStatus "@baseboard_fab2_lib.baseboard_fab2(sch_1):tp_p3e_cpu1_pe2_rsr_rxn(2)" )
			)
			( signal "TP_P3E_CPU1_PE2_RSR_RXN<3>"
				( objectStatus "@baseboard_fab2_lib.baseboard_fab2(sch_1):tp_p3e_cpu1_pe2_rsr_rxn(3)" )
			)
			( signal "TP_P3E_CPU1_PE2_RSR_RXN<4>"
				( objectStatus "@baseboard_fab2_lib.baseboard_fab2(sch_1):tp_p3e_cpu1_pe2_rsr_rxn(4)" )
			)
			( signal "TP_P3E_CPU1_PE2_RSR_RXN<5>"
				( objectStatus "@baseboard_fab2_lib.baseboard_fab2(sch_1):tp_p3e_cpu1_pe2_rsr_rxn(5)" )
			)
			( signal "TP_P3E_CPU1_PE2_RSR_RXN<6>"
				( objectStatus "@baseboard_fab2_lib.baseboard_fab2(sch_1):tp_p3e_cpu1_pe2_rsr_rxn(6)" )
			)
			( signal "TP_P3E_CPU1_PE2_RSR_RXN<7>"
				( objectStatus "@baseboard_fab2_lib.baseboard_fab2(sch_1):tp_p3e_cpu1_pe2_rsr_rxn(7)" )
			)
			( signal "TP_P3E_CPU1_PE2_RSR_RXN<8>"
				( objectStatus "@baseboard_fab2_lib.baseboard_fab2(sch_1):tp_p3e_cpu1_pe2_rsr_rxn(8)" )
			)
			( signal "TP_P3E_CPU1_PE2_RSR_RXN<9>"
				( objectStatus "@baseboard_fab2_lib.baseboard_fab2(sch_1):tp_p3e_cpu1_pe2_rsr_rxn(9)" )
			)
			( signal "TP_P3E_CPU1_PE2_RSR_RXN<10>"
				( objectStatus "@baseboard_fab2_lib.baseboard_fab2(sch_1):tp_p3e_cpu1_pe2_rsr_rxn(10)" )
			)
			( signal "TP_P3E_CPU1_PE2_RSR_RXN<11>"
				( objectStatus "@baseboard_fab2_lib.baseboard_fab2(sch_1):tp_p3e_cpu1_pe2_rsr_rxn(11)" )
			)
			( signal "TP_P3E_CPU1_PE2_RSR_RXN<12>"
				( objectStatus "@baseboard_fab2_lib.baseboard_fab2(sch_1):tp_p3e_cpu1_pe2_rsr_rxn(12)" )
			)
			( signal "TP_P3E_CPU1_PE2_RSR_RXN<13>"
				( objectStatus "@baseboard_fab2_lib.baseboard_fab2(sch_1):tp_p3e_cpu1_pe2_rsr_rxn(13)" )
			)
			( signal "TP_P3E_CPU1_PE2_RSR_RXN<14>"
				( objectStatus "@baseboard_fab2_lib.baseboard_fab2(sch_1):tp_p3e_cpu1_pe2_rsr_rxn(14)" )
			)
			( signal "TP_P3E_CPU1_PE2_RSR_RXN<15>"
				( objectStatus "@baseboard_fab2_lib.baseboard_fab2(sch_1):tp_p3e_cpu1_pe2_rsr_rxn(15)" )
			)
			( signal "TP_P3E_CPU1_PE2_RSR_RXP<0>"
				( objectStatus "@baseboard_fab2_lib.baseboard_fab2(sch_1):tp_p3e_cpu1_pe2_rsr_rxp(0)" )
			)
			( signal "TP_P3E_CPU1_PE2_RSR_RXP<1>"
				( objectStatus "@baseboard_fab2_lib.baseboard_fab2(sch_1):tp_p3e_cpu1_pe2_rsr_rxp(1)" )
			)
			( signal "TP_P3E_CPU1_PE2_RSR_RXP<2>"
				( objectStatus "@baseboard_fab2_lib.baseboard_fab2(sch_1):tp_p3e_cpu1_pe2_rsr_rxp(2)" )
			)
			( signal "TP_P3E_CPU1_PE2_RSR_RXP<3>"
				( objectStatus "@baseboard_fab2_lib.baseboard_fab2(sch_1):tp_p3e_cpu1_pe2_rsr_rxp(3)" )
			)
			( signal "TP_P3E_CPU1_PE2_RSR_RXP<4>"
				( objectStatus "@baseboard_fab2_lib.baseboard_fab2(sch_1):tp_p3e_cpu1_pe2_rsr_rxp(4)" )
			)
			( signal "TP_P3E_CPU1_PE2_RSR_RXP<5>"
				( objectStatus "@baseboard_fab2_lib.baseboard_fab2(sch_1):tp_p3e_cpu1_pe2_rsr_rxp(5)" )
			)
			( signal "TP_P3E_CPU1_PE2_RSR_RXP<6>"
				( objectStatus "@baseboard_fab2_lib.baseboard_fab2(sch_1):tp_p3e_cpu1_pe2_rsr_rxp(6)" )
			)
			( signal "TP_P3E_CPU1_PE2_RSR_RXP<7>"
				( objectStatus "@baseboard_fab2_lib.baseboard_fab2(sch_1):tp_p3e_cpu1_pe2_rsr_rxp(7)" )
			)
			( signal "TP_P3E_CPU1_PE2_RSR_RXP<8>"
				( objectStatus "@baseboard_fab2_lib.baseboard_fab2(sch_1):tp_p3e_cpu1_pe2_rsr_rxp(8)" )
			)
			( signal "TP_P3E_CPU1_PE2_RSR_RXP<9>"
				( objectStatus "@baseboard_fab2_lib.baseboard_fab2(sch_1):tp_p3e_cpu1_pe2_rsr_rxp(9)" )
			)
			( signal "TP_P3E_CPU1_PE2_RSR_RXP<10>"
				( objectStatus "@baseboard_fab2_lib.baseboard_fab2(sch_1):tp_p3e_cpu1_pe2_rsr_rxp(10)" )
			)
			( signal "TP_P3E_CPU1_PE2_RSR_RXP<11>"
				( objectStatus "@baseboard_fab2_lib.baseboard_fab2(sch_1):tp_p3e_cpu1_pe2_rsr_rxp(11)" )
			)
			( signal "TP_P3E_CPU1_PE2_RSR_RXP<12>"
				( objectStatus "@baseboard_fab2_lib.baseboard_fab2(sch_1):tp_p3e_cpu1_pe2_rsr_rxp(12)" )
			)
			( signal "TP_P3E_CPU1_PE2_RSR_RXP<13>"
				( objectStatus "@baseboard_fab2_lib.baseboard_fab2(sch_1):tp_p3e_cpu1_pe2_rsr_rxp(13)" )
			)
			( signal "TP_P3E_CPU1_PE2_RSR_RXP<14>"
				( objectStatus "@baseboard_fab2_lib.baseboard_fab2(sch_1):tp_p3e_cpu1_pe2_rsr_rxp(14)" )
			)
			( signal "TP_P3E_CPU1_PE2_RSR_RXP<15>"
				( objectStatus "@baseboard_fab2_lib.baseboard_fab2(sch_1):tp_p3e_cpu1_pe2_rsr_rxp(15)" )
			)
			( signal "TP_P3E_CPU1_PE2_RSR_TXN<0>"
				( objectStatus "@baseboard_fab2_lib.baseboard_fab2(sch_1):tp_p3e_cpu1_pe2_rsr_txn(0)" )
			)
			( signal "TP_P3E_CPU1_PE2_RSR_TXN<1>"
				( objectStatus "@baseboard_fab2_lib.baseboard_fab2(sch_1):tp_p3e_cpu1_pe2_rsr_txn(1)" )
			)
			( signal "TP_P3E_CPU1_PE2_RSR_TXN<2>"
				( objectStatus "@baseboard_fab2_lib.baseboard_fab2(sch_1):tp_p3e_cpu1_pe2_rsr_txn(2)" )
			)
			( signal "TP_P3E_CPU1_PE2_RSR_TXN<3>"
				( objectStatus "@baseboard_fab2_lib.baseboard_fab2(sch_1):tp_p3e_cpu1_pe2_rsr_txn(3)" )
			)
			( signal "TP_P3E_CPU1_PE2_RSR_TXN<4>"
				( objectStatus "@baseboard_fab2_lib.baseboard_fab2(sch_1):tp_p3e_cpu1_pe2_rsr_txn(4)" )
			)
			( signal "TP_P3E_CPU1_PE2_RSR_TXN<5>"
				( objectStatus "@baseboard_fab2_lib.baseboard_fab2(sch_1):tp_p3e_cpu1_pe2_rsr_txn(5)" )
			)
			( signal "TP_P3E_CPU1_PE2_RSR_TXN<6>"
				( objectStatus "@baseboard_fab2_lib.baseboard_fab2(sch_1):tp_p3e_cpu1_pe2_rsr_txn(6)" )
			)
			( signal "TP_P3E_CPU1_PE2_RSR_TXN<7>"
				( objectStatus "@baseboard_fab2_lib.baseboard_fab2(sch_1):tp_p3e_cpu1_pe2_rsr_txn(7)" )
			)
			( signal "TP_P3E_CPU1_PE2_RSR_TXN<8>"
				( objectStatus "@baseboard_fab2_lib.baseboard_fab2(sch_1):tp_p3e_cpu1_pe2_rsr_txn(8)" )
			)
			( signal "TP_P3E_CPU1_PE2_RSR_TXN<9>"
				( objectStatus "@baseboard_fab2_lib.baseboard_fab2(sch_1):tp_p3e_cpu1_pe2_rsr_txn(9)" )
			)
			( signal "TP_P3E_CPU1_PE2_RSR_TXN<10>"
				( objectStatus "@baseboard_fab2_lib.baseboard_fab2(sch_1):tp_p3e_cpu1_pe2_rsr_txn(10)" )
			)
			( signal "TP_P3E_CPU1_PE2_RSR_TXN<11>"
				( objectStatus "@baseboard_fab2_lib.baseboard_fab2(sch_1):tp_p3e_cpu1_pe2_rsr_txn(11)" )
			)
			( signal "TP_P3E_CPU1_PE2_RSR_TXN<12>"
				( objectStatus "@baseboard_fab2_lib.baseboard_fab2(sch_1):tp_p3e_cpu1_pe2_rsr_txn(12)" )
			)
			( signal "TP_P3E_CPU1_PE2_RSR_TXN<13>"
				( objectStatus "@baseboard_fab2_lib.baseboard_fab2(sch_1):tp_p3e_cpu1_pe2_rsr_txn(13)" )
			)
			( signal "TP_P3E_CPU1_PE2_RSR_TXN<14>"
				( objectStatus "@baseboard_fab2_lib.baseboard_fab2(sch_1):tp_p3e_cpu1_pe2_rsr_txn(14)" )
			)
			( signal "TP_P3E_CPU1_PE2_RSR_TXN<15>"
				( objectStatus "@baseboard_fab2_lib.baseboard_fab2(sch_1):tp_p3e_cpu1_pe2_rsr_txn(15)" )
			)
			( signal "TP_P3E_CPU1_PE2_RSR_TXP<0>"
				( objectStatus "@baseboard_fab2_lib.baseboard_fab2(sch_1):tp_p3e_cpu1_pe2_rsr_txp(0)" )
			)
			( signal "TP_P3E_CPU1_PE2_RSR_TXP<1>"
				( objectStatus "@baseboard_fab2_lib.baseboard_fab2(sch_1):tp_p3e_cpu1_pe2_rsr_txp(1)" )
			)
			( signal "TP_P3E_CPU1_PE2_RSR_TXP<2>"
				( objectStatus "@baseboard_fab2_lib.baseboard_fab2(sch_1):tp_p3e_cpu1_pe2_rsr_txp(2)" )
			)
			( signal "TP_P3E_CPU1_PE2_RSR_TXP<3>"
				( objectStatus "@baseboard_fab2_lib.baseboard_fab2(sch_1):tp_p3e_cpu1_pe2_rsr_txp(3)" )
			)
			( signal "TP_P3E_CPU1_PE2_RSR_TXP<4>"
				( objectStatus "@baseboard_fab2_lib.baseboard_fab2(sch_1):tp_p3e_cpu1_pe2_rsr_txp(4)" )
			)
			( signal "TP_P3E_CPU1_PE2_RSR_TXP<5>"
				( objectStatus "@baseboard_fab2_lib.baseboard_fab2(sch_1):tp_p3e_cpu1_pe2_rsr_txp(5)" )
			)
			( signal "TP_P3E_CPU1_PE2_RSR_TXP<6>"
				( objectStatus "@baseboard_fab2_lib.baseboard_fab2(sch_1):tp_p3e_cpu1_pe2_rsr_txp(6)" )
			)
			( signal "TP_P3E_CPU1_PE2_RSR_TXP<7>"
				( objectStatus "@baseboard_fab2_lib.baseboard_fab2(sch_1):tp_p3e_cpu1_pe2_rsr_txp(7)" )
			)
			( signal "TP_P3E_CPU1_PE2_RSR_TXP<8>"
				( objectStatus "@baseboard_fab2_lib.baseboard_fab2(sch_1):tp_p3e_cpu1_pe2_rsr_txp(8)" )
			)
			( signal "TP_P3E_CPU1_PE2_RSR_TXP<9>"
				( objectStatus "@baseboard_fab2_lib.baseboard_fab2(sch_1):tp_p3e_cpu1_pe2_rsr_txp(9)" )
			)
			( signal "TP_P3E_CPU1_PE2_RSR_TXP<10>"
				( objectStatus "@baseboard_fab2_lib.baseboard_fab2(sch_1):tp_p3e_cpu1_pe2_rsr_txp(10)" )
			)
			( signal "TP_P3E_CPU1_PE2_RSR_TXP<11>"
				( objectStatus "@baseboard_fab2_lib.baseboard_fab2(sch_1):tp_p3e_cpu1_pe2_rsr_txp(11)" )
			)
			( signal "TP_P3E_CPU1_PE2_RSR_TXP<12>"
				( objectStatus "@baseboard_fab2_lib.baseboard_fab2(sch_1):tp_p3e_cpu1_pe2_rsr_txp(12)" )
			)
			( signal "TP_P3E_CPU1_PE2_RSR_TXP<13>"
				( objectStatus "@baseboard_fab2_lib.baseboard_fab2(sch_1):tp_p3e_cpu1_pe2_rsr_txp(13)" )
			)
			( signal "TP_P3E_CPU1_PE2_RSR_TXP<14>"
				( objectStatus "@baseboard_fab2_lib.baseboard_fab2(sch_1):tp_p3e_cpu1_pe2_rsr_txp(14)" )
			)
			( signal "TP_P3E_CPU1_PE2_RSR_TXP<15>"
				( objectStatus "@baseboard_fab2_lib.baseboard_fab2(sch_1):tp_p3e_cpu1_pe2_rsr_txp(15)" )
			)
			( signal "P3E_CPU1_PE3_MP_RXN<0>"
				( objectStatus "@baseboard_fab2_lib.baseboard_fab2(sch_1):p3e_cpu1_pe3_mp_rxn(0)" )
			)
			( signal "P3E_CPU1_PE3_MP_RXN<1>"
				( objectStatus "@baseboard_fab2_lib.baseboard_fab2(sch_1):p3e_cpu1_pe3_mp_rxn(1)" )
			)
			( signal "P3E_CPU1_PE3_MP_RXN<2>"
				( objectStatus "@baseboard_fab2_lib.baseboard_fab2(sch_1):p3e_cpu1_pe3_mp_rxn(2)" )
			)
			( signal "P3E_CPU1_PE3_MP_RXN<3>"
				( objectStatus "@baseboard_fab2_lib.baseboard_fab2(sch_1):p3e_cpu1_pe3_mp_rxn(3)" )
			)
			( signal "P3E_CPU1_PE3_MP_RXN<4>"
				( objectStatus "@baseboard_fab2_lib.baseboard_fab2(sch_1):p3e_cpu1_pe3_mp_rxn(4)" )
			)
			( signal "P3E_CPU1_PE3_MP_RXN<5>"
				( objectStatus "@baseboard_fab2_lib.baseboard_fab2(sch_1):p3e_cpu1_pe3_mp_rxn(5)" )
			)
			( signal "P3E_CPU1_PE3_MP_RXN<6>"
				( objectStatus "@baseboard_fab2_lib.baseboard_fab2(sch_1):p3e_cpu1_pe3_mp_rxn(6)" )
			)
			( signal "P3E_CPU1_PE3_MP_RXN<7>"
				( objectStatus "@baseboard_fab2_lib.baseboard_fab2(sch_1):p3e_cpu1_pe3_mp_rxn(7)" )
			)
			( signal "P3E_CPU1_PE3_MP_RXN<8>"
				( objectStatus "@baseboard_fab2_lib.baseboard_fab2(sch_1):p3e_cpu1_pe3_mp_rxn(8)" )
			)
			( signal "P3E_CPU1_PE3_MP_RXN<9>"
				( objectStatus "@baseboard_fab2_lib.baseboard_fab2(sch_1):p3e_cpu1_pe3_mp_rxn(9)" )
			)
			( signal "P3E_CPU1_PE3_MP_RXN<10>"
				( objectStatus "@baseboard_fab2_lib.baseboard_fab2(sch_1):p3e_cpu1_pe3_mp_rxn(10)" )
			)
			( signal "P3E_CPU1_PE3_MP_RXN<11>"
				( objectStatus "@baseboard_fab2_lib.baseboard_fab2(sch_1):p3e_cpu1_pe3_mp_rxn(11)" )
			)
			( signal "P3E_CPU1_PE3_MP_RXN<12>"
				( objectStatus "@baseboard_fab2_lib.baseboard_fab2(sch_1):p3e_cpu1_pe3_mp_rxn(12)" )
			)
			( signal "P3E_CPU1_PE3_MP_RXN<13>"
				( objectStatus "@baseboard_fab2_lib.baseboard_fab2(sch_1):p3e_cpu1_pe3_mp_rxn(13)" )
			)
			( signal "P3E_CPU1_PE3_MP_RXN<14>"
				( objectStatus "@baseboard_fab2_lib.baseboard_fab2(sch_1):p3e_cpu1_pe3_mp_rxn(14)" )
			)
			( signal "P3E_CPU1_PE3_MP_RXN<15>"
				( objectStatus "@baseboard_fab2_lib.baseboard_fab2(sch_1):p3e_cpu1_pe3_mp_rxn(15)" )
			)
			( signal "P3E_CPU1_PE3_MP_RXP<0>"
				( objectStatus "@baseboard_fab2_lib.baseboard_fab2(sch_1):p3e_cpu1_pe3_mp_rxp(0)" )
			)
			( signal "P3E_CPU1_PE3_MP_RXP<1>"
				( objectStatus "@baseboard_fab2_lib.baseboard_fab2(sch_1):p3e_cpu1_pe3_mp_rxp(1)" )
			)
			( signal "P3E_CPU1_PE3_MP_RXP<2>"
				( objectStatus "@baseboard_fab2_lib.baseboard_fab2(sch_1):p3e_cpu1_pe3_mp_rxp(2)" )
			)
			( signal "P3E_CPU1_PE3_MP_RXP<3>"
				( objectStatus "@baseboard_fab2_lib.baseboard_fab2(sch_1):p3e_cpu1_pe3_mp_rxp(3)" )
			)
			( signal "P3E_CPU1_PE3_MP_RXP<4>"
				( objectStatus "@baseboard_fab2_lib.baseboard_fab2(sch_1):p3e_cpu1_pe3_mp_rxp(4)" )
			)
			( signal "P3E_CPU1_PE3_MP_RXP<5>"
				( objectStatus "@baseboard_fab2_lib.baseboard_fab2(sch_1):p3e_cpu1_pe3_mp_rxp(5)" )
			)
			( signal "P3E_CPU1_PE3_MP_RXP<6>"
				( objectStatus "@baseboard_fab2_lib.baseboard_fab2(sch_1):p3e_cpu1_pe3_mp_rxp(6)" )
			)
			( signal "P3E_CPU1_PE3_MP_RXP<7>"
				( objectStatus "@baseboard_fab2_lib.baseboard_fab2(sch_1):p3e_cpu1_pe3_mp_rxp(7)" )
			)
			( signal "P3E_CPU1_PE3_MP_RXP<8>"
				( objectStatus "@baseboard_fab2_lib.baseboard_fab2(sch_1):p3e_cpu1_pe3_mp_rxp(8)" )
			)
			( signal "P3E_CPU1_PE3_MP_RXP<9>"
				( objectStatus "@baseboard_fab2_lib.baseboard_fab2(sch_1):p3e_cpu1_pe3_mp_rxp(9)" )
			)
			( signal "P3E_CPU1_PE3_MP_RXP<10>"
				( objectStatus "@baseboard_fab2_lib.baseboard_fab2(sch_1):p3e_cpu1_pe3_mp_rxp(10)" )
			)
			( signal "P3E_CPU1_PE3_MP_RXP<11>"
				( objectStatus "@baseboard_fab2_lib.baseboard_fab2(sch_1):p3e_cpu1_pe3_mp_rxp(11)" )
			)
			( signal "P3E_CPU1_PE3_MP_RXP<12>"
				( objectStatus "@baseboard_fab2_lib.baseboard_fab2(sch_1):p3e_cpu1_pe3_mp_rxp(12)" )
			)
			( signal "P3E_CPU1_PE3_MP_RXP<13>"
				( objectStatus "@baseboard_fab2_lib.baseboard_fab2(sch_1):p3e_cpu1_pe3_mp_rxp(13)" )
			)
			( signal "P3E_CPU1_PE3_MP_RXP<14>"
				( objectStatus "@baseboard_fab2_lib.baseboard_fab2(sch_1):p3e_cpu1_pe3_mp_rxp(14)" )
			)
			( signal "P3E_CPU1_PE3_MP_RXP<15>"
				( objectStatus "@baseboard_fab2_lib.baseboard_fab2(sch_1):p3e_cpu1_pe3_mp_rxp(15)" )
			)
			( signal "P3E_CPU1_PE3_MP_TXN<0>"
				( objectStatus "@baseboard_fab2_lib.baseboard_fab2(sch_1):p3e_cpu1_pe3_mp_txn(0)" )
			)
			( signal "P3E_CPU1_PE3_MP_TXN<1>"
				( objectStatus "@baseboard_fab2_lib.baseboard_fab2(sch_1):p3e_cpu1_pe3_mp_txn(1)" )
			)
			( signal "P3E_CPU1_PE3_MP_TXN<2>"
				( objectStatus "@baseboard_fab2_lib.baseboard_fab2(sch_1):p3e_cpu1_pe3_mp_txn(2)" )
			)
			( signal "P3E_CPU1_PE3_MP_TXN<3>"
				( objectStatus "@baseboard_fab2_lib.baseboard_fab2(sch_1):p3e_cpu1_pe3_mp_txn(3)" )
			)
			( signal "P3E_CPU1_PE3_MP_TXN<4>"
				( objectStatus "@baseboard_fab2_lib.baseboard_fab2(sch_1):p3e_cpu1_pe3_mp_txn(4)" )
			)
			( signal "P3E_CPU1_PE3_MP_TXN<5>"
				( objectStatus "@baseboard_fab2_lib.baseboard_fab2(sch_1):p3e_cpu1_pe3_mp_txn(5)" )
			)
			( signal "P3E_CPU1_PE3_MP_TXN<6>"
				( objectStatus "@baseboard_fab2_lib.baseboard_fab2(sch_1):p3e_cpu1_pe3_mp_txn(6)" )
			)
			( signal "P3E_CPU1_PE3_MP_TXN<7>"
				( objectStatus "@baseboard_fab2_lib.baseboard_fab2(sch_1):p3e_cpu1_pe3_mp_txn(7)" )
			)
			( signal "P3E_CPU1_PE3_MP_TXN<8>"
				( objectStatus "@baseboard_fab2_lib.baseboard_fab2(sch_1):p3e_cpu1_pe3_mp_txn(8)" )
			)
			( signal "P3E_CPU1_PE3_MP_TXN<9>"
				( objectStatus "@baseboard_fab2_lib.baseboard_fab2(sch_1):p3e_cpu1_pe3_mp_txn(9)" )
			)
			( signal "P3E_CPU1_PE3_MP_TXN<10>"
				( objectStatus "@baseboard_fab2_lib.baseboard_fab2(sch_1):p3e_cpu1_pe3_mp_txn(10)" )
			)
			( signal "P3E_CPU1_PE3_MP_TXN<11>"
				( objectStatus "@baseboard_fab2_lib.baseboard_fab2(sch_1):p3e_cpu1_pe3_mp_txn(11)" )
			)
			( signal "P3E_CPU1_PE3_MP_TXN<12>"
				( objectStatus "@baseboard_fab2_lib.baseboard_fab2(sch_1):p3e_cpu1_pe3_mp_txn(12)" )
			)
			( signal "P3E_CPU1_PE3_MP_TXN<13>"
				( objectStatus "@baseboard_fab2_lib.baseboard_fab2(sch_1):p3e_cpu1_pe3_mp_txn(13)" )
			)
			( signal "P3E_CPU1_PE3_MP_TXN<14>"
				( objectStatus "@baseboard_fab2_lib.baseboard_fab2(sch_1):p3e_cpu1_pe3_mp_txn(14)" )
			)
			( signal "P3E_CPU1_PE3_MP_TXN<15>"
				( objectStatus "@baseboard_fab2_lib.baseboard_fab2(sch_1):p3e_cpu1_pe3_mp_txn(15)" )
			)
			( signal "P3E_CPU1_PE3_MP_TXP<0>"
				( objectStatus "@baseboard_fab2_lib.baseboard_fab2(sch_1):p3e_cpu1_pe3_mp_txp(0)" )
			)
			( signal "P3E_CPU1_PE3_MP_TXP<1>"
				( objectStatus "@baseboard_fab2_lib.baseboard_fab2(sch_1):p3e_cpu1_pe3_mp_txp(1)" )
			)
			( signal "P3E_CPU1_PE3_MP_TXP<2>"
				( objectStatus "@baseboard_fab2_lib.baseboard_fab2(sch_1):p3e_cpu1_pe3_mp_txp(2)" )
			)
			( signal "P3E_CPU1_PE3_MP_TXP<3>"
				( objectStatus "@baseboard_fab2_lib.baseboard_fab2(sch_1):p3e_cpu1_pe3_mp_txp(3)" )
			)
			( signal "P3E_CPU1_PE3_MP_TXP<4>"
				( objectStatus "@baseboard_fab2_lib.baseboard_fab2(sch_1):p3e_cpu1_pe3_mp_txp(4)" )
			)
			( signal "P3E_CPU1_PE3_MP_TXP<5>"
				( objectStatus "@baseboard_fab2_lib.baseboard_fab2(sch_1):p3e_cpu1_pe3_mp_txp(5)" )
			)
			( signal "P3E_CPU1_PE3_MP_TXP<6>"
				( objectStatus "@baseboard_fab2_lib.baseboard_fab2(sch_1):p3e_cpu1_pe3_mp_txp(6)" )
			)
			( signal "P3E_CPU1_PE3_MP_TXP<7>"
				( objectStatus "@baseboard_fab2_lib.baseboard_fab2(sch_1):p3e_cpu1_pe3_mp_txp(7)" )
			)
			( signal "P3E_CPU1_PE3_MP_TXP<8>"
				( objectStatus "@baseboard_fab2_lib.baseboard_fab2(sch_1):p3e_cpu1_pe3_mp_txp(8)" )
			)
			( signal "P3E_CPU1_PE3_MP_TXP<9>"
				( objectStatus "@baseboard_fab2_lib.baseboard_fab2(sch_1):p3e_cpu1_pe3_mp_txp(9)" )
			)
			( signal "P3E_CPU1_PE3_MP_TXP<10>"
				( objectStatus "@baseboard_fab2_lib.baseboard_fab2(sch_1):p3e_cpu1_pe3_mp_txp(10)" )
			)
			( signal "P3E_CPU1_PE3_MP_TXP<11>"
				( objectStatus "@baseboard_fab2_lib.baseboard_fab2(sch_1):p3e_cpu1_pe3_mp_txp(11)" )
			)
			( signal "P3E_CPU1_PE3_MP_TXP<12>"
				( objectStatus "@baseboard_fab2_lib.baseboard_fab2(sch_1):p3e_cpu1_pe3_mp_txp(12)" )
			)
			( signal "P3E_CPU1_PE3_MP_TXP<13>"
				( objectStatus "@baseboard_fab2_lib.baseboard_fab2(sch_1):p3e_cpu1_pe3_mp_txp(13)" )
			)
			( signal "P3E_CPU1_PE3_MP_TXP<14>"
				( objectStatus "@baseboard_fab2_lib.baseboard_fab2(sch_1):p3e_cpu1_pe3_mp_txp(14)" )
			)
			( signal "P3E_CPU1_PE3_MP_TXP<15>"
				( objectStatus "@baseboard_fab2_lib.baseboard_fab2(sch_1):p3e_cpu1_pe3_mp_txp(15)" )
			)
			( signal "TP_CPU1_UPI2_RSVD_CA12"
				( objectStatus "@baseboard_fab2_lib.baseboard_fab2(sch_1):tp_cpu1_upi2_rsvd_ca12" )
			)
			( signal "TP_CPU1_UPI2_RSVD_CB11"
				( objectStatus "@baseboard_fab2_lib.baseboard_fab2(sch_1):tp_cpu1_upi2_rsvd_cb11" )
			)
			( signal "TP_CPU1_UPI2_RSVD_CC10"
				( objectStatus "@baseboard_fab2_lib.baseboard_fab2(sch_1):tp_cpu1_upi2_rsvd_cc10" )
			)
			( signal "TP_CPU1_UPI2_RSVD_CC12"
				( objectStatus "@baseboard_fab2_lib.baseboard_fab2(sch_1):tp_cpu1_upi2_rsvd_cc12" )
			)
			( signal "TP_CPU1_UPI2_RSVD_CD11"
				( objectStatus "@baseboard_fab2_lib.baseboard_fab2(sch_1):tp_cpu1_upi2_rsvd_cd11" )
			)
			( signal "TP_CPU1_UPI2_RSVD_CE12"
				( objectStatus "@baseboard_fab2_lib.baseboard_fab2(sch_1):tp_cpu1_upi2_rsvd_ce12" )
			)
			( signal "TP_CPU1_UPI2_RSVD_CF11"
				( objectStatus "@baseboard_fab2_lib.baseboard_fab2(sch_1):tp_cpu1_upi2_rsvd_cf11" )
			)
			( signal "TP_CPU1_UPI2_RSVD_CF13"
				( objectStatus "@baseboard_fab2_lib.baseboard_fab2(sch_1):tp_cpu1_upi2_rsvd_cf13" )
			)
			( signal "TP_CPU1_UPI2_RSVD_CG12"
				( objectStatus "@baseboard_fab2_lib.baseboard_fab2(sch_1):tp_cpu1_upi2_rsvd_cg12" )
			)
			( signal "TP_CPU1_UPI2_RSVD_CH11"
				( objectStatus "@baseboard_fab2_lib.baseboard_fab2(sch_1):tp_cpu1_upi2_rsvd_ch11" )
			)
			( signal "TP_CPU1_UPI2_RSVD_CH13"
				( objectStatus "@baseboard_fab2_lib.baseboard_fab2(sch_1):tp_cpu1_upi2_rsvd_ch13" )
			)
			( signal "TP_CPU1_UPI2_RSVD_CJ14"
				( objectStatus "@baseboard_fab2_lib.baseboard_fab2(sch_1):tp_cpu1_upi2_rsvd_cj14" )
			)
			( signal "TP_CPU1_UPI2_RSVD_CK13"
				( objectStatus "@baseboard_fab2_lib.baseboard_fab2(sch_1):tp_cpu1_upi2_rsvd_ck13" )
			)
			( signal "TP_CPU1_UPI2_RSVD_CM13"
				( objectStatus "@baseboard_fab2_lib.baseboard_fab2(sch_1):tp_cpu1_upi2_rsvd_cm13" )
			)
			( signal "TP_CPU1_UPI2_RSVD_CR14"
				( objectStatus "@baseboard_fab2_lib.baseboard_fab2(sch_1):tp_cpu1_upi2_rsvd_cr14" )
			)
			( signal "TP_CPU1_UPI2_RSVD_CU14"
				( objectStatus "@baseboard_fab2_lib.baseboard_fab2(sch_1):tp_cpu1_upi2_rsvd_cu14" )
			)
			( signal "TP_CPU1_UPI2_RSVD_CV13"
				( objectStatus "@baseboard_fab2_lib.baseboard_fab2(sch_1):tp_cpu1_upi2_rsvd_cv13" )
			)
			( signal "TP_CPU1_UPI2_RSVD_CW14"
				( objectStatus "@baseboard_fab2_lib.baseboard_fab2(sch_1):tp_cpu1_upi2_rsvd_cw14" )
			)
			( signal "TP_CPU1_UPI2_RSVD_CW16"
				( objectStatus "@baseboard_fab2_lib.baseboard_fab2(sch_1):tp_cpu1_upi2_rsvd_cw16" )
			)
			( signal "TP_CPU1_UPI2_RSVD_DA16"
				( objectStatus "@baseboard_fab2_lib.baseboard_fab2(sch_1):tp_cpu1_upi2_rsvd_da16" )
			)
			( signal "TP_CPU1_UPI2_RSVD_DB15"
				( objectStatus "@baseboard_fab2_lib.baseboard_fab2(sch_1):tp_cpu1_upi2_rsvd_db15" )
			)
			( signal "TP_CPU1_UPI2_RSVD_DC16"
				( objectStatus "@baseboard_fab2_lib.baseboard_fab2(sch_1):tp_cpu1_upi2_rsvd_dc16" )
			)
			( signal "TP_CPU1_UPI2_RSVD_DD15"
				( objectStatus "@baseboard_fab2_lib.baseboard_fab2(sch_1):tp_cpu1_upi2_rsvd_dd15" )
			)
			( signal "TP_CPU1_UPI2_RSVD_DD17"
				( objectStatus "@baseboard_fab2_lib.baseboard_fab2(sch_1):tp_cpu1_upi2_rsvd_dd17" )
			)
			( signal "TP_CPU1_UPI2_RSVD_DE16"
				( objectStatus "@baseboard_fab2_lib.baseboard_fab2(sch_1):tp_cpu1_upi2_rsvd_de16" )
			)
			( signal "TP_CPU1_UPI2_RSVD_DF15"
				( objectStatus "@baseboard_fab2_lib.baseboard_fab2(sch_1):tp_cpu1_upi2_rsvd_df15" )
			)
			( signal "TP_CPU1_UPI2_RSVD_DF17"
				( objectStatus "@baseboard_fab2_lib.baseboard_fab2(sch_1):tp_cpu1_upi2_rsvd_df17" )
			)
			( signal "TP_CPU1_UPI2_RSVD_DG18"
				( objectStatus "@baseboard_fab2_lib.baseboard_fab2(sch_1):tp_cpu1_upi2_rsvd_dg18" )
			)
			( signal "TP_CPU1_UPI2_RSVD_DG20"
				( objectStatus "@baseboard_fab2_lib.baseboard_fab2(sch_1):tp_cpu1_upi2_rsvd_dg20" )
			)
			( signal "TP_CPU1_UPI2_RSVD_DH17"
				( objectStatus "@baseboard_fab2_lib.baseboard_fab2(sch_1):tp_cpu1_upi2_rsvd_dh17" )
			)
			( signal "TP_CPU1_UPI2_RSVD_DH19"
				( objectStatus "@baseboard_fab2_lib.baseboard_fab2(sch_1):tp_cpu1_upi2_rsvd_dh19" )
			)
			( signal "TP_CPU1_UPI2_RSVD_DJ18"
				( objectStatus "@baseboard_fab2_lib.baseboard_fab2(sch_1):tp_cpu1_upi2_rsvd_dj18" )
			)
			( signal "TP_CPU1_UPI2_RSVD_DJ20"
				( objectStatus "@baseboard_fab2_lib.baseboard_fab2(sch_1):tp_cpu1_upi2_rsvd_dj20" )
			)
			( signal "TP_CPU1_UPI2_RSVD_DK17"
				( objectStatus "@baseboard_fab2_lib.baseboard_fab2(sch_1):tp_cpu1_upi2_rsvd_dk17" )
			)
			( signal "TP_CPU1_UPI2_RSVD_DK19"
				( objectStatus "@baseboard_fab2_lib.baseboard_fab2(sch_1):tp_cpu1_upi2_rsvd_dk19" )
			)
			( signal "TP_CPU1_UPI2_RSVD_DL20"
				( objectStatus "@baseboard_fab2_lib.baseboard_fab2(sch_1):tp_cpu1_upi2_rsvd_dl20" )
			)
			( signal "TP_CPU1_UPI2_RSVD_DM21"
				( objectStatus "@baseboard_fab2_lib.baseboard_fab2(sch_1):tp_cpu1_upi2_rsvd_dm21" )
			)
			( signal "TP_CPU1_UPI2_RSVD_DN20"
				( objectStatus "@baseboard_fab2_lib.baseboard_fab2(sch_1):tp_cpu1_upi2_rsvd_dn20" )
			)
			( signal "TP_CPU1_UPI2_RSVD_DP21"
				( objectStatus "@baseboard_fab2_lib.baseboard_fab2(sch_1):tp_cpu1_upi2_rsvd_dp21" )
			)
			( signal "TP_CPU1_UPI2_RSVD_DT21"
				( objectStatus "@baseboard_fab2_lib.baseboard_fab2(sch_1):tp_cpu1_upi2_rsvd_dt21" )
			)
			( signal "CLK_100M_CPU1_RC_REFCLK1_DN"
				( objectStatus "@baseboard_fab2_lib.baseboard_fab2(sch_1):clk_100m_cpu1_rc_refclk1_dn" )
			)
			( signal "CLK_100M_CPU1_RC_REFCLK1_DP"
				( objectStatus "@baseboard_fab2_lib.baseboard_fab2(sch_1):clk_100m_cpu1_rc_refclk1_dp" )
			)
			( signal "TP_CPU1_RSVD_100"
				( objectStatus "@baseboard_fab2_lib.baseboard_fab2(sch_1):tp_cpu1_rsvd_100" )
			)
			( signal "TP_CPU1_RSVD_101"
				( objectStatus "@baseboard_fab2_lib.baseboard_fab2(sch_1):tp_cpu1_rsvd_101" )
			)
			( signal "TP_CPU1_RSVD_105"
				( objectStatus "@baseboard_fab2_lib.baseboard_fab2(sch_1):tp_cpu1_rsvd_105" )
			)
			( signal "TP_CPU1_RSVD_106"
				( objectStatus "@baseboard_fab2_lib.baseboard_fab2(sch_1):tp_cpu1_rsvd_106" )
			)
			( signal "TP_CPU1_RSVD_108"
				( objectStatus "@baseboard_fab2_lib.baseboard_fab2(sch_1):tp_cpu1_rsvd_108" )
			)
			( signal "TP_CPU1_RSVD_111"
				( objectStatus "@baseboard_fab2_lib.baseboard_fab2(sch_1):tp_cpu1_rsvd_111" )
			)
			( signal "TP_CPU1_RSVD_113"
				( objectStatus "@baseboard_fab2_lib.baseboard_fab2(sch_1):tp_cpu1_rsvd_113" )
			)
			( signal "TP_CPU1_RSVD_114"
				( objectStatus "@baseboard_fab2_lib.baseboard_fab2(sch_1):tp_cpu1_rsvd_114" )
			)
			( signal "TP_CPU1_RSVD_117"
				( objectStatus "@baseboard_fab2_lib.baseboard_fab2(sch_1):tp_cpu1_rsvd_117" )
			)
			( signal "TP_CPU1_RSVD_119"
				( objectStatus "@baseboard_fab2_lib.baseboard_fab2(sch_1):tp_cpu1_rsvd_119" )
			)
			( signal "TP_CPU1_RSVD_121"
				( objectStatus "@baseboard_fab2_lib.baseboard_fab2(sch_1):tp_cpu1_rsvd_121" )
			)
			( signal "TP_CPU1_RSVD_123"
				( objectStatus "@baseboard_fab2_lib.baseboard_fab2(sch_1):tp_cpu1_rsvd_123" )
			)
			( signal "TP_CPU1_RSVD_124"
				( objectStatus "@baseboard_fab2_lib.baseboard_fab2(sch_1):tp_cpu1_rsvd_124" )
			)
			( signal "TP_CPU1_RSVD_144"
				( objectStatus "@baseboard_fab2_lib.baseboard_fab2(sch_1):tp_cpu1_rsvd_144" )
			)
			( signal "TP_CPU1_RSVD_145"
				( objectStatus "@baseboard_fab2_lib.baseboard_fab2(sch_1):tp_cpu1_rsvd_145" )
			)
			( signal "TP_CPU1_RSVD_146"
				( objectStatus "@baseboard_fab2_lib.baseboard_fab2(sch_1):tp_cpu1_rsvd_146" )
			)
			( signal "TP_CPU1_RSVD_147"
				( objectStatus "@baseboard_fab2_lib.baseboard_fab2(sch_1):tp_cpu1_rsvd_147" )
			)
			( signal "TP_CPU1_RSVD_148"
				( objectStatus "@baseboard_fab2_lib.baseboard_fab2(sch_1):tp_cpu1_rsvd_148" )
			)
			( signal "TP_CPU1_RSVD_149"
				( objectStatus "@baseboard_fab2_lib.baseboard_fab2(sch_1):tp_cpu1_rsvd_149" )
			)
			( signal "TP_CPU1_RSVD_150"
				( objectStatus "@baseboard_fab2_lib.baseboard_fab2(sch_1):tp_cpu1_rsvd_150" )
			)
			( signal "TP_CPU1_RSVD_151"
				( objectStatus "@baseboard_fab2_lib.baseboard_fab2(sch_1):tp_cpu1_rsvd_151" )
			)
			( signal "TP_CPU1_RSVD_152"
				( objectStatus "@baseboard_fab2_lib.baseboard_fab2(sch_1):tp_cpu1_rsvd_152" )
			)
			( signal "TP_CPU1_RSVD_154"
				( objectStatus "@baseboard_fab2_lib.baseboard_fab2(sch_1):tp_cpu1_rsvd_154" )
			)
			( signal "TP_CPU1_RSVD_155"
				( objectStatus "@baseboard_fab2_lib.baseboard_fab2(sch_1):tp_cpu1_rsvd_155" )
			)
			( signal "TP_CPU1_RSVD_156"
				( objectStatus "@baseboard_fab2_lib.baseboard_fab2(sch_1):tp_cpu1_rsvd_156" )
			)
			( signal "TP_CPU1_RSVD_157"
				( objectStatus "@baseboard_fab2_lib.baseboard_fab2(sch_1):tp_cpu1_rsvd_157" )
			)
			( signal "TP_CPU1_RSVD_158"
				( objectStatus "@baseboard_fab2_lib.baseboard_fab2(sch_1):tp_cpu1_rsvd_158" )
			)
			( signal "TP_CPU1_RSVD_159"
				( objectStatus "@baseboard_fab2_lib.baseboard_fab2(sch_1):tp_cpu1_rsvd_159" )
			)
			( signal "TP_CPU1_RSVD_160"
				( objectStatus "@baseboard_fab2_lib.baseboard_fab2(sch_1):tp_cpu1_rsvd_160" )
			)
			( signal "TP_CPU1_RSVD_161"
				( objectStatus "@baseboard_fab2_lib.baseboard_fab2(sch_1):tp_cpu1_rsvd_161" )
			)
			( signal "TP_CPU1_RSVD_162"
				( objectStatus "@baseboard_fab2_lib.baseboard_fab2(sch_1):tp_cpu1_rsvd_162" )
			)
			( signal "TP_CPU1_RSVD_163"
				( objectStatus "@baseboard_fab2_lib.baseboard_fab2(sch_1):tp_cpu1_rsvd_163" )
			)
			( signal "TP_CPU1_RSVD_164"
				( objectStatus "@baseboard_fab2_lib.baseboard_fab2(sch_1):tp_cpu1_rsvd_164" )
			)
			( signal "TP_CPU1_RSVD_166"
				( objectStatus "@baseboard_fab2_lib.baseboard_fab2(sch_1):tp_cpu1_rsvd_166" )
			)
			( signal "TP_CPU1_RSVD_167"
				( objectStatus "@baseboard_fab2_lib.baseboard_fab2(sch_1):tp_cpu1_rsvd_167" )
			)
			( signal "TP_CPU1_RSVD_168"
				( objectStatus "@baseboard_fab2_lib.baseboard_fab2(sch_1):tp_cpu1_rsvd_168" )
			)
			( signal "TP_CPU1_RSVD_169"
				( objectStatus "@baseboard_fab2_lib.baseboard_fab2(sch_1):tp_cpu1_rsvd_169" )
			)
			( signal "TP_CPU1_RSVD_170"
				( objectStatus "@baseboard_fab2_lib.baseboard_fab2(sch_1):tp_cpu1_rsvd_170" )
			)
			( signal "TP_CPU1_RSVD_171"
				( objectStatus "@baseboard_fab2_lib.baseboard_fab2(sch_1):tp_cpu1_rsvd_171" )
			)
			( signal "TP_CPU1_RSVD_255"
				( objectStatus "@baseboard_fab2_lib.baseboard_fab2(sch_1):tp_cpu1_rsvd_255" )
			)
			( signal "TP_CPU1_RSVD_82"
				( objectStatus "@baseboard_fab2_lib.baseboard_fab2(sch_1):tp_cpu1_rsvd_82" )
			)
			( signal "TP_CPU1_RSVD_85"
				( objectStatus "@baseboard_fab2_lib.baseboard_fab2(sch_1):tp_cpu1_rsvd_85" )
			)
			( signal "TP_CPU1_RSVD_90"
				( objectStatus "@baseboard_fab2_lib.baseboard_fab2(sch_1):tp_cpu1_rsvd_90" )
			)
			( signal "TP_CPU1_RSVD_91"
				( objectStatus "@baseboard_fab2_lib.baseboard_fab2(sch_1):tp_cpu1_rsvd_91" )
			)
			( signal "TP_CPU1_RSVD_94"
				( objectStatus "@baseboard_fab2_lib.baseboard_fab2(sch_1):tp_cpu1_rsvd_94" )
			)
			( signal "TP_CPU1_RSVD_95"
				( objectStatus "@baseboard_fab2_lib.baseboard_fab2(sch_1):tp_cpu1_rsvd_95" )
			)
			( signal "TP_CPU1_RSVD_97"
				( objectStatus "@baseboard_fab2_lib.baseboard_fab2(sch_1):tp_cpu1_rsvd_97" )
			)
			( signal "TP_CPU1_RSVD_99"
				( objectStatus "@baseboard_fab2_lib.baseboard_fab2(sch_1):tp_cpu1_rsvd_99" )
			)
			( signal "TP_CPU1_TEST_10"
				( objectStatus "@baseboard_fab2_lib.baseboard_fab2(sch_1):tp_cpu1_test_10" )
			)
			( signal "TP_CPU1_TEST_6"
				( objectStatus "@baseboard_fab2_lib.baseboard_fab2(sch_1):tp_cpu1_test_6" )
			)
			( signal "TP_CPU1_TEST_7"
				( objectStatus "@baseboard_fab2_lib.baseboard_fab2(sch_1):tp_cpu1_test_7" )
			)
			( signal "TP_CPU1_TEST_8"
				( objectStatus "@baseboard_fab2_lib.baseboard_fab2(sch_1):tp_cpu1_test_8" )
			)
			( signal "TP_CPU1_TEST_9"
				( objectStatus "@baseboard_fab2_lib.baseboard_fab2(sch_1):tp_cpu1_test_9" )
			)
			( signal "PVCCIN_CPU1"
				( attribute "VOLTAGE" "2.0V"
					( Units "uVoltage" "V" 1.000000)
					( Status sAliasFlattened )
					( Origin gFrontEnd )
				)
				( objectStatus "@baseboard_fab2_lib.baseboard_fab2(sch_1):pvccin_cpu1" )
			)
			( signal "VSENSE_PMAX_CPU1"
				( objectStatus "@baseboard_fab2_lib.baseboard_fab2(sch_1):vsense_pmax_cpu1" )
			)
			( signal "VSENSE_PVCCIN_CPU1_SKT_VRTN"
				( attribute "VOLTAGE" "0.3"
					( Units "uVoltage" "V" 1.000000)
					( Status sAliasFlattened )
					( Origin gFrontEnd )
				)
				( objectStatus "@baseboard_fab2_lib.baseboard_fab2(sch_1):vsense_pvccin_cpu1_skt_vrtn" )
			)
			( signal "VSENSE_PVCCIN_CPU1_SKT_VSEN"
				( attribute "VOLTAGE" "2.0"
					( Units "uVoltage" "V" 1.000000)
					( Status sAliasFlattened )
					( Origin gFrontEnd )
				)
				( objectStatus "@baseboard_fab2_lib.baseboard_fab2(sch_1):vsense_pvccin_cpu1_skt_vsen" )
			)
			( signal "VSENSE_VCCINR2PMAX_CPU1"
				( objectStatus "@baseboard_fab2_lib.baseboard_fab2(sch_1):vsense_vccinr2pmax_cpu1" )
			)
			( signal "PVCCIOMCP_CPU1"
				( attribute "VOLTAGE" "+0.95V"
					( Units "uVoltage" "V" 1.000000)
					( Status sAliasFlattened )
					( Status sAliasConflict )
					( Origin gFrontEnd )
				)
				( objectStatus "@baseboard_fab2_lib.baseboard_fab2(sch_1):pvcciomcp_cpu1" )
			)
			( signal "PVDDQ_GHJ"
				( attribute "VOLTAGE" "1.2V"
					( Units "uVoltage" "V" 1.000000)
					( Status sAliasFlattened )
					( Origin gFrontEnd )
				)
				( objectStatus "@baseboard_fab2_lib.baseboard_fab2(sch_1):pvddq_ghj" )
			)
			( signal "PVDDQ_KLM"
				( attribute "VOLTAGE" "1.2V"
					( Units "uVoltage" "V" 1.000000)
					( Status sAliasFlattened )
					( Origin gFrontEnd )
				)
				( objectStatus "@baseboard_fab2_lib.baseboard_fab2(sch_1):pvddq_klm" )
			)
			( signal "PVPP_GHJ"
				( attribute "VOLTAGE" "2.5V"
					( Units "uVoltage" "V" 1.000000)
					( Status sAliasFlattened )
					( Origin gFrontEnd )
				)
				( objectStatus "@baseboard_fab2_lib.baseboard_fab2(sch_1):pvpp_ghj" )
			)
			( signal "PVSA_CPU1"
				( attribute "VOLTAGE" "1.1V"
					( Units "uVoltage" "V" 1.000000)
					( Status sAliasFlattened )
					( Origin gFrontEnd )
				)
				( objectStatus "@baseboard_fab2_lib.baseboard_fab2(sch_1):pvsa_cpu1" )
			)
			( signal "PD_CPU1_MCP01_DMON"
				( objectStatus "@baseboard_fab2_lib.baseboard_fab2(sch_1):pd_cpu1_mcp01_dmon" )
			)
			( signal "TP_CPU1_KTI2_AMONV"
				( objectStatus "@baseboard_fab2_lib.baseboard_fab2(sch_1):tp_cpu1_kti2_amonv" )
			)
			( signal "TP_CPU1_KTI2_DFX_DN"
				( objectStatus "@baseboard_fab2_lib.baseboard_fab2(sch_1):tp_cpu1_kti2_dfx_dn" )
			)
			( signal "TP_CPU1_RSVD_0"
				( objectStatus "@baseboard_fab2_lib.baseboard_fab2(sch_1):tp_cpu1_rsvd_0" )
			)
			( signal "TP_CPU1_RSVD_1"
				( objectStatus "@baseboard_fab2_lib.baseboard_fab2(sch_1):tp_cpu1_rsvd_1" )
			)
			( signal "TP_CPU1_RSVD_10"
				( objectStatus "@baseboard_fab2_lib.baseboard_fab2(sch_1):tp_cpu1_rsvd_10" )
			)
			( signal "TP_CPU1_RSVD_11"
				( objectStatus "@baseboard_fab2_lib.baseboard_fab2(sch_1):tp_cpu1_rsvd_11" )
			)
			( signal "TP_CPU1_RSVD_12"
				( objectStatus "@baseboard_fab2_lib.baseboard_fab2(sch_1):tp_cpu1_rsvd_12" )
			)
			( signal "TP_CPU1_RSVD_13"
				( objectStatus "@baseboard_fab2_lib.baseboard_fab2(sch_1):tp_cpu1_rsvd_13" )
			)
			( signal "TP_CPU1_RSVD_14"
				( objectStatus "@baseboard_fab2_lib.baseboard_fab2(sch_1):tp_cpu1_rsvd_14" )
			)
			( signal "TP_CPU1_RSVD_15"
				( objectStatus "@baseboard_fab2_lib.baseboard_fab2(sch_1):tp_cpu1_rsvd_15" )
			)
			( signal "TP_CPU1_RSVD_16"
				( objectStatus "@baseboard_fab2_lib.baseboard_fab2(sch_1):tp_cpu1_rsvd_16" )
			)
			( signal "TP_CPU1_RSVD_17"
				( objectStatus "@baseboard_fab2_lib.baseboard_fab2(sch_1):tp_cpu1_rsvd_17" )
			)
			( signal "TP_CPU1_RSVD_18"
				( objectStatus "@baseboard_fab2_lib.baseboard_fab2(sch_1):tp_cpu1_rsvd_18" )
			)
			( signal "TP_CPU1_RSVD_19"
				( objectStatus "@baseboard_fab2_lib.baseboard_fab2(sch_1):tp_cpu1_rsvd_19" )
			)
			( signal "TP_CPU1_RSVD_2"
				( objectStatus "@baseboard_fab2_lib.baseboard_fab2(sch_1):tp_cpu1_rsvd_2" )
			)
			( signal "TP_CPU1_RSVD_20"
				( objectStatus "@baseboard_fab2_lib.baseboard_fab2(sch_1):tp_cpu1_rsvd_20" )
			)
			( signal "TP_CPU1_RSVD_21"
				( objectStatus "@baseboard_fab2_lib.baseboard_fab2(sch_1):tp_cpu1_rsvd_21" )
			)
			( signal "TP_CPU1_RSVD_22"
				( objectStatus "@baseboard_fab2_lib.baseboard_fab2(sch_1):tp_cpu1_rsvd_22" )
			)
			( signal "TP_CPU1_RSVD_23"
				( objectStatus "@baseboard_fab2_lib.baseboard_fab2(sch_1):tp_cpu1_rsvd_23" )
			)
			( signal "TP_CPU1_RSVD_24"
				( objectStatus "@baseboard_fab2_lib.baseboard_fab2(sch_1):tp_cpu1_rsvd_24" )
			)
			( signal "TP_CPU1_RSVD_25"
				( objectStatus "@baseboard_fab2_lib.baseboard_fab2(sch_1):tp_cpu1_rsvd_25" )
			)
			( signal "TP_CPU1_RSVD_26"
				( objectStatus "@baseboard_fab2_lib.baseboard_fab2(sch_1):tp_cpu1_rsvd_26" )
			)
			( signal "TP_CPU1_RSVD_27"
				( objectStatus "@baseboard_fab2_lib.baseboard_fab2(sch_1):tp_cpu1_rsvd_27" )
			)
			( signal "TP_CPU1_RSVD_28"
				( objectStatus "@baseboard_fab2_lib.baseboard_fab2(sch_1):tp_cpu1_rsvd_28" )
			)
			( signal "TP_CPU1_RSVD_29"
				( objectStatus "@baseboard_fab2_lib.baseboard_fab2(sch_1):tp_cpu1_rsvd_29" )
			)
			( signal "TP_CPU1_RSVD_3"
				( objectStatus "@baseboard_fab2_lib.baseboard_fab2(sch_1):tp_cpu1_rsvd_3" )
			)
			( signal "TP_CPU1_RSVD_30"
				( objectStatus "@baseboard_fab2_lib.baseboard_fab2(sch_1):tp_cpu1_rsvd_30" )
			)
			( signal "TP_CPU1_RSVD_31"
				( objectStatus "@baseboard_fab2_lib.baseboard_fab2(sch_1):tp_cpu1_rsvd_31" )
			)
			( signal "TP_CPU1_RSVD_32"
				( objectStatus "@baseboard_fab2_lib.baseboard_fab2(sch_1):tp_cpu1_rsvd_32" )
			)
			( signal "TP_CPU1_RSVD_33"
				( objectStatus "@baseboard_fab2_lib.baseboard_fab2(sch_1):tp_cpu1_rsvd_33" )
			)
			( signal "TP_CPU1_RSVD_34"
				( objectStatus "@baseboard_fab2_lib.baseboard_fab2(sch_1):tp_cpu1_rsvd_34" )
			)
			( signal "TP_CPU1_RSVD_35"
				( objectStatus "@baseboard_fab2_lib.baseboard_fab2(sch_1):tp_cpu1_rsvd_35" )
			)
			( signal "TP_CPU1_RSVD_36"
				( objectStatus "@baseboard_fab2_lib.baseboard_fab2(sch_1):tp_cpu1_rsvd_36" )
			)
			( signal "TP_CPU1_RSVD_37"
				( objectStatus "@baseboard_fab2_lib.baseboard_fab2(sch_1):tp_cpu1_rsvd_37" )
			)
			( signal "TP_CPU1_RSVD_38"
				( objectStatus "@baseboard_fab2_lib.baseboard_fab2(sch_1):tp_cpu1_rsvd_38" )
			)
			( signal "TP_CPU1_RSVD_39"
				( objectStatus "@baseboard_fab2_lib.baseboard_fab2(sch_1):tp_cpu1_rsvd_39" )
			)
			( signal "TP_CPU1_RSVD_4"
				( objectStatus "@baseboard_fab2_lib.baseboard_fab2(sch_1):tp_cpu1_rsvd_4" )
			)
			( signal "TP_CPU1_RSVD_40"
				( objectStatus "@baseboard_fab2_lib.baseboard_fab2(sch_1):tp_cpu1_rsvd_40" )
			)
			( signal "TP_CPU1_RSVD_41"
				( objectStatus "@baseboard_fab2_lib.baseboard_fab2(sch_1):tp_cpu1_rsvd_41" )
			)
			( signal "TP_CPU1_RSVD_42"
				( objectStatus "@baseboard_fab2_lib.baseboard_fab2(sch_1):tp_cpu1_rsvd_42" )
			)
			( signal "TP_CPU1_RSVD_43"
				( objectStatus "@baseboard_fab2_lib.baseboard_fab2(sch_1):tp_cpu1_rsvd_43" )
			)
			( signal "TP_CPU1_RSVD_44"
				( objectStatus "@baseboard_fab2_lib.baseboard_fab2(sch_1):tp_cpu1_rsvd_44" )
			)
			( signal "TP_CPU1_RSVD_45"
				( objectStatus "@baseboard_fab2_lib.baseboard_fab2(sch_1):tp_cpu1_rsvd_45" )
			)
			( signal "TP_CPU1_RSVD_46"
				( objectStatus "@baseboard_fab2_lib.baseboard_fab2(sch_1):tp_cpu1_rsvd_46" )
			)
			( signal "TP_CPU1_RSVD_47"
				( objectStatus "@baseboard_fab2_lib.baseboard_fab2(sch_1):tp_cpu1_rsvd_47" )
			)
			( signal "TP_CPU1_RSVD_48"
				( objectStatus "@baseboard_fab2_lib.baseboard_fab2(sch_1):tp_cpu1_rsvd_48" )
			)
			( signal "TP_CPU1_RSVD_49"
				( objectStatus "@baseboard_fab2_lib.baseboard_fab2(sch_1):tp_cpu1_rsvd_49" )
			)
			( signal "TP_CPU1_RSVD_5"
				( objectStatus "@baseboard_fab2_lib.baseboard_fab2(sch_1):tp_cpu1_rsvd_5" )
			)
			( signal "TP_CPU1_RSVD_50"
				( objectStatus "@baseboard_fab2_lib.baseboard_fab2(sch_1):tp_cpu1_rsvd_50" )
			)
			( signal "TP_CPU1_RSVD_51"
				( objectStatus "@baseboard_fab2_lib.baseboard_fab2(sch_1):tp_cpu1_rsvd_51" )
			)
			( signal "TP_CPU1_RSVD_53"
				( objectStatus "@baseboard_fab2_lib.baseboard_fab2(sch_1):tp_cpu1_rsvd_53" )
			)
			( signal "TP_CPU1_RSVD_54"
				( objectStatus "@baseboard_fab2_lib.baseboard_fab2(sch_1):tp_cpu1_rsvd_54" )
			)
			( signal "TP_CPU1_RSVD_55"
				( objectStatus "@baseboard_fab2_lib.baseboard_fab2(sch_1):tp_cpu1_rsvd_55" )
			)
			( signal "TP_CPU1_RSVD_56"
				( objectStatus "@baseboard_fab2_lib.baseboard_fab2(sch_1):tp_cpu1_rsvd_56" )
			)
			( signal "TP_CPU1_RSVD_57"
				( objectStatus "@baseboard_fab2_lib.baseboard_fab2(sch_1):tp_cpu1_rsvd_57" )
			)
			( signal "TP_CPU1_RSVD_59"
				( objectStatus "@baseboard_fab2_lib.baseboard_fab2(sch_1):tp_cpu1_rsvd_59" )
			)
			( signal "TP_CPU1_RSVD_6"
				( objectStatus "@baseboard_fab2_lib.baseboard_fab2(sch_1):tp_cpu1_rsvd_6" )
			)
			( signal "TP_CPU1_RSVD_60"
				( objectStatus "@baseboard_fab2_lib.baseboard_fab2(sch_1):tp_cpu1_rsvd_60" )
			)
			( signal "TP_CPU1_RSVD_61"
				( objectStatus "@baseboard_fab2_lib.baseboard_fab2(sch_1):tp_cpu1_rsvd_61" )
			)
			( signal "TP_CPU1_RSVD_64"
				( objectStatus "@baseboard_fab2_lib.baseboard_fab2(sch_1):tp_cpu1_rsvd_64" )
			)
			( signal "TP_CPU1_RSVD_66"
				( objectStatus "@baseboard_fab2_lib.baseboard_fab2(sch_1):tp_cpu1_rsvd_66" )
			)
			( signal "TP_CPU1_RSVD_67"
				( objectStatus "@baseboard_fab2_lib.baseboard_fab2(sch_1):tp_cpu1_rsvd_67" )
			)
			( signal "TP_CPU1_RSVD_69"
				( objectStatus "@baseboard_fab2_lib.baseboard_fab2(sch_1):tp_cpu1_rsvd_69" )
			)
			( signal "TP_CPU1_RSVD_7"
				( objectStatus "@baseboard_fab2_lib.baseboard_fab2(sch_1):tp_cpu1_rsvd_7" )
			)
			( signal "TP_CPU1_RSVD_70"
				( objectStatus "@baseboard_fab2_lib.baseboard_fab2(sch_1):tp_cpu1_rsvd_70" )
			)
			( signal "TP_CPU1_RSVD_72"
				( objectStatus "@baseboard_fab2_lib.baseboard_fab2(sch_1):tp_cpu1_rsvd_72" )
			)
			( signal "TP_CPU1_RSVD_73"
				( objectStatus "@baseboard_fab2_lib.baseboard_fab2(sch_1):tp_cpu1_rsvd_73" )
			)
			( signal "TP_CPU1_RSVD_8"
				( objectStatus "@baseboard_fab2_lib.baseboard_fab2(sch_1):tp_cpu1_rsvd_8" )
			)
			( signal "TP_CPU1_RSVD_9"
				( objectStatus "@baseboard_fab2_lib.baseboard_fab2(sch_1):tp_cpu1_rsvd_9" )
			)
			( signal "VSENSE_PVCCIO_CPU1_SKT_VRTN"
				( objectStatus "@baseboard_fab2_lib.baseboard_fab2(sch_1):vsense_pvccio_cpu1_skt_vrtn" )
			)
			( signal "VSENSE_PVCCIO_CPU1_SKT_VSEN"
				( objectStatus "@baseboard_fab2_lib.baseboard_fab2(sch_1):vsense_pvccio_cpu1_skt_vsen" )
			)
			( signal "VSENSE_PVCCIOMCP_CPU1_SKT_VRTN"
				( objectStatus "@baseboard_fab2_lib.baseboard_fab2(sch_1):vsense_pvcciomcp_cpu1_skt_vrtn" )
			)
			( signal "VSENSE_PVCCIOMCP_CPU1_SKT_VSEN"
				( objectStatus "@baseboard_fab2_lib.baseboard_fab2(sch_1):vsense_pvcciomcp_cpu1_skt_vsen" )
			)
			( signal "VSENSE_PVCCMCP_CPU1_SKT_VRTN"
				( objectStatus "@baseboard_fab2_lib.baseboard_fab2(sch_1):vsense_pvccmcp_cpu1_skt_vrtn" )
			)
			( signal "VSENSE_PVCCMCP_CPU1_SKT_VSEN"
				( objectStatus "@baseboard_fab2_lib.baseboard_fab2(sch_1):vsense_pvccmcp_cpu1_skt_vsen" )
			)
			( signal "VSENSE_PVSA_CPU1_SKT_VRTN"
				( attribute "VOLTAGE" "0.3"
					( Units "uVoltage" "V" 1.000000)
					( Status sAliasFlattened )
					( Origin gFrontEnd )
				)
				( objectStatus "@baseboard_fab2_lib.baseboard_fab2(sch_1):vsense_pvsa_cpu1_skt_vrtn" )
			)
			( signal "VSENSE_PVSA_CPU1_SKT_VSEN"
				( attribute "VOLTAGE" "1.0"
					( Units "uVoltage" "V" 1.000000)
					( Status sAliasFlattened )
					( Origin gFrontEnd )
				)
				( objectStatus "@baseboard_fab2_lib.baseboard_fab2(sch_1):vsense_pvsa_cpu1_skt_vsen" )
			)
			( signal "FM_ADR_COMPLETE_GHJ_N"
				( objectStatus "@baseboard_fab2_lib.baseboard_fab2(sch_1):fm_adr_complete_ghj_n" )
			)
			( signal "M_G_VREF"
				( objectStatus "@baseboard_fab2_lib.baseboard_fab2(sch_1):m_g_vref" )
			)
			( signal "P12V_NVDIMM_GHJ"
				( attribute "VOLTAGE" "12.0"
					( Units "uVoltage" "V" 1.000000)
					( Status sAliasFlattened )
					( Origin gFrontEnd )
				)
				( objectStatus "@baseboard_fab2_lib.baseboard_fab2(sch_1):p12v_nvdimm_ghj" )
			)
			( signal "PVTT_GHJ"
				( attribute "VOLTAGE" "0.6V"
					( Units "uVoltage" "V" 1.000000)
					( Status sAliasFlattened )
					( Origin gFrontEnd )
				)
				( objectStatus "@baseboard_fab2_lib.baseboard_fab2(sch_1):pvtt_ghj" )
			)
			( signal "SMB_DDR_GHJ_VPP_SCL"
				( objectStatus "@baseboard_fab2_lib.baseboard_fab2(sch_1):smb_ddr_ghj_vpp_scl" )
			)
			( signal "SMB_DDR_GHJ_VPP_SDA"
				( objectStatus "@baseboard_fab2_lib.baseboard_fab2(sch_1):smb_ddr_ghj_vpp_sda" )
			)
			( signal "TP_CH_G_DIMM_G0_RFU_0"
				( objectStatus "@baseboard_fab2_lib.baseboard_fab2(sch_1):tp_ch_g_dimm_g0_rfu_0" )
			)
			( signal "TP_CH_G_DIMM_G0_RFU_1"
				( objectStatus "@baseboard_fab2_lib.baseboard_fab2(sch_1):tp_ch_g_dimm_g0_rfu_1" )
			)
			( signal "TP_CH_G_DIMM_G0_RFU_2"
				( objectStatus "@baseboard_fab2_lib.baseboard_fab2(sch_1):tp_ch_g_dimm_g0_rfu_2" )
			)
			( signal "TP_CH_G_DIMM0_RFU_0"
				( objectStatus "@baseboard_fab2_lib.baseboard_fab2(sch_1):tp_ch_g_dimm0_rfu_0" )
			)
			( signal "TP_CH_G_DIMM0_RFU_1"
				( objectStatus "@baseboard_fab2_lib.baseboard_fab2(sch_1):tp_ch_g_dimm0_rfu_1" )
			)
			( signal "TP_CH_G_DIMM0_RFU_2"
				( objectStatus "@baseboard_fab2_lib.baseboard_fab2(sch_1):tp_ch_g_dimm0_rfu_2" )
			)
			( signal "M_H_VREF"
				( objectStatus "@baseboard_fab2_lib.baseboard_fab2(sch_1):m_h_vref" )
			)
			( signal "TP_CH_H_DIMM_H0_RFU_0"
				( objectStatus "@baseboard_fab2_lib.baseboard_fab2(sch_1):tp_ch_h_dimm_h0_rfu_0" )
			)
			( signal "TP_CH_H_DIMM_H0_RFU_1"
				( objectStatus "@baseboard_fab2_lib.baseboard_fab2(sch_1):tp_ch_h_dimm_h0_rfu_1" )
			)
			( signal "TP_CH_H_DIMM_H0_RFU_2"
				( objectStatus "@baseboard_fab2_lib.baseboard_fab2(sch_1):tp_ch_h_dimm_h0_rfu_2" )
			)
			( signal "TP_CH_H_DIMM0_RFU_0"
				( objectStatus "@baseboard_fab2_lib.baseboard_fab2(sch_1):tp_ch_h_dimm0_rfu_0" )
			)
			( signal "TP_CH_H_DIMM0_RFU_1"
				( objectStatus "@baseboard_fab2_lib.baseboard_fab2(sch_1):tp_ch_h_dimm0_rfu_1" )
			)
			( signal "TP_CH_H_DIMM0_RFU_2"
				( objectStatus "@baseboard_fab2_lib.baseboard_fab2(sch_1):tp_ch_h_dimm0_rfu_2" )
			)
			( signal "M_J_VREF"
				( objectStatus "@baseboard_fab2_lib.baseboard_fab2(sch_1):m_j_vref" )
			)
			( signal "TP_CH_J_DIMM_J0_RFU_0"
				( objectStatus "@baseboard_fab2_lib.baseboard_fab2(sch_1):tp_ch_j_dimm_j0_rfu_0" )
			)
			( signal "TP_CH_J_DIMM_J0_RFU_1"
				( objectStatus "@baseboard_fab2_lib.baseboard_fab2(sch_1):tp_ch_j_dimm_j0_rfu_1" )
			)
			( signal "TP_CH_J_DIMM_J0_RFU_2"
				( objectStatus "@baseboard_fab2_lib.baseboard_fab2(sch_1):tp_ch_j_dimm_j0_rfu_2" )
			)
			( signal "TP_CH_J_DIMM_J1_RFU_0"
				( objectStatus "@baseboard_fab2_lib.baseboard_fab2(sch_1):tp_ch_j_dimm_j1_rfu_0" )
			)
			( signal "TP_CH_J_DIMM_J1_RFU_1"
				( objectStatus "@baseboard_fab2_lib.baseboard_fab2(sch_1):tp_ch_j_dimm_j1_rfu_1" )
			)
			( signal "TP_CH_J_DIMM_J1_RFU_2"
				( objectStatus "@baseboard_fab2_lib.baseboard_fab2(sch_1):tp_ch_j_dimm_j1_rfu_2" )
			)
			( signal "FM_ADR_COMPLETE_KLM_N"
				( objectStatus "@baseboard_fab2_lib.baseboard_fab2(sch_1):fm_adr_complete_klm_n" )
			)
			( signal "M_K_VREF"
				( objectStatus "@baseboard_fab2_lib.baseboard_fab2(sch_1):m_k_vref" )
			)
			( signal "P12V_NVDIMM_KLM"
				( attribute "VOLTAGE" "12.0"
					( Units "uVoltage" "V" 1.000000)
					( Status sAliasFlattened )
					( Origin gFrontEnd )
				)
				( objectStatus "@baseboard_fab2_lib.baseboard_fab2(sch_1):p12v_nvdimm_klm" )
			)
			( signal "PVPP_KLM"
				( attribute "VOLTAGE" "2.5V"
					( Units "uVoltage" "V" 1.000000)
					( Status sAliasFlattened )
					( Origin gFrontEnd )
				)
				( objectStatus "@baseboard_fab2_lib.baseboard_fab2(sch_1):pvpp_klm" )
			)
			( signal "PVTT_KLM"
				( attribute "VOLTAGE" "0.6V"
					( Units "uVoltage" "V" 1.000000)
					( Status sAliasFlattened )
					( Origin gFrontEnd )
				)
				( objectStatus "@baseboard_fab2_lib.baseboard_fab2(sch_1):pvtt_klm" )
			)
			( signal "SMB_DDR_KLM_VPP_SCL"
				( objectStatus "@baseboard_fab2_lib.baseboard_fab2(sch_1):smb_ddr_klm_vpp_scl" )
			)
			( signal "SMB_DDR_KLM_VPP_SDA"
				( objectStatus "@baseboard_fab2_lib.baseboard_fab2(sch_1):smb_ddr_klm_vpp_sda" )
			)
			( signal "TP_CH_K_DIMM_K0_RFU_0"
				( objectStatus "@baseboard_fab2_lib.baseboard_fab2(sch_1):tp_ch_k_dimm_k0_rfu_0" )
			)
			( signal "TP_CH_K_DIMM_K0_RFU_1"
				( objectStatus "@baseboard_fab2_lib.baseboard_fab2(sch_1):tp_ch_k_dimm_k0_rfu_1" )
			)
			( signal "TP_CH_K_DIMM_K0_RFU_2"
				( objectStatus "@baseboard_fab2_lib.baseboard_fab2(sch_1):tp_ch_k_dimm_k0_rfu_2" )
			)
			( signal "TP_CH_K_DIMM0_RFU_0"
				( objectStatus "@baseboard_fab2_lib.baseboard_fab2(sch_1):tp_ch_k_dimm0_rfu_0" )
			)
			( signal "TP_CH_K_DIMM0_RFU_1"
				( objectStatus "@baseboard_fab2_lib.baseboard_fab2(sch_1):tp_ch_k_dimm0_rfu_1" )
			)
			( signal "TP_CH_K_DIMM0_RFU_2"
				( objectStatus "@baseboard_fab2_lib.baseboard_fab2(sch_1):tp_ch_k_dimm0_rfu_2" )
			)
			( signal "M_L_VREF"
				( objectStatus "@baseboard_fab2_lib.baseboard_fab2(sch_1):m_l_vref" )
			)
			( signal "TP_CH_L_DIMM_L0_RFU_0"
				( objectStatus "@baseboard_fab2_lib.baseboard_fab2(sch_1):tp_ch_l_dimm_l0_rfu_0" )
			)
			( signal "TP_CH_L_DIMM_L0_RFU_1"
				( objectStatus "@baseboard_fab2_lib.baseboard_fab2(sch_1):tp_ch_l_dimm_l0_rfu_1" )
			)
			( signal "TP_CH_L_DIMM_L0_RFU_2"
				( objectStatus "@baseboard_fab2_lib.baseboard_fab2(sch_1):tp_ch_l_dimm_l0_rfu_2" )
			)
			( signal "TP_CH_L_DIMM0_RFU_0"
				( objectStatus "@baseboard_fab2_lib.baseboard_fab2(sch_1):tp_ch_l_dimm0_rfu_0" )
			)
			( signal "TP_CH_L_DIMM0_RFU_1"
				( objectStatus "@baseboard_fab2_lib.baseboard_fab2(sch_1):tp_ch_l_dimm0_rfu_1" )
			)
			( signal "TP_CH_L_DIMM0_RFU_2"
				( objectStatus "@baseboard_fab2_lib.baseboard_fab2(sch_1):tp_ch_l_dimm0_rfu_2" )
			)
			( signal "M_M_VREF"
				( objectStatus "@baseboard_fab2_lib.baseboard_fab2(sch_1):m_m_vref" )
			)
			( signal "TP_CH_M_DIMM_M0_RFU_0"
				( objectStatus "@baseboard_fab2_lib.baseboard_fab2(sch_1):tp_ch_m_dimm_m0_rfu_0" )
			)
			( signal "TP_CH_M_DIMM_M0_RFU_1"
				( objectStatus "@baseboard_fab2_lib.baseboard_fab2(sch_1):tp_ch_m_dimm_m0_rfu_1" )
			)
			( signal "TP_CH_M_DIMM_M0_RFU_2"
				( objectStatus "@baseboard_fab2_lib.baseboard_fab2(sch_1):tp_ch_m_dimm_m0_rfu_2" )
			)
			( signal "TP_CH_M_DIMM_M1_RFU_0"
				( objectStatus "@baseboard_fab2_lib.baseboard_fab2(sch_1):tp_ch_m_dimm_m1_rfu_0" )
			)
			( signal "TP_CH_M_DIMM_M1_RFU_1"
				( objectStatus "@baseboard_fab2_lib.baseboard_fab2(sch_1):tp_ch_m_dimm_m1_rfu_1" )
			)
			( signal "TP_CH_M_DIMM_M1_RFU_2"
				( objectStatus "@baseboard_fab2_lib.baseboard_fab2(sch_1):tp_ch_m_dimm_m1_rfu_2" )
			)
			( signal "FM_ADR_COMPLETE"
				( objectStatus "@baseboard_fab2_lib.baseboard_fab2(sch_1):fm_adr_complete" )
			)
			( signal "FM_ADR_COMPLETE_DLY"
				( objectStatus "@baseboard_fab2_lib.baseboard_fab2(sch_1):fm_adr_complete_dly" )
			)
			( signal "FM_ADR_COMPLETE_R"
				( objectStatus "@baseboard_fab2_lib.baseboard_fab2(sch_1):fm_adr_complete_r" )
			)
			( signal "FM_ADR_SMI_GPIO_N"
				( objectStatus "@baseboard_fab2_lib.baseboard_fab2(sch_1):fm_adr_smi_gpio_n" )
			)
			( signal "IRQ_DIMM_SAVE_LVT3"
				( objectStatus "@baseboard_fab2_lib.baseboard_fab2(sch_1):irq_dimm_save_lvt3" )
			)
			( signal "IRQ_DIMM_SAVE_LVT3_N"
				( objectStatus "@baseboard_fab2_lib.baseboard_fab2(sch_1):irq_dimm_save_lvt3_n" )
			)
			( signal "IRQ_DIMM_SAVE_N"
				( objectStatus "@baseboard_fab2_lib.baseboard_fab2(sch_1):irq_dimm_save_n" )
			)
			( signal "IRQ_DIMM_SAVE_R_N"
				( objectStatus "@baseboard_fab2_lib.baseboard_fab2(sch_1):irq_dimm_save_r_n" )
			)
			( signal "P3V3"
				( attribute "VOLTAGE" "3.3V"
					( Units "uVoltage" "V" 1.000000)
					( Status sAliasFlattened )
					( Status sAliasConflict )
					( Origin gFrontEnd )
				)
				( objectStatus "@baseboard_fab2_lib.baseboard_fab2(sch_1):p3v3" )
			)
			( signal "PWRGD_PVPP_ABC"
				( objectStatus "@baseboard_fab2_lib.baseboard_fab2(sch_1):pwrgd_pvpp_abc" )
			)
			( signal "SMB_OCP_FRU_STBY_LVC3_SCL"
				( objectStatus "@baseboard_fab2_lib.baseboard_fab2(sch_1):smb_ocp_fru_stby_lvc3_scl" )
			)
			( signal "SMB_OCP_FRU_STBY_LVC3_SDA"
				( objectStatus "@baseboard_fab2_lib.baseboard_fab2(sch_1):smb_ocp_fru_stby_lvc3_sda" )
			)
			( signal "TP_HFI_IO_CONN0_RSVD_17"
				( objectStatus "@baseboard_fab2_lib.baseboard_fab2(sch_1):tp_hfi_io_conn0_rsvd_17" )
			)
			( signal "FM_CPU0_FIVR_FAULT_LVT3"
				( objectStatus "@baseboard_fab2_lib.baseboard_fab2(sch_1):fm_cpu0_fivr_fault_lvt3" )
			)
			( signal "FM_CPU0_FIVR_FAULT_LVT3_R2_N"
				( objectStatus "@baseboard_fab2_lib.baseboard_fab2(sch_1):fm_cpu0_fivr_fault_lvt3_r2_n" )
			)
			( signal "FM_CPU0_THERMTRIP_LVT3_N"
				( objectStatus "@baseboard_fab2_lib.baseboard_fab2(sch_1):fm_cpu0_thermtrip_lvt3_n" )
			)
			( signal "FM_CPU0_THERMTRIP_LVT3_R_N"
				( objectStatus "@baseboard_fab2_lib.baseboard_fab2(sch_1):fm_cpu0_thermtrip_lvt3_r_n" )
			)
			( signal "FM_CPU1_FIVR_FAULT_LVT3"
				( objectStatus "@baseboard_fab2_lib.baseboard_fab2(sch_1):fm_cpu1_fivr_fault_lvt3" )
			)
			( signal "FM_CPU1_FIVR_FAULT_LVT3_R1_N"
				( objectStatus "@baseboard_fab2_lib.baseboard_fab2(sch_1):fm_cpu1_fivr_fault_lvt3_r1_n" )
			)
			( signal "FM_CPU1_THERMTRIP_LVT3_N"
				( objectStatus "@baseboard_fab2_lib.baseboard_fab2(sch_1):fm_cpu1_thermtrip_lvt3_n" )
			)
			( signal "FM_CPU1_THERMTRIP_LVT3_R_N"
				( objectStatus "@baseboard_fab2_lib.baseboard_fab2(sch_1):fm_cpu1_thermtrip_lvt3_r_n" )
			)
			( signal "FM_CPU_CATERR_LVT3_N"
				( objectStatus "@baseboard_fab2_lib.baseboard_fab2(sch_1):fm_cpu_caterr_lvt3_n" )
			)
			( signal "FM_CPU_CATERR_LVT3_R2_N"
				( objectStatus "@baseboard_fab2_lib.baseboard_fab2(sch_1):fm_cpu_caterr_lvt3_r2_n" )
			)
			( signal "FM_CPU_ERR2_LVT3_N"
				( objectStatus "@baseboard_fab2_lib.baseboard_fab2(sch_1):fm_cpu_err2_lvt3_n" )
			)
			( signal "FM_CPU_ERR2_LVT3_R_N"
				( objectStatus "@baseboard_fab2_lib.baseboard_fab2(sch_1):fm_cpu_err2_lvt3_r_n" )
			)
			( signal "FM_CPU_MSMI_LVT3_N"
				( objectStatus "@baseboard_fab2_lib.baseboard_fab2(sch_1):fm_cpu_msmi_lvt3_n" )
			)
			( signal "FM_CPU_MSMI_LVT3_R_N"
				( objectStatus "@baseboard_fab2_lib.baseboard_fab2(sch_1):fm_cpu_msmi_lvt3_r_n" )
			)
			( signal "H_CPU_CATERR_G_N"
				( objectStatus "@baseboard_fab2_lib.baseboard_fab2(sch_1):h_cpu_caterr_g_n" )
			)
			( signal "H_CPU_ERR2_G_R_N"
				( objectStatus "@baseboard_fab2_lib.baseboard_fab2(sch_1):h_cpu_err2_g_r_n" )
			)
			( signal "H_CPU_ERR2_GTL_N"
				( objectStatus "@baseboard_fab2_lib.baseboard_fab2(sch_1):h_cpu_err2_gtl_n" )
			)
			( signal "H_CPU_MSMI_G_N"
				( objectStatus "@baseboard_fab2_lib.baseboard_fab2(sch_1):h_cpu_msmi_g_n" )
			)
			( signal "P0V7_GTL2104_VREF_0"
				( attribute "VOLTAGE" "+0.7 V"
					( Units "uVoltage" "V" 1.000000)
					( Status sAliasFlattened )
					( Origin gFrontEnd )
				)
				( objectStatus "@baseboard_fab2_lib.baseboard_fab2(sch_1):p0v7_gtl2104_vref_0" )
			)
			( signal "P0V7_GTL2104_VREF_1"
				( attribute "VOLTAGE" "+0.7 V"
					( Units "uVoltage" "V" 1.000000)
					( Status sAliasFlattened )
					( Origin gFrontEnd )
				)
				( objectStatus "@baseboard_fab2_lib.baseboard_fab2(sch_1):p0v7_gtl2104_vref_1" )
			)
			( signal "PD_GTL2104_DIR_0"
				( objectStatus "@baseboard_fab2_lib.baseboard_fab2(sch_1):pd_gtl2104_dir_0" )
			)
			( signal "PD_GTL2104_DIR_1"
				( objectStatus "@baseboard_fab2_lib.baseboard_fab2(sch_1):pd_gtl2104_dir_1" )
			)
			( signal "PWRGD_CPUPWRGD"
				( objectStatus "@baseboard_fab2_lib.baseboard_fab2(sch_1):pwrgd_cpupwrgd" )
			)
			( signal "PWRGD_CPUPWRGD_GTL"
				( objectStatus "@baseboard_fab2_lib.baseboard_fab2(sch_1):pwrgd_cpupwrgd_gtl" )
			)
			( signal "PWRGD_CPUPWRGD_R1"
				( objectStatus "@baseboard_fab2_lib.baseboard_fab2(sch_1):pwrgd_cpupwrgd_r1" )
			)
			( signal "FM_CPU0_PROCHOT_LVT3_BMC_N"
				( objectStatus "@baseboard_fab2_lib.baseboard_fab2(sch_1):fm_cpu0_prochot_lvt3_bmc_n" )
			)
			( signal "FM_CPU0_PROCHOT_LVT3_K_N"
				( objectStatus "@baseboard_fab2_lib.baseboard_fab2(sch_1):fm_cpu0_prochot_lvt3_k_n" )
			)
			( signal "FM_CPU0_PROCHOT_LVT3_N"
				( objectStatus "@baseboard_fab2_lib.baseboard_fab2(sch_1):fm_cpu0_prochot_lvt3_n" )
			)
			( signal "FM_CPU0_PROCHOT_LVT3_R_N"
				( objectStatus "@baseboard_fab2_lib.baseboard_fab2(sch_1):fm_cpu0_prochot_lvt3_r_n" )
			)
			( signal "FM_CPU1_PROCHOT_LVT3_BMC_N"
				( objectStatus "@baseboard_fab2_lib.baseboard_fab2(sch_1):fm_cpu1_prochot_lvt3_bmc_n" )
			)
			( signal "FM_CPU1_PROCHOT_LVT3_K_N"
				( objectStatus "@baseboard_fab2_lib.baseboard_fab2(sch_1):fm_cpu1_prochot_lvt3_k_n" )
			)
			( signal "FM_CPU1_PROCHOT_LVT3_N"
				( objectStatus "@baseboard_fab2_lib.baseboard_fab2(sch_1):fm_cpu1_prochot_lvt3_n" )
			)
			( signal "FM_CPU1_PROCHOT_LVT3_R_N"
				( objectStatus "@baseboard_fab2_lib.baseboard_fab2(sch_1):fm_cpu1_prochot_lvt3_r_n" )
			)
			( signal "FM_CPU_ERR0_LVT3_BMC_N"
				( objectStatus "@baseboard_fab2_lib.baseboard_fab2(sch_1):fm_cpu_err0_lvt3_bmc_n" )
			)
			( signal "FM_CPU_ERR0_LVT3_K_N"
				( objectStatus "@baseboard_fab2_lib.baseboard_fab2(sch_1):fm_cpu_err0_lvt3_k_n" )
			)
			( signal "FM_CPU_ERR0_LVT3_N"
				( objectStatus "@baseboard_fab2_lib.baseboard_fab2(sch_1):fm_cpu_err0_lvt3_n" )
			)
			( signal "FM_CPU_ERR0_LVT3_R_N"
				( objectStatus "@baseboard_fab2_lib.baseboard_fab2(sch_1):fm_cpu_err0_lvt3_r_n" )
			)
			( signal "FM_CPU_ERR1_LVT3_BMC_N"
				( objectStatus "@baseboard_fab2_lib.baseboard_fab2(sch_1):fm_cpu_err1_lvt3_bmc_n" )
			)
			( signal "FM_CPU_ERR1_LVT3_N"
				( objectStatus "@baseboard_fab2_lib.baseboard_fab2(sch_1):fm_cpu_err1_lvt3_n" )
			)
			( signal "FM_CPU_ERR1_LVT3_R_N"
				( objectStatus "@baseboard_fab2_lib.baseboard_fab2(sch_1):fm_cpu_err1_lvt3_r_n" )
			)
			( signal "H_CPU0_PROCHOT_G_PCH_N"
				( objectStatus "@baseboard_fab2_lib.baseboard_fab2(sch_1):h_cpu0_prochot_g_pch_n" )
			)
			( signal "H_CPU0_PROCHOT_G_R_N"
				( objectStatus "@baseboard_fab2_lib.baseboard_fab2(sch_1):h_cpu0_prochot_g_r_n" )
			)
			( signal "H_CPU1_PROCHOT_G_PCH_N"
				( objectStatus "@baseboard_fab2_lib.baseboard_fab2(sch_1):h_cpu1_prochot_g_pch_n" )
			)
			( signal "H_CPU1_PROCHOT_G_R_N"
				( objectStatus "@baseboard_fab2_lib.baseboard_fab2(sch_1):h_cpu1_prochot_g_r_n" )
			)
			( signal "H_CPU_ERR0_GTL_N"
				( objectStatus "@baseboard_fab2_lib.baseboard_fab2(sch_1):h_cpu_err0_gtl_n" )
			)
			( signal "H_CPU_ERR0_GTL_R_N"
				( objectStatus "@baseboard_fab2_lib.baseboard_fab2(sch_1):h_cpu_err0_gtl_r_n" )
			)
			( signal "H_CPU_ERR0_PCH_N"
				( objectStatus "@baseboard_fab2_lib.baseboard_fab2(sch_1):h_cpu_err0_pch_n" )
			)
			( signal "H_CPU_ERR1_GTL_N"
				( objectStatus "@baseboard_fab2_lib.baseboard_fab2(sch_1):h_cpu_err1_gtl_n" )
			)
			( signal "H_CPU_ERR1_GTL_R_N"
				( objectStatus "@baseboard_fab2_lib.baseboard_fab2(sch_1):h_cpu_err1_gtl_r_n" )
			)
			( signal "H_CPU_ERR1_PCH_N"
				( objectStatus "@baseboard_fab2_lib.baseboard_fab2(sch_1):h_cpu_err1_pch_n" )
			)
			( signal "P0V7_GTL2104_5_VREF"
				( attribute "VOLTAGE" "0.734"
					( Units "uVoltage" "V" 1.000000)
					( Status sAliasFlattened )
					( Origin gFrontEnd )
				)
				( objectStatus "@baseboard_fab2_lib.baseboard_fab2(sch_1):p0v7_gtl2104_5_vref" )
			)
			( signal "PD_GTL2104_4_DIR"
				( objectStatus "@baseboard_fab2_lib.baseboard_fab2(sch_1):pd_gtl2104_4_dir" )
			)
			( signal "FM_DIMM_EVENT_FET"
				( objectStatus "@baseboard_fab2_lib.baseboard_fab2(sch_1):fm_dimm_event_fet" )
			)
			( signal "FM_MEM_THERM_EVENT_LVT3_N"
				( objectStatus "@baseboard_fab2_lib.baseboard_fab2(sch_1):fm_mem_therm_event_lvt3_n" )
			)
			( signal "H_CPU0_MEMABC_MEMHOT"
				( objectStatus "@baseboard_fab2_lib.baseboard_fab2(sch_1):h_cpu0_memabc_memhot" )
			)
			( signal "H_CPU0_MEMDEF_MEMHOT"
				( objectStatus "@baseboard_fab2_lib.baseboard_fab2(sch_1):h_cpu0_memdef_memhot" )
			)
			( signal "H_CPU1_MEMGHJ_MEMHOT"
				( objectStatus "@baseboard_fab2_lib.baseboard_fab2(sch_1):h_cpu1_memghj_memhot" )
			)
			( signal "H_CPU1_MEMKLM_MEMHOT"
				( objectStatus "@baseboard_fab2_lib.baseboard_fab2(sch_1):h_cpu1_memklm_memhot" )
			)
			( signal "IRQ_PVDDQ_ABC_VRHOT_LVT3_N"
				( objectStatus "@baseboard_fab2_lib.baseboard_fab2(sch_1):irq_pvddq_abc_vrhot_lvt3_n" )
			)
			( signal "IRQ_PVDDQ_DEF_VRHOT_LVT3_N"
				( objectStatus "@baseboard_fab2_lib.baseboard_fab2(sch_1):irq_pvddq_def_vrhot_lvt3_n" )
			)
			( signal "IRQ_PVDDQ_GHJ_VRHOT_LVT3_N"
				( objectStatus "@baseboard_fab2_lib.baseboard_fab2(sch_1):irq_pvddq_ghj_vrhot_lvt3_n" )
			)
			( signal "IRQ_PVDDQ_KLM_VRHOT_LVT3_N"
				( objectStatus "@baseboard_fab2_lib.baseboard_fab2(sch_1):irq_pvddq_klm_vrhot_lvt3_n" )
			)
			( signal "FM_PVCCIN_CPU0_PWR_IN_ALERT_N"
				( objectStatus "@baseboard_fab2_lib.baseboard_fab2(sch_1):fm_pvccin_cpu0_pwr_in_alert_n" )
			)
			( signal "FM_PVCCIN_CPU1_PWR_IN_ALERT_N"
				( objectStatus "@baseboard_fab2_lib.baseboard_fab2(sch_1):fm_pvccin_cpu1_pwr_in_alert_n" )
			)
			( signal "FM_PWRBRK_N"
				( objectStatus "@baseboard_fab2_lib.baseboard_fab2(sch_1):fm_pwrbrk_n" )
			)
			( signal "FM_SYS_THROTTLE_LVC3"
				( objectStatus "@baseboard_fab2_lib.baseboard_fab2(sch_1):fm_sys_throttle_lvc3" )
			)
			( signal "FM_THROTTLE_N"
				( objectStatus "@baseboard_fab2_lib.baseboard_fab2(sch_1):fm_throttle_n" )
			)
			( signal "FM_THROTTLE_R_N"
				( objectStatus "@baseboard_fab2_lib.baseboard_fab2(sch_1):fm_throttle_r_n" )
			)
			( signal "IRQ_CPU0_PROCHOT_G_N"
				( objectStatus "@baseboard_fab2_lib.baseboard_fab2(sch_1):irq_cpu0_prochot_g_n" )
			)
			( signal "IRQ_CPU0_VRHOT"
				( objectStatus "@baseboard_fab2_lib.baseboard_fab2(sch_1):irq_cpu0_vrhot" )
			)
			( signal "IRQ_CPU1_PROCHOT_G_N"
				( objectStatus "@baseboard_fab2_lib.baseboard_fab2(sch_1):irq_cpu1_prochot_g_n" )
			)
			( signal "IRQ_CPU1_VRHOT"
				( objectStatus "@baseboard_fab2_lib.baseboard_fab2(sch_1):irq_cpu1_vrhot" )
			)
			( signal "IRQ_PVCCIN_CPU0_VRHOT_LVC3_N"
				( objectStatus "@baseboard_fab2_lib.baseboard_fab2(sch_1):irq_pvccin_cpu0_vrhot_lvc3_n" )
			)
			( signal "IRQ_PVCCIN_CPU1_VRHOT_LVC3_N"
				( objectStatus "@baseboard_fab2_lib.baseboard_fab2(sch_1):irq_pvccin_cpu1_vrhot_lvc3_n" )
			)
			( signal "PD_GTL2014_1_VREF"
				( objectStatus "@baseboard_fab2_lib.baseboard_fab2(sch_1):pd_gtl2014_1_vref" )
			)
			( signal "PD_GTL2014_2_VREF"
				( objectStatus "@baseboard_fab2_lib.baseboard_fab2(sch_1):pd_gtl2014_2_vref" )
			)
			( signal "PU_GTL2014_1_DIR"
				( objectStatus "@baseboard_fab2_lib.baseboard_fab2(sch_1):pu_gtl2014_1_dir" )
			)
			( signal "PU_GTL2014_2_DIR"
				( objectStatus "@baseboard_fab2_lib.baseboard_fab2(sch_1):pu_gtl2014_2_dir" )
			)
			( signal "PWRGD_CPU0_LVC3"
				( objectStatus "@baseboard_fab2_lib.baseboard_fab2(sch_1):pwrgd_cpu0_lvc3" )
			)
			( signal "PWRGD_CPU1_LVC3"
				( objectStatus "@baseboard_fab2_lib.baseboard_fab2(sch_1):pwrgd_cpu1_lvc3" )
			)
			( signal "PWRGD_DRAMPWRGD"
				( objectStatus "@baseboard_fab2_lib.baseboard_fab2(sch_1):pwrgd_drampwrgd" )
			)
			( signal "RST_CPU0_LVC3_N"
				( objectStatus "@baseboard_fab2_lib.baseboard_fab2(sch_1):rst_cpu0_lvc3_n" )
			)
			( signal "RST_CPU1_LVC3_N"
				( objectStatus "@baseboard_fab2_lib.baseboard_fab2(sch_1):rst_cpu1_lvc3_n" )
			)
			( signal "SMB_DDR_ABC_SCL_G"
				( objectStatus "@baseboard_fab2_lib.baseboard_fab2(sch_1):smb_ddr_abc_scl_g" )
			)
			( signal "SMB_DDR_ABC_SDA_G"
				( objectStatus "@baseboard_fab2_lib.baseboard_fab2(sch_1):smb_ddr_abc_sda_g" )
			)
			( signal "SMB_DDR_ABC_VPP_SCL_R"
				( objectStatus "@baseboard_fab2_lib.baseboard_fab2(sch_1):smb_ddr_abc_vpp_scl_r" )
			)
			( signal "SMB_DDR_ABC_VPP_SDA_R"
				( objectStatus "@baseboard_fab2_lib.baseboard_fab2(sch_1):smb_ddr_abc_vpp_sda_r" )
			)
			( signal "SMB_DDR_DEF_SCL_G"
				( objectStatus "@baseboard_fab2_lib.baseboard_fab2(sch_1):smb_ddr_def_scl_g" )
			)
			( signal "SMB_DDR_DEF_SDA_G"
				( objectStatus "@baseboard_fab2_lib.baseboard_fab2(sch_1):smb_ddr_def_sda_g" )
			)
			( signal "SMB_DDR_DEF_VPP_SCL_R"
				( objectStatus "@baseboard_fab2_lib.baseboard_fab2(sch_1):smb_ddr_def_vpp_scl_r" )
			)
			( signal "SMB_DDR_DEF_VPP_SDA_R"
				( objectStatus "@baseboard_fab2_lib.baseboard_fab2(sch_1):smb_ddr_def_vpp_sda_r" )
			)
			( signal "SMB_DDR_GHJ_SCL_G"
				( objectStatus "@baseboard_fab2_lib.baseboard_fab2(sch_1):smb_ddr_ghj_scl_g" )
			)
			( signal "SMB_DDR_GHJ_SDA_G"
				( objectStatus "@baseboard_fab2_lib.baseboard_fab2(sch_1):smb_ddr_ghj_sda_g" )
			)
			( signal "SMB_DDR_GHJ_VPP_SCL_R"
				( objectStatus "@baseboard_fab2_lib.baseboard_fab2(sch_1):smb_ddr_ghj_vpp_scl_r" )
			)
			( signal "SMB_DDR_GHJ_VPP_SDA_R"
				( objectStatus "@baseboard_fab2_lib.baseboard_fab2(sch_1):smb_ddr_ghj_vpp_sda_r" )
			)
			( signal "SMB_DDR_KLM_SCL_G"
				( objectStatus "@baseboard_fab2_lib.baseboard_fab2(sch_1):smb_ddr_klm_scl_g" )
			)
			( signal "SMB_DDR_KLM_SDA_G"
				( objectStatus "@baseboard_fab2_lib.baseboard_fab2(sch_1):smb_ddr_klm_sda_g" )
			)
			( signal "SMB_DDR_KLM_VPP_SCL_R"
				( objectStatus "@baseboard_fab2_lib.baseboard_fab2(sch_1):smb_ddr_klm_vpp_scl_r" )
			)
			( signal "SMB_DDR_KLM_VPP_SDA_R"
				( objectStatus "@baseboard_fab2_lib.baseboard_fab2(sch_1):smb_ddr_klm_vpp_sda_r" )
			)
			( signal "TP_SMB_DDR_ABC_EN"
				( objectStatus "@baseboard_fab2_lib.baseboard_fab2(sch_1):tp_smb_ddr_abc_en" )
			)
			( signal "TP_SMB_DDR_DEF_EN"
				( objectStatus "@baseboard_fab2_lib.baseboard_fab2(sch_1):tp_smb_ddr_def_en" )
			)
			( signal "TP_SMB_DDR_GHJ_EN"
				( objectStatus "@baseboard_fab2_lib.baseboard_fab2(sch_1):tp_smb_ddr_ghj_en" )
			)
			( signal "TP_SMB_DDR_KLM_EN"
				( objectStatus "@baseboard_fab2_lib.baseboard_fab2(sch_1):tp_smb_ddr_klm_en" )
			)
			( signal "A_COMP_CKMNG"
				( objectStatus "@baseboard_fab2_lib.baseboard_fab2(sch_1):a_comp_ckmng" )
			)
			( signal "CLK_25M_BMC"
				( objectStatus "@baseboard_fab2_lib.baseboard_fab2(sch_1):clk_25m_bmc" )
			)
			( signal "CLK_25M_BMC_R"
				( objectStatus "@baseboard_fab2_lib.baseboard_fab2(sch_1):clk_25m_bmc_r" )
			)
			( signal "CLK_25M_CPLD"
				( objectStatus "@baseboard_fab2_lib.baseboard_fab2(sch_1):clk_25m_cpld" )
			)
			( signal "CLK_25M_CPLD_R"
				( objectStatus "@baseboard_fab2_lib.baseboard_fab2(sch_1):clk_25m_cpld_r" )
			)
			( signal "CLK_32K_SUSCLK_PLD"
				( objectStatus "@baseboard_fab2_lib.baseboard_fab2(sch_1):clk_32k_susclk_pld" )
			)
			( signal "CLK_32K_SUSCLK_PLD_R"
				( objectStatus "@baseboard_fab2_lib.baseboard_fab2(sch_1):clk_32k_susclk_pld_r" )
			)
			( signal "CLK_50M_CKMNG_BMC_1"
				( objectStatus "@baseboard_fab2_lib.baseboard_fab2(sch_1):clk_50m_ckmng_bmc_1" )
			)
			( signal "CLK_50M_CKMNG_BMC_1_R"
				( objectStatus "@baseboard_fab2_lib.baseboard_fab2(sch_1):clk_50m_ckmng_bmc_1_r" )
			)
			( signal "CLK_50M_CKMNG_BMC_2"
				( objectStatus "@baseboard_fab2_lib.baseboard_fab2(sch_1):clk_50m_ckmng_bmc_2" )
			)
			( signal "CLK_50M_CKMNG_BMC_2_R"
				( objectStatus "@baseboard_fab2_lib.baseboard_fab2(sch_1):clk_50m_ckmng_bmc_2_r" )
			)
			( signal "CLK_50M_CKMNG_OCP"
				( objectStatus "@baseboard_fab2_lib.baseboard_fab2(sch_1):clk_50m_ckmng_ocp" )
			)
			( signal "CLK_50M_CKMNG_OCP_R"
				( objectStatus "@baseboard_fab2_lib.baseboard_fab2(sch_1):clk_50m_ckmng_ocp_r" )
			)
			( signal "CLK_50M_CKMNG_PCH_10GBE"
				( objectStatus "@baseboard_fab2_lib.baseboard_fab2(sch_1):clk_50m_ckmng_pch_10gbe" )
			)
			( signal "CLK_50M_CKMNG_PCH_10GBE_R"
				( objectStatus "@baseboard_fab2_lib.baseboard_fab2(sch_1):clk_50m_ckmng_pch_10gbe_r" )
			)
			( signal "CLK_50M_CKMNG_SPRVLLE"
				( objectStatus "@baseboard_fab2_lib.baseboard_fab2(sch_1):clk_50m_ckmng_sprvlle" )
			)
			( signal "CLK_50M_CKMNG_SPRVLLE_R"
				( objectStatus "@baseboard_fab2_lib.baseboard_fab2(sch_1):clk_50m_ckmng_sprvlle_r" )
			)
			( signal "P3V3_STBY_MNG"
				( attribute "VOLTAGE" "5"
					( Units "uVoltage" "V" 1.000000)
					( Status sAliasFlattened )
					( Origin gFrontEnd )
				)
				( objectStatus "@baseboard_fab2_lib.baseboard_fab2(sch_1):p3v3_stby_mng" )
			)
			( signal "P3V3_STBY_MNG_CPU"
				( attribute "VOLTAGE" "3.3"
					( Units "uVoltage" "V" 1.000000)
					( Status sAliasFlattened )
					( Origin gFrontEnd )
				)
				( objectStatus "@baseboard_fab2_lib.baseboard_fab2(sch_1):p3v3_stby_mng_cpu" )
			)
			( signal "P3V3_STBY_MNG_RGMII"
				( attribute "VOLTAGE" "3.3"
					( Units "uVoltage" "V" 1.000000)
					( Status sAliasFlattened )
					( Origin gFrontEnd )
				)
				( objectStatus "@baseboard_fab2_lib.baseboard_fab2(sch_1):p3v3_stby_mng_rgmii" )
			)
			( signal "P3V3_STBY_MNG_RMII"
				( attribute "VOLTAGE" "3.3"
					( Units "uVoltage" "V" 1.000000)
					( Status sAliasFlattened )
					( Origin gFrontEnd )
				)
				( objectStatus "@baseboard_fab2_lib.baseboard_fab2(sch_1):p3v3_stby_mng_rmii" )
			)
			( signal "PD_CKMNG_OE"
				( objectStatus "@baseboard_fab2_lib.baseboard_fab2(sch_1):pd_ckmng_oe" )
			)
			( signal "PWRGD_P3V3_STBY"
				( objectStatus "@baseboard_fab2_lib.baseboard_fab2(sch_1):pwrgd_p3v3_stby" )
			)
			( signal "SMB_HOST_STBY_LVC3_SCL"
				( objectStatus "@baseboard_fab2_lib.baseboard_fab2(sch_1):smb_host_stby_lvc3_scl" )
			)
			( signal "SMB_HOST_STBY_LVC3_SDA"
				( objectStatus "@baseboard_fab2_lib.baseboard_fab2(sch_1):smb_host_stby_lvc3_sda" )
			)
			( signal "TP_33P_33M_SMBADR"
				( objectStatus "@baseboard_fab2_lib.baseboard_fab2(sch_1):tp_33p_33m_smbadr" )
			)
			( signal "TP_CLK5_50M_CKMNG"
				( objectStatus "@baseboard_fab2_lib.baseboard_fab2(sch_1):tp_clk5_50m_ckmng" )
			)
			( signal "TP_CLK_100M_R_DN"
				( objectStatus "@baseboard_fab2_lib.baseboard_fab2(sch_1):tp_clk_100m_r_dn" )
			)
			( signal "TP_CLK_100M_R_DP"
				( objectStatus "@baseboard_fab2_lib.baseboard_fab2(sch_1):tp_clk_100m_r_dp" )
			)
			( signal "TP_CLK_125M"
				( objectStatus "@baseboard_fab2_lib.baseboard_fab2(sch_1):tp_clk_125m" )
			)
			( signal "TP_CLK_125M_BMCA"
				( objectStatus "@baseboard_fab2_lib.baseboard_fab2(sch_1):tp_clk_125m_bmca" )
			)
			( signal "TP_CLK_96M_CKMNG_N"
				( objectStatus "@baseboard_fab2_lib.baseboard_fab2(sch_1):tp_clk_96m_ckmng_n" )
			)
			( signal "TP_CLK_96M_CKMNG_P"
				( objectStatus "@baseboard_fab2_lib.baseboard_fab2(sch_1):tp_clk_96m_ckmng_p" )
			)
			( signal "XTAL_CK_MNG_IN"
				( objectStatus "@baseboard_fab2_lib.baseboard_fab2(sch_1):xtal_ck_mng_in" )
			)
			( signal "XTAL_CK_MNG_OUT"
				( objectStatus "@baseboard_fab2_lib.baseboard_fab2(sch_1):xtal_ck_mng_out" )
			)
			( signal "CLK_100M_CPU0_BCLK0_R_DN"
				( objectStatus "@baseboard_fab2_lib.baseboard_fab2(sch_1):clk_100m_cpu0_bclk0_r_dn" )
			)
			( signal "CLK_100M_CPU0_BCLK0_R_DP"
				( objectStatus "@baseboard_fab2_lib.baseboard_fab2(sch_1):clk_100m_cpu0_bclk0_r_dp" )
			)
			( signal "CLK_100M_CPU0_BCLK1_R_DN"
				( objectStatus "@baseboard_fab2_lib.baseboard_fab2(sch_1):clk_100m_cpu0_bclk1_r_dn" )
			)
			( signal "CLK_100M_CPU0_BCLK1_R_DP"
				( objectStatus "@baseboard_fab2_lib.baseboard_fab2(sch_1):clk_100m_cpu0_bclk1_r_dp" )
			)
			( signal "CLK_100M_CPU0_BCLK2_R_DN"
				( objectStatus "@baseboard_fab2_lib.baseboard_fab2(sch_1):clk_100m_cpu0_bclk2_r_dn" )
			)
			( signal "CLK_100M_CPU0_BCLK2_R_DP"
				( objectStatus "@baseboard_fab2_lib.baseboard_fab2(sch_1):clk_100m_cpu0_bclk2_r_dp" )
			)
			( signal "CLK_100M_CPU0_PE_REFCLK_R_DN"
				( objectStatus "@baseboard_fab2_lib.baseboard_fab2(sch_1):clk_100m_cpu0_pe_refclk_r_dn" )
			)
			( signal "CLK_100M_CPU0_PE_REFCLK_R_DP"
				( objectStatus "@baseboard_fab2_lib.baseboard_fab2(sch_1):clk_100m_cpu0_pe_refclk_r_dp" )
			)
			( signal "CLK_100M_CPU0_RC_REFCLK0_R_DN"
				( objectStatus "@baseboard_fab2_lib.baseboard_fab2(sch_1):clk_100m_cpu0_rc_refclk0_r_dn" )
			)
			( signal "CLK_100M_CPU0_RC_REFCLK0_R_DP"
				( objectStatus "@baseboard_fab2_lib.baseboard_fab2(sch_1):clk_100m_cpu0_rc_refclk0_r_dp" )
			)
			( signal "CLK_100M_CPU0_RC_REFCLK1_R_DN"
				( objectStatus "@baseboard_fab2_lib.baseboard_fab2(sch_1):clk_100m_cpu0_rc_refclk1_r_dn" )
			)
			( signal "CLK_100M_CPU0_RC_REFCLK1_R_DP"
				( objectStatus "@baseboard_fab2_lib.baseboard_fab2(sch_1):clk_100m_cpu0_rc_refclk1_r_dp" )
			)
			( signal "CLK_100M_CPU1_BCLK0_R_DN"
				( objectStatus "@baseboard_fab2_lib.baseboard_fab2(sch_1):clk_100m_cpu1_bclk0_r_dn" )
			)
			( signal "CLK_100M_CPU1_BCLK0_R_DP"
				( objectStatus "@baseboard_fab2_lib.baseboard_fab2(sch_1):clk_100m_cpu1_bclk0_r_dp" )
			)
			( signal "CLK_100M_CPU1_BCLK1_R_DN"
				( objectStatus "@baseboard_fab2_lib.baseboard_fab2(sch_1):clk_100m_cpu1_bclk1_r_dn" )
			)
			( signal "CLK_100M_CPU1_BCLK1_R_DP"
				( objectStatus "@baseboard_fab2_lib.baseboard_fab2(sch_1):clk_100m_cpu1_bclk1_r_dp" )
			)
			( signal "CLK_100M_CPU1_BCLK2_R_DN"
				( objectStatus "@baseboard_fab2_lib.baseboard_fab2(sch_1):clk_100m_cpu1_bclk2_r_dn" )
			)
			( signal "CLK_100M_CPU1_BCLK2_R_DP"
				( objectStatus "@baseboard_fab2_lib.baseboard_fab2(sch_1):clk_100m_cpu1_bclk2_r_dp" )
			)
			( signal "CLK_100M_CPU1_PE_REFCLK_R_DN"
				( objectStatus "@baseboard_fab2_lib.baseboard_fab2(sch_1):clk_100m_cpu1_pe_refclk_r_dn" )
			)
			( signal "CLK_100M_CPU1_PE_REFCLK_R_DP"
				( objectStatus "@baseboard_fab2_lib.baseboard_fab2(sch_1):clk_100m_cpu1_pe_refclk_r_dp" )
			)
			( signal "CLK_100M_CPU1_RC_REFCLK0_R_DN"
				( objectStatus "@baseboard_fab2_lib.baseboard_fab2(sch_1):clk_100m_cpu1_rc_refclk0_r_dn" )
			)
			( signal "CLK_100M_CPU1_RC_REFCLK0_R_DP"
				( objectStatus "@baseboard_fab2_lib.baseboard_fab2(sch_1):clk_100m_cpu1_rc_refclk0_r_dp" )
			)
			( signal "CLK_100M_CPU1_RC_REFCLK1_R_DN"
				( objectStatus "@baseboard_fab2_lib.baseboard_fab2(sch_1):clk_100m_cpu1_rc_refclk1_r_dn" )
			)
			( signal "CLK_100M_CPU1_RC_REFCLK1_R_DP"
				( objectStatus "@baseboard_fab2_lib.baseboard_fab2(sch_1):clk_100m_cpu1_rc_refclk1_r_dp" )
			)
			( signal "CLK_100M_DB1200_DN"
				( objectStatus "@baseboard_fab2_lib.baseboard_fab2(sch_1):clk_100m_db1200_dn" )
			)
			( signal "CLK_100M_DB1200_DP"
				( objectStatus "@baseboard_fab2_lib.baseboard_fab2(sch_1):clk_100m_db1200_dp" )
			)
			( signal "FM_100M_N"
				( objectStatus "@baseboard_fab2_lib.baseboard_fab2(sch_1):fm_100m_n" )
			)
			( signal "FM_CPU0_MCP_CLK_EN_N"
				( objectStatus "@baseboard_fab2_lib.baseboard_fab2(sch_1):fm_cpu0_mcp_clk_en_n" )
			)
			( signal "FM_CPU1_MCP_CLK_EN_N"
				( objectStatus "@baseboard_fab2_lib.baseboard_fab2(sch_1):fm_cpu1_mcp_clk_en_n" )
			)
			( signal "FM_DB1200_PWRGD"
				( objectStatus "@baseboard_fab2_lib.baseboard_fab2(sch_1):fm_db1200_pwrgd" )
			)
			( signal "FM_DB1200_SMB_SA0"
				( objectStatus "@baseboard_fab2_lib.baseboard_fab2(sch_1):fm_db1200_smb_sa0" )
			)
			( signal "FM_DB1200_SMB_SA1"
				( objectStatus "@baseboard_fab2_lib.baseboard_fab2(sch_1):fm_db1200_smb_sa1" )
			)
			( signal "FM_DB1200ZL_BCLKS_EN_N"
				( objectStatus "@baseboard_fab2_lib.baseboard_fab2(sch_1):fm_db1200zl_bclks_en_n" )
			)
			( signal "FM_HBW_BYPASS_LOWBW_N"
				( objectStatus "@baseboard_fab2_lib.baseboard_fab2(sch_1):fm_hbw_bypass_lowbw_n" )
			)
			( signal "NC_DB1200ZL<0>"
				( objectStatus "@baseboard_fab2_lib.baseboard_fab2(sch_1):nc_db1200zl(0)" )
			)
			( signal "NC_DB1200ZL<1>"
				( objectStatus "@baseboard_fab2_lib.baseboard_fab2(sch_1):nc_db1200zl(1)" )
			)
			( signal "NC_DB1200ZL<2>"
				( objectStatus "@baseboard_fab2_lib.baseboard_fab2(sch_1):nc_db1200zl(2)" )
			)
			( signal "P3V3_DB1200"
				( attribute "VOLTAGE" "5"
					( Units "uVoltage" "V" 1.000000)
					( Status sAliasFlattened )
					( Origin gFrontEnd )
				)
				( objectStatus "@baseboard_fab2_lib.baseboard_fab2(sch_1):p3v3_db1200" )
			)
			( signal "P3V3_DB1200_A"
				( attribute "VOLTAGE" "+3.3V"
					( Units "uVoltage" "V" 1.000000)
					( Status sAliasFlattened )
					( Origin gFrontEnd )
				)
				( objectStatus "@baseboard_fab2_lib.baseboard_fab2(sch_1):p3v3_db1200_a" )
			)
			( signal "P3V3_DB1200_R"
				( attribute "VOLTAGE" "+3.3V"
					( Units "uVoltage" "V" 1.000000)
					( Status sAliasFlattened )
					( Origin gFrontEnd )
				)
				( objectStatus "@baseboard_fab2_lib.baseboard_fab2(sch_1):p3v3_db1200_r" )
			)
			( signal "SMB_HOST_STBY_LVC3_SCL_R2"
				( objectStatus "@baseboard_fab2_lib.baseboard_fab2(sch_1):smb_host_stby_lvc3_scl_r2" )
			)
			( signal "SMB_HOST_STBY_LVC3_SDA_R2"
				( objectStatus "@baseboard_fab2_lib.baseboard_fab2(sch_1):smb_host_stby_lvc3_sda_r2" )
			)
			( signal "CLK_156M_OSC_BRD_CPU0_DN"
				( objectStatus "@baseboard_fab2_lib.baseboard_fab2(sch_1):clk_156m_osc_brd_cpu0_dn" )
			)
			( signal "CLK_156M_OSC_BRD_CPU0_DP"
				( objectStatus "@baseboard_fab2_lib.baseboard_fab2(sch_1):clk_156m_osc_brd_cpu0_dp" )
			)
			( signal "CLK_156M_OSC_BRD_CPU1_DN"
				( objectStatus "@baseboard_fab2_lib.baseboard_fab2(sch_1):clk_156m_osc_brd_cpu1_dn" )
			)
			( signal "CLK_156M_OSC_BRD_CPU1_DP"
				( objectStatus "@baseboard_fab2_lib.baseboard_fab2(sch_1):clk_156m_osc_brd_cpu1_dp" )
			)
			( signal "CLK_322M_156M_CPU0_OSC_VRM_DN"
				( objectStatus "@baseboard_fab2_lib.baseboard_fab2(sch_1):clk_322m_156m_cpu0_osc_vrm_dn" )
			)
			( signal "CLK_322M_156M_CPU0_OSC_VRM_DP"
				( objectStatus "@baseboard_fab2_lib.baseboard_fab2(sch_1):clk_322m_156m_cpu0_osc_vrm_dp" )
			)
			( signal "CLK_322M_156M_CPU1_OSC_VRM_DN"
				( objectStatus "@baseboard_fab2_lib.baseboard_fab2(sch_1):clk_322m_156m_cpu1_osc_vrm_dn" )
			)
			( signal "CLK_322M_156M_CPU1_OSC_VRM_DP"
				( objectStatus "@baseboard_fab2_lib.baseboard_fab2(sch_1):clk_322m_156m_cpu1_osc_vrm_dp" )
			)
			( signal "FM_156M_CPU0_BRD_OSC_EN"
				( objectStatus "@baseboard_fab2_lib.baseboard_fab2(sch_1):fm_156m_cpu0_brd_osc_en" )
			)
			( signal "FM_156M_CPU1_BRD_OSC_EN"
				( objectStatus "@baseboard_fab2_lib.baseboard_fab2(sch_1):fm_156m_cpu1_brd_osc_en" )
			)
			( signal "FM_CPU0_STL_BRD_OSC_EN"
				( objectStatus "@baseboard_fab2_lib.baseboard_fab2(sch_1):fm_cpu0_stl_brd_osc_en" )
			)
			( signal "FM_CPU0_VRM_322M_156M_OSC_EN"
				( objectStatus "@baseboard_fab2_lib.baseboard_fab2(sch_1):fm_cpu0_vrm_322m_156m_osc_en" )
			)
			( signal "FM_CPU0_VRM_OSC_EN"
				( objectStatus "@baseboard_fab2_lib.baseboard_fab2(sch_1):fm_cpu0_vrm_osc_en" )
			)
			( signal "FM_CPU1_STL_BRD_OSC_EN"
				( objectStatus "@baseboard_fab2_lib.baseboard_fab2(sch_1):fm_cpu1_stl_brd_osc_en" )
			)
			( signal "FM_CPU1_VRM_322M_156M_OSC_EN"
				( objectStatus "@baseboard_fab2_lib.baseboard_fab2(sch_1):fm_cpu1_vrm_322m_156m_osc_en" )
			)
			( signal "FM_CPU1_VRM_OSC_EN"
				( objectStatus "@baseboard_fab2_lib.baseboard_fab2(sch_1):fm_cpu1_vrm_osc_en" )
			)
			( signal "NC_CLK_156M_CPU0_OSC"
				( objectStatus "@baseboard_fab2_lib.baseboard_fab2(sch_1):nc_clk_156m_cpu0_osc" )
			)
			( signal "NC_CLK_156M_CPU1_OSC"
				( objectStatus "@baseboard_fab2_lib.baseboard_fab2(sch_1):nc_clk_156m_cpu1_osc" )
			)
			( signal "P3E_CPU0_PE1_PCH_C_TXN<8>"
				( objectStatus "@baseboard_fab2_lib.baseboard_fab2(sch_1):p3e_cpu0_pe1_pch_c_txn(8)" )
			)
			( signal "P3E_CPU0_PE1_PCH_C_TXN<9>"
				( objectStatus "@baseboard_fab2_lib.baseboard_fab2(sch_1):p3e_cpu0_pe1_pch_c_txn(9)" )
			)
			( signal "P3E_CPU0_PE1_PCH_C_TXN<10>"
				( objectStatus "@baseboard_fab2_lib.baseboard_fab2(sch_1):p3e_cpu0_pe1_pch_c_txn(10)" )
			)
			( signal "P3E_CPU0_PE1_PCH_C_TXN<11>"
				( objectStatus "@baseboard_fab2_lib.baseboard_fab2(sch_1):p3e_cpu0_pe1_pch_c_txn(11)" )
			)
			( signal "P3E_CPU0_PE1_PCH_C_TXN<12>"
				( objectStatus "@baseboard_fab2_lib.baseboard_fab2(sch_1):p3e_cpu0_pe1_pch_c_txn(12)" )
			)
			( signal "P3E_CPU0_PE1_PCH_C_TXN<13>"
				( objectStatus "@baseboard_fab2_lib.baseboard_fab2(sch_1):p3e_cpu0_pe1_pch_c_txn(13)" )
			)
			( signal "P3E_CPU0_PE1_PCH_C_TXN<14>"
				( objectStatus "@baseboard_fab2_lib.baseboard_fab2(sch_1):p3e_cpu0_pe1_pch_c_txn(14)" )
			)
			( signal "P3E_CPU0_PE1_PCH_C_TXN<15>"
				( objectStatus "@baseboard_fab2_lib.baseboard_fab2(sch_1):p3e_cpu0_pe1_pch_c_txn(15)" )
			)
			( signal "P3E_CPU0_PE1_PCH_C_TXP<8>"
				( objectStatus "@baseboard_fab2_lib.baseboard_fab2(sch_1):p3e_cpu0_pe1_pch_c_txp(8)" )
			)
			( signal "P3E_CPU0_PE1_PCH_C_TXP<9>"
				( objectStatus "@baseboard_fab2_lib.baseboard_fab2(sch_1):p3e_cpu0_pe1_pch_c_txp(9)" )
			)
			( signal "P3E_CPU0_PE1_PCH_C_TXP<10>"
				( objectStatus "@baseboard_fab2_lib.baseboard_fab2(sch_1):p3e_cpu0_pe1_pch_c_txp(10)" )
			)
			( signal "P3E_CPU0_PE1_PCH_C_TXP<11>"
				( objectStatus "@baseboard_fab2_lib.baseboard_fab2(sch_1):p3e_cpu0_pe1_pch_c_txp(11)" )
			)
			( signal "P3E_CPU0_PE1_PCH_C_TXP<12>"
				( objectStatus "@baseboard_fab2_lib.baseboard_fab2(sch_1):p3e_cpu0_pe1_pch_c_txp(12)" )
			)
			( signal "P3E_CPU0_PE1_PCH_C_TXP<13>"
				( objectStatus "@baseboard_fab2_lib.baseboard_fab2(sch_1):p3e_cpu0_pe1_pch_c_txp(13)" )
			)
			( signal "P3E_CPU0_PE1_PCH_C_TXP<14>"
				( objectStatus "@baseboard_fab2_lib.baseboard_fab2(sch_1):p3e_cpu0_pe1_pch_c_txp(14)" )
			)
			( signal "P3E_CPU0_PE1_PCH_C_TXP<15>"
				( objectStatus "@baseboard_fab2_lib.baseboard_fab2(sch_1):p3e_cpu0_pe1_pch_c_txp(15)" )
			)
			( signal "P3E_CPU0_PE1_PCH_R_RXN<8>"
				( objectStatus "@baseboard_fab2_lib.baseboard_fab2(sch_1):p3e_cpu0_pe1_pch_r_rxn(8)" )
			)
			( signal "P3E_CPU0_PE1_PCH_R_RXN<9>"
				( objectStatus "@baseboard_fab2_lib.baseboard_fab2(sch_1):p3e_cpu0_pe1_pch_r_rxn(9)" )
			)
			( signal "P3E_CPU0_PE1_PCH_R_RXN<10>"
				( objectStatus "@baseboard_fab2_lib.baseboard_fab2(sch_1):p3e_cpu0_pe1_pch_r_rxn(10)" )
			)
			( signal "P3E_CPU0_PE1_PCH_R_RXN<11>"
				( objectStatus "@baseboard_fab2_lib.baseboard_fab2(sch_1):p3e_cpu0_pe1_pch_r_rxn(11)" )
			)
			( signal "P3E_CPU0_PE1_PCH_R_RXN<12>"
				( objectStatus "@baseboard_fab2_lib.baseboard_fab2(sch_1):p3e_cpu0_pe1_pch_r_rxn(12)" )
			)
			( signal "P3E_CPU0_PE1_PCH_R_RXN<13>"
				( objectStatus "@baseboard_fab2_lib.baseboard_fab2(sch_1):p3e_cpu0_pe1_pch_r_rxn(13)" )
			)
			( signal "P3E_CPU0_PE1_PCH_R_RXN<14>"
				( objectStatus "@baseboard_fab2_lib.baseboard_fab2(sch_1):p3e_cpu0_pe1_pch_r_rxn(14)" )
			)
			( signal "P3E_CPU0_PE1_PCH_R_RXN<15>"
				( objectStatus "@baseboard_fab2_lib.baseboard_fab2(sch_1):p3e_cpu0_pe1_pch_r_rxn(15)" )
			)
			( signal "P3E_CPU0_PE1_PCH_R_RXP<8>"
				( objectStatus "@baseboard_fab2_lib.baseboard_fab2(sch_1):p3e_cpu0_pe1_pch_r_rxp(8)" )
			)
			( signal "P3E_CPU0_PE1_PCH_R_RXP<9>"
				( objectStatus "@baseboard_fab2_lib.baseboard_fab2(sch_1):p3e_cpu0_pe1_pch_r_rxp(9)" )
			)
			( signal "P3E_CPU0_PE1_PCH_R_RXP<10>"
				( objectStatus "@baseboard_fab2_lib.baseboard_fab2(sch_1):p3e_cpu0_pe1_pch_r_rxp(10)" )
			)
			( signal "P3E_CPU0_PE1_PCH_R_RXP<11>"
				( objectStatus "@baseboard_fab2_lib.baseboard_fab2(sch_1):p3e_cpu0_pe1_pch_r_rxp(11)" )
			)
			( signal "P3E_CPU0_PE1_PCH_R_RXP<12>"
				( objectStatus "@baseboard_fab2_lib.baseboard_fab2(sch_1):p3e_cpu0_pe1_pch_r_rxp(12)" )
			)
			( signal "P3E_CPU0_PE1_PCH_R_RXP<13>"
				( objectStatus "@baseboard_fab2_lib.baseboard_fab2(sch_1):p3e_cpu0_pe1_pch_r_rxp(13)" )
			)
			( signal "P3E_CPU0_PE1_PCH_R_RXP<14>"
				( objectStatus "@baseboard_fab2_lib.baseboard_fab2(sch_1):p3e_cpu0_pe1_pch_r_rxp(14)" )
			)
			( signal "P3E_CPU0_PE1_PCH_R_RXP<15>"
				( objectStatus "@baseboard_fab2_lib.baseboard_fab2(sch_1):p3e_cpu0_pe1_pch_r_rxp(15)" )
			)
			( signal "P3E_CPU0_PE2_SS_C_TXN<0>"
				( objectStatus "@baseboard_fab2_lib.baseboard_fab2(sch_1):p3e_cpu0_pe2_ss_c_txn(0)" )
			)
			( signal "P3E_CPU0_PE2_SS_C_TXN<1>"
				( objectStatus "@baseboard_fab2_lib.baseboard_fab2(sch_1):p3e_cpu0_pe2_ss_c_txn(1)" )
			)
			( signal "P3E_CPU0_PE2_SS_C_TXN<2>"
				( objectStatus "@baseboard_fab2_lib.baseboard_fab2(sch_1):p3e_cpu0_pe2_ss_c_txn(2)" )
			)
			( signal "P3E_CPU0_PE2_SS_C_TXN<3>"
				( objectStatus "@baseboard_fab2_lib.baseboard_fab2(sch_1):p3e_cpu0_pe2_ss_c_txn(3)" )
			)
			( signal "P3E_CPU0_PE2_SS_C_TXN<4>"
				( objectStatus "@baseboard_fab2_lib.baseboard_fab2(sch_1):p3e_cpu0_pe2_ss_c_txn(4)" )
			)
			( signal "P3E_CPU0_PE2_SS_C_TXN<5>"
				( objectStatus "@baseboard_fab2_lib.baseboard_fab2(sch_1):p3e_cpu0_pe2_ss_c_txn(5)" )
			)
			( signal "P3E_CPU0_PE2_SS_C_TXN<6>"
				( objectStatus "@baseboard_fab2_lib.baseboard_fab2(sch_1):p3e_cpu0_pe2_ss_c_txn(6)" )
			)
			( signal "P3E_CPU0_PE2_SS_C_TXN<7>"
				( objectStatus "@baseboard_fab2_lib.baseboard_fab2(sch_1):p3e_cpu0_pe2_ss_c_txn(7)" )
			)
			( signal "P3E_CPU0_PE2_SS_C_TXN<8>"
				( objectStatus "@baseboard_fab2_lib.baseboard_fab2(sch_1):p3e_cpu0_pe2_ss_c_txn(8)" )
			)
			( signal "P3E_CPU0_PE2_SS_C_TXN<9>"
				( objectStatus "@baseboard_fab2_lib.baseboard_fab2(sch_1):p3e_cpu0_pe2_ss_c_txn(9)" )
			)
			( signal "P3E_CPU0_PE2_SS_C_TXN<10>"
				( objectStatus "@baseboard_fab2_lib.baseboard_fab2(sch_1):p3e_cpu0_pe2_ss_c_txn(10)" )
			)
			( signal "P3E_CPU0_PE2_SS_C_TXN<11>"
				( objectStatus "@baseboard_fab2_lib.baseboard_fab2(sch_1):p3e_cpu0_pe2_ss_c_txn(11)" )
			)
			( signal "P3E_CPU0_PE2_SS_C_TXN<12>"
				( objectStatus "@baseboard_fab2_lib.baseboard_fab2(sch_1):p3e_cpu0_pe2_ss_c_txn(12)" )
			)
			( signal "P3E_CPU0_PE2_SS_C_TXN<13>"
				( objectStatus "@baseboard_fab2_lib.baseboard_fab2(sch_1):p3e_cpu0_pe2_ss_c_txn(13)" )
			)
			( signal "P3E_CPU0_PE2_SS_C_TXN<14>"
				( objectStatus "@baseboard_fab2_lib.baseboard_fab2(sch_1):p3e_cpu0_pe2_ss_c_txn(14)" )
			)
			( signal "P3E_CPU0_PE2_SS_C_TXN<15>"
				( objectStatus "@baseboard_fab2_lib.baseboard_fab2(sch_1):p3e_cpu0_pe2_ss_c_txn(15)" )
			)
			( signal "P3E_CPU0_PE2_SS_C_TXP<0>"
				( objectStatus "@baseboard_fab2_lib.baseboard_fab2(sch_1):p3e_cpu0_pe2_ss_c_txp(0)" )
			)
			( signal "P3E_CPU0_PE2_SS_C_TXP<1>"
				( objectStatus "@baseboard_fab2_lib.baseboard_fab2(sch_1):p3e_cpu0_pe2_ss_c_txp(1)" )
			)
			( signal "P3E_CPU0_PE2_SS_C_TXP<2>"
				( objectStatus "@baseboard_fab2_lib.baseboard_fab2(sch_1):p3e_cpu0_pe2_ss_c_txp(2)" )
			)
			( signal "P3E_CPU0_PE2_SS_C_TXP<3>"
				( objectStatus "@baseboard_fab2_lib.baseboard_fab2(sch_1):p3e_cpu0_pe2_ss_c_txp(3)" )
			)
			( signal "P3E_CPU0_PE2_SS_C_TXP<4>"
				( objectStatus "@baseboard_fab2_lib.baseboard_fab2(sch_1):p3e_cpu0_pe2_ss_c_txp(4)" )
			)
			( signal "P3E_CPU0_PE2_SS_C_TXP<5>"
				( objectStatus "@baseboard_fab2_lib.baseboard_fab2(sch_1):p3e_cpu0_pe2_ss_c_txp(5)" )
			)
			( signal "P3E_CPU0_PE2_SS_C_TXP<6>"
				( objectStatus "@baseboard_fab2_lib.baseboard_fab2(sch_1):p3e_cpu0_pe2_ss_c_txp(6)" )
			)
			( signal "P3E_CPU0_PE2_SS_C_TXP<7>"
				( objectStatus "@baseboard_fab2_lib.baseboard_fab2(sch_1):p3e_cpu0_pe2_ss_c_txp(7)" )
			)
			( signal "P3E_CPU0_PE2_SS_C_TXP<8>"
				( objectStatus "@baseboard_fab2_lib.baseboard_fab2(sch_1):p3e_cpu0_pe2_ss_c_txp(8)" )
			)
			( signal "P3E_CPU0_PE2_SS_C_TXP<9>"
				( objectStatus "@baseboard_fab2_lib.baseboard_fab2(sch_1):p3e_cpu0_pe2_ss_c_txp(9)" )
			)
			( signal "P3E_CPU0_PE2_SS_C_TXP<10>"
				( objectStatus "@baseboard_fab2_lib.baseboard_fab2(sch_1):p3e_cpu0_pe2_ss_c_txp(10)" )
			)
			( signal "P3E_CPU0_PE2_SS_C_TXP<11>"
				( objectStatus "@baseboard_fab2_lib.baseboard_fab2(sch_1):p3e_cpu0_pe2_ss_c_txp(11)" )
			)
			( signal "P3E_CPU0_PE2_SS_C_TXP<12>"
				( objectStatus "@baseboard_fab2_lib.baseboard_fab2(sch_1):p3e_cpu0_pe2_ss_c_txp(12)" )
			)
			( signal "P3E_CPU0_PE2_SS_C_TXP<13>"
				( objectStatus "@baseboard_fab2_lib.baseboard_fab2(sch_1):p3e_cpu0_pe2_ss_c_txp(13)" )
			)
			( signal "P3E_CPU0_PE2_SS_C_TXP<14>"
				( objectStatus "@baseboard_fab2_lib.baseboard_fab2(sch_1):p3e_cpu0_pe2_ss_c_txp(14)" )
			)
			( signal "P3E_CPU0_PE2_SS_C_TXP<15>"
				( objectStatus "@baseboard_fab2_lib.baseboard_fab2(sch_1):p3e_cpu0_pe2_ss_c_txp(15)" )
			)
			( signal "P3E_OCP_CPU0_PE3_C_TXN<0>"
				( objectStatus "@baseboard_fab2_lib.baseboard_fab2(sch_1):p3e_ocp_cpu0_pe3_c_txn(0)" )
			)
			( signal "P3E_OCP_CPU0_PE3_C_TXN<1>"
				( objectStatus "@baseboard_fab2_lib.baseboard_fab2(sch_1):p3e_ocp_cpu0_pe3_c_txn(1)" )
			)
			( signal "P3E_OCP_CPU0_PE3_C_TXN<2>"
				( objectStatus "@baseboard_fab2_lib.baseboard_fab2(sch_1):p3e_ocp_cpu0_pe3_c_txn(2)" )
			)
			( signal "P3E_OCP_CPU0_PE3_C_TXN<3>"
				( objectStatus "@baseboard_fab2_lib.baseboard_fab2(sch_1):p3e_ocp_cpu0_pe3_c_txn(3)" )
			)
			( signal "P3E_OCP_CPU0_PE3_C_TXN<4>"
				( objectStatus "@baseboard_fab2_lib.baseboard_fab2(sch_1):p3e_ocp_cpu0_pe3_c_txn(4)" )
			)
			( signal "P3E_OCP_CPU0_PE3_C_TXN<5>"
				( objectStatus "@baseboard_fab2_lib.baseboard_fab2(sch_1):p3e_ocp_cpu0_pe3_c_txn(5)" )
			)
			( signal "P3E_OCP_CPU0_PE3_C_TXN<6>"
				( objectStatus "@baseboard_fab2_lib.baseboard_fab2(sch_1):p3e_ocp_cpu0_pe3_c_txn(6)" )
			)
			( signal "P3E_OCP_CPU0_PE3_C_TXN<7>"
				( objectStatus "@baseboard_fab2_lib.baseboard_fab2(sch_1):p3e_ocp_cpu0_pe3_c_txn(7)" )
			)
			( signal "P3E_OCP_CPU0_PE3_C_TXN<8>"
				( objectStatus "@baseboard_fab2_lib.baseboard_fab2(sch_1):p3e_ocp_cpu0_pe3_c_txn(8)" )
			)
			( signal "P3E_OCP_CPU0_PE3_C_TXN<9>"
				( objectStatus "@baseboard_fab2_lib.baseboard_fab2(sch_1):p3e_ocp_cpu0_pe3_c_txn(9)" )
			)
			( signal "P3E_OCP_CPU0_PE3_C_TXN<10>"
				( objectStatus "@baseboard_fab2_lib.baseboard_fab2(sch_1):p3e_ocp_cpu0_pe3_c_txn(10)" )
			)
			( signal "P3E_OCP_CPU0_PE3_C_TXN<11>"
				( objectStatus "@baseboard_fab2_lib.baseboard_fab2(sch_1):p3e_ocp_cpu0_pe3_c_txn(11)" )
			)
			( signal "P3E_OCP_CPU0_PE3_C_TXN<12>"
				( objectStatus "@baseboard_fab2_lib.baseboard_fab2(sch_1):p3e_ocp_cpu0_pe3_c_txn(12)" )
			)
			( signal "P3E_OCP_CPU0_PE3_C_TXN<13>"
				( objectStatus "@baseboard_fab2_lib.baseboard_fab2(sch_1):p3e_ocp_cpu0_pe3_c_txn(13)" )
			)
			( signal "P3E_OCP_CPU0_PE3_C_TXN<14>"
				( objectStatus "@baseboard_fab2_lib.baseboard_fab2(sch_1):p3e_ocp_cpu0_pe3_c_txn(14)" )
			)
			( signal "P3E_OCP_CPU0_PE3_C_TXN<15>"
				( objectStatus "@baseboard_fab2_lib.baseboard_fab2(sch_1):p3e_ocp_cpu0_pe3_c_txn(15)" )
			)
			( signal "P3E_OCP_CPU0_PE3_C_TXP<0>"
				( objectStatus "@baseboard_fab2_lib.baseboard_fab2(sch_1):p3e_ocp_cpu0_pe3_c_txp(0)" )
			)
			( signal "P3E_OCP_CPU0_PE3_C_TXP<1>"
				( objectStatus "@baseboard_fab2_lib.baseboard_fab2(sch_1):p3e_ocp_cpu0_pe3_c_txp(1)" )
			)
			( signal "P3E_OCP_CPU0_PE3_C_TXP<2>"
				( objectStatus "@baseboard_fab2_lib.baseboard_fab2(sch_1):p3e_ocp_cpu0_pe3_c_txp(2)" )
			)
			( signal "P3E_OCP_CPU0_PE3_C_TXP<3>"
				( objectStatus "@baseboard_fab2_lib.baseboard_fab2(sch_1):p3e_ocp_cpu0_pe3_c_txp(3)" )
			)
			( signal "P3E_OCP_CPU0_PE3_C_TXP<4>"
				( objectStatus "@baseboard_fab2_lib.baseboard_fab2(sch_1):p3e_ocp_cpu0_pe3_c_txp(4)" )
			)
			( signal "P3E_OCP_CPU0_PE3_C_TXP<5>"
				( objectStatus "@baseboard_fab2_lib.baseboard_fab2(sch_1):p3e_ocp_cpu0_pe3_c_txp(5)" )
			)
			( signal "P3E_OCP_CPU0_PE3_C_TXP<6>"
				( objectStatus "@baseboard_fab2_lib.baseboard_fab2(sch_1):p3e_ocp_cpu0_pe3_c_txp(6)" )
			)
			( signal "P3E_OCP_CPU0_PE3_C_TXP<7>"
				( objectStatus "@baseboard_fab2_lib.baseboard_fab2(sch_1):p3e_ocp_cpu0_pe3_c_txp(7)" )
			)
			( signal "P3E_OCP_CPU0_PE3_C_TXP<8>"
				( objectStatus "@baseboard_fab2_lib.baseboard_fab2(sch_1):p3e_ocp_cpu0_pe3_c_txp(8)" )
			)
			( signal "P3E_OCP_CPU0_PE3_C_TXP<9>"
				( objectStatus "@baseboard_fab2_lib.baseboard_fab2(sch_1):p3e_ocp_cpu0_pe3_c_txp(9)" )
			)
			( signal "P3E_OCP_CPU0_PE3_C_TXP<10>"
				( objectStatus "@baseboard_fab2_lib.baseboard_fab2(sch_1):p3e_ocp_cpu0_pe3_c_txp(10)" )
			)
			( signal "P3E_OCP_CPU0_PE3_C_TXP<11>"
				( objectStatus "@baseboard_fab2_lib.baseboard_fab2(sch_1):p3e_ocp_cpu0_pe3_c_txp(11)" )
			)
			( signal "P3E_OCP_CPU0_PE3_C_TXP<12>"
				( objectStatus "@baseboard_fab2_lib.baseboard_fab2(sch_1):p3e_ocp_cpu0_pe3_c_txp(12)" )
			)
			( signal "P3E_OCP_CPU0_PE3_C_TXP<13>"
				( objectStatus "@baseboard_fab2_lib.baseboard_fab2(sch_1):p3e_ocp_cpu0_pe3_c_txp(13)" )
			)
			( signal "P3E_OCP_CPU0_PE3_C_TXP<14>"
				( objectStatus "@baseboard_fab2_lib.baseboard_fab2(sch_1):p3e_ocp_cpu0_pe3_c_txp(14)" )
			)
			( signal "P3E_OCP_CPU0_PE3_C_TXP<15>"
				( objectStatus "@baseboard_fab2_lib.baseboard_fab2(sch_1):p3e_ocp_cpu0_pe3_c_txp(15)" )
			)
			( signal "P3E_CPU0_PE1_PCH_RXN<0>"
				( objectStatus "@baseboard_fab2_lib.baseboard_fab2(sch_1):p3e_cpu0_pe1_pch_rxn(0)" )
			)
			( signal "P3E_CPU0_PE1_PCH_RXN<1>"
				( objectStatus "@baseboard_fab2_lib.baseboard_fab2(sch_1):p3e_cpu0_pe1_pch_rxn(1)" )
			)
			( signal "P3E_CPU0_PE1_PCH_RXN<2>"
				( objectStatus "@baseboard_fab2_lib.baseboard_fab2(sch_1):p3e_cpu0_pe1_pch_rxn(2)" )
			)
			( signal "P3E_CPU0_PE1_PCH_RXN<3>"
				( objectStatus "@baseboard_fab2_lib.baseboard_fab2(sch_1):p3e_cpu0_pe1_pch_rxn(3)" )
			)
			( signal "P3E_CPU0_PE1_PCH_RXN<4>"
				( objectStatus "@baseboard_fab2_lib.baseboard_fab2(sch_1):p3e_cpu0_pe1_pch_rxn(4)" )
			)
			( signal "P3E_CPU0_PE1_PCH_RXN<5>"
				( objectStatus "@baseboard_fab2_lib.baseboard_fab2(sch_1):p3e_cpu0_pe1_pch_rxn(5)" )
			)
			( signal "P3E_CPU0_PE1_PCH_RXN<6>"
				( objectStatus "@baseboard_fab2_lib.baseboard_fab2(sch_1):p3e_cpu0_pe1_pch_rxn(6)" )
			)
			( signal "P3E_CPU0_PE1_PCH_RXN<7>"
				( objectStatus "@baseboard_fab2_lib.baseboard_fab2(sch_1):p3e_cpu0_pe1_pch_rxn(7)" )
			)
			( signal "P3E_CPU0_PE1_PCH_RXP<0>"
				( objectStatus "@baseboard_fab2_lib.baseboard_fab2(sch_1):p3e_cpu0_pe1_pch_rxp(0)" )
			)
			( signal "P3E_CPU0_PE1_PCH_RXP<1>"
				( objectStatus "@baseboard_fab2_lib.baseboard_fab2(sch_1):p3e_cpu0_pe1_pch_rxp(1)" )
			)
			( signal "P3E_CPU0_PE1_PCH_RXP<2>"
				( objectStatus "@baseboard_fab2_lib.baseboard_fab2(sch_1):p3e_cpu0_pe1_pch_rxp(2)" )
			)
			( signal "P3E_CPU0_PE1_PCH_RXP<3>"
				( objectStatus "@baseboard_fab2_lib.baseboard_fab2(sch_1):p3e_cpu0_pe1_pch_rxp(3)" )
			)
			( signal "P3E_CPU0_PE1_PCH_RXP<4>"
				( objectStatus "@baseboard_fab2_lib.baseboard_fab2(sch_1):p3e_cpu0_pe1_pch_rxp(4)" )
			)
			( signal "P3E_CPU0_PE1_PCH_RXP<5>"
				( objectStatus "@baseboard_fab2_lib.baseboard_fab2(sch_1):p3e_cpu0_pe1_pch_rxp(5)" )
			)
			( signal "P3E_CPU0_PE1_PCH_RXP<6>"
				( objectStatus "@baseboard_fab2_lib.baseboard_fab2(sch_1):p3e_cpu0_pe1_pch_rxp(6)" )
			)
			( signal "P3E_CPU0_PE1_PCH_RXP<7>"
				( objectStatus "@baseboard_fab2_lib.baseboard_fab2(sch_1):p3e_cpu0_pe1_pch_rxp(7)" )
			)
			( signal "P3E_CPU0_PE1_PCH_TXN<0>"
				( objectStatus "@baseboard_fab2_lib.baseboard_fab2(sch_1):p3e_cpu0_pe1_pch_txn(0)" )
			)
			( signal "P3E_CPU0_PE1_PCH_TXN<1>"
				( objectStatus "@baseboard_fab2_lib.baseboard_fab2(sch_1):p3e_cpu0_pe1_pch_txn(1)" )
			)
			( signal "P3E_CPU0_PE1_PCH_TXN<2>"
				( objectStatus "@baseboard_fab2_lib.baseboard_fab2(sch_1):p3e_cpu0_pe1_pch_txn(2)" )
			)
			( signal "P3E_CPU0_PE1_PCH_TXN<3>"
				( objectStatus "@baseboard_fab2_lib.baseboard_fab2(sch_1):p3e_cpu0_pe1_pch_txn(3)" )
			)
			( signal "P3E_CPU0_PE1_PCH_TXN<4>"
				( objectStatus "@baseboard_fab2_lib.baseboard_fab2(sch_1):p3e_cpu0_pe1_pch_txn(4)" )
			)
			( signal "P3E_CPU0_PE1_PCH_TXN<5>"
				( objectStatus "@baseboard_fab2_lib.baseboard_fab2(sch_1):p3e_cpu0_pe1_pch_txn(5)" )
			)
			( signal "P3E_CPU0_PE1_PCH_TXN<6>"
				( objectStatus "@baseboard_fab2_lib.baseboard_fab2(sch_1):p3e_cpu0_pe1_pch_txn(6)" )
			)
			( signal "P3E_CPU0_PE1_PCH_TXN<7>"
				( objectStatus "@baseboard_fab2_lib.baseboard_fab2(sch_1):p3e_cpu0_pe1_pch_txn(7)" )
			)
			( signal "P3E_CPU0_PE1_PCH_TXP<0>"
				( objectStatus "@baseboard_fab2_lib.baseboard_fab2(sch_1):p3e_cpu0_pe1_pch_txp(0)" )
			)
			( signal "P3E_CPU0_PE1_PCH_TXP<1>"
				( objectStatus "@baseboard_fab2_lib.baseboard_fab2(sch_1):p3e_cpu0_pe1_pch_txp(1)" )
			)
			( signal "P3E_CPU0_PE1_PCH_TXP<2>"
				( objectStatus "@baseboard_fab2_lib.baseboard_fab2(sch_1):p3e_cpu0_pe1_pch_txp(2)" )
			)
			( signal "P3E_CPU0_PE1_PCH_TXP<3>"
				( objectStatus "@baseboard_fab2_lib.baseboard_fab2(sch_1):p3e_cpu0_pe1_pch_txp(3)" )
			)
			( signal "P3E_CPU0_PE1_PCH_TXP<4>"
				( objectStatus "@baseboard_fab2_lib.baseboard_fab2(sch_1):p3e_cpu0_pe1_pch_txp(4)" )
			)
			( signal "P3E_CPU0_PE1_PCH_TXP<5>"
				( objectStatus "@baseboard_fab2_lib.baseboard_fab2(sch_1):p3e_cpu0_pe1_pch_txp(5)" )
			)
			( signal "P3E_CPU0_PE1_PCH_TXP<6>"
				( objectStatus "@baseboard_fab2_lib.baseboard_fab2(sch_1):p3e_cpu0_pe1_pch_txp(6)" )
			)
			( signal "P3E_CPU0_PE1_PCH_TXP<7>"
				( objectStatus "@baseboard_fab2_lib.baseboard_fab2(sch_1):p3e_cpu0_pe1_pch_txp(7)" )
			)
			( signal "P3E_CPU0_PE1_SS_C_TXN<0>"
				( objectStatus "@baseboard_fab2_lib.baseboard_fab2(sch_1):p3e_cpu0_pe1_ss_c_txn(0)" )
			)
			( signal "P3E_CPU0_PE1_SS_C_TXN<1>"
				( objectStatus "@baseboard_fab2_lib.baseboard_fab2(sch_1):p3e_cpu0_pe1_ss_c_txn(1)" )
			)
			( signal "P3E_CPU0_PE1_SS_C_TXN<2>"
				( objectStatus "@baseboard_fab2_lib.baseboard_fab2(sch_1):p3e_cpu0_pe1_ss_c_txn(2)" )
			)
			( signal "P3E_CPU0_PE1_SS_C_TXN<3>"
				( objectStatus "@baseboard_fab2_lib.baseboard_fab2(sch_1):p3e_cpu0_pe1_ss_c_txn(3)" )
			)
			( signal "P3E_CPU0_PE1_SS_C_TXN<4>"
				( objectStatus "@baseboard_fab2_lib.baseboard_fab2(sch_1):p3e_cpu0_pe1_ss_c_txn(4)" )
			)
			( signal "P3E_CPU0_PE1_SS_C_TXN<5>"
				( objectStatus "@baseboard_fab2_lib.baseboard_fab2(sch_1):p3e_cpu0_pe1_ss_c_txn(5)" )
			)
			( signal "P3E_CPU0_PE1_SS_C_TXN<6>"
				( objectStatus "@baseboard_fab2_lib.baseboard_fab2(sch_1):p3e_cpu0_pe1_ss_c_txn(6)" )
			)
			( signal "P3E_CPU0_PE1_SS_C_TXN<7>"
				( objectStatus "@baseboard_fab2_lib.baseboard_fab2(sch_1):p3e_cpu0_pe1_ss_c_txn(7)" )
			)
			( signal "P3E_CPU0_PE1_SS_C_TXP<0>"
				( objectStatus "@baseboard_fab2_lib.baseboard_fab2(sch_1):p3e_cpu0_pe1_ss_c_txp(0)" )
			)
			( signal "P3E_CPU0_PE1_SS_C_TXP<1>"
				( objectStatus "@baseboard_fab2_lib.baseboard_fab2(sch_1):p3e_cpu0_pe1_ss_c_txp(1)" )
			)
			( signal "P3E_CPU0_PE1_SS_C_TXP<2>"
				( objectStatus "@baseboard_fab2_lib.baseboard_fab2(sch_1):p3e_cpu0_pe1_ss_c_txp(2)" )
			)
			( signal "P3E_CPU0_PE1_SS_C_TXP<3>"
				( objectStatus "@baseboard_fab2_lib.baseboard_fab2(sch_1):p3e_cpu0_pe1_ss_c_txp(3)" )
			)
			( signal "P3E_CPU0_PE1_SS_C_TXP<4>"
				( objectStatus "@baseboard_fab2_lib.baseboard_fab2(sch_1):p3e_cpu0_pe1_ss_c_txp(4)" )
			)
			( signal "P3E_CPU0_PE1_SS_C_TXP<5>"
				( objectStatus "@baseboard_fab2_lib.baseboard_fab2(sch_1):p3e_cpu0_pe1_ss_c_txp(5)" )
			)
			( signal "P3E_CPU0_PE1_SS_C_TXP<6>"
				( objectStatus "@baseboard_fab2_lib.baseboard_fab2(sch_1):p3e_cpu0_pe1_ss_c_txp(6)" )
			)
			( signal "P3E_CPU0_PE1_SS_C_TXP<7>"
				( objectStatus "@baseboard_fab2_lib.baseboard_fab2(sch_1):p3e_cpu0_pe1_ss_c_txp(7)" )
			)
			( signal "P3E_CPU0_PE1_SS_R_RXN<0>"
				( objectStatus "@baseboard_fab2_lib.baseboard_fab2(sch_1):p3e_cpu0_pe1_ss_r_rxn(0)" )
			)
			( signal "P3E_CPU0_PE1_SS_R_RXN<1>"
				( objectStatus "@baseboard_fab2_lib.baseboard_fab2(sch_1):p3e_cpu0_pe1_ss_r_rxn(1)" )
			)
			( signal "P3E_CPU0_PE1_SS_R_RXN<2>"
				( objectStatus "@baseboard_fab2_lib.baseboard_fab2(sch_1):p3e_cpu0_pe1_ss_r_rxn(2)" )
			)
			( signal "P3E_CPU0_PE1_SS_R_RXN<3>"
				( objectStatus "@baseboard_fab2_lib.baseboard_fab2(sch_1):p3e_cpu0_pe1_ss_r_rxn(3)" )
			)
			( signal "P3E_CPU0_PE1_SS_R_RXN<4>"
				( objectStatus "@baseboard_fab2_lib.baseboard_fab2(sch_1):p3e_cpu0_pe1_ss_r_rxn(4)" )
			)
			( signal "P3E_CPU0_PE1_SS_R_RXN<5>"
				( objectStatus "@baseboard_fab2_lib.baseboard_fab2(sch_1):p3e_cpu0_pe1_ss_r_rxn(5)" )
			)
			( signal "P3E_CPU0_PE1_SS_R_RXN<6>"
				( objectStatus "@baseboard_fab2_lib.baseboard_fab2(sch_1):p3e_cpu0_pe1_ss_r_rxn(6)" )
			)
			( signal "P3E_CPU0_PE1_SS_R_RXN<7>"
				( objectStatus "@baseboard_fab2_lib.baseboard_fab2(sch_1):p3e_cpu0_pe1_ss_r_rxn(7)" )
			)
			( signal "P3E_CPU0_PE1_SS_R_RXP<0>"
				( objectStatus "@baseboard_fab2_lib.baseboard_fab2(sch_1):p3e_cpu0_pe1_ss_r_rxp(0)" )
			)
			( signal "P3E_CPU0_PE1_SS_R_RXP<1>"
				( objectStatus "@baseboard_fab2_lib.baseboard_fab2(sch_1):p3e_cpu0_pe1_ss_r_rxp(1)" )
			)
			( signal "P3E_CPU0_PE1_SS_R_RXP<2>"
				( objectStatus "@baseboard_fab2_lib.baseboard_fab2(sch_1):p3e_cpu0_pe1_ss_r_rxp(2)" )
			)
			( signal "P3E_CPU0_PE1_SS_R_RXP<3>"
				( objectStatus "@baseboard_fab2_lib.baseboard_fab2(sch_1):p3e_cpu0_pe1_ss_r_rxp(3)" )
			)
			( signal "P3E_CPU0_PE1_SS_R_RXP<4>"
				( objectStatus "@baseboard_fab2_lib.baseboard_fab2(sch_1):p3e_cpu0_pe1_ss_r_rxp(4)" )
			)
			( signal "P3E_CPU0_PE1_SS_R_RXP<5>"
				( objectStatus "@baseboard_fab2_lib.baseboard_fab2(sch_1):p3e_cpu0_pe1_ss_r_rxp(5)" )
			)
			( signal "P3E_CPU0_PE1_SS_R_RXP<6>"
				( objectStatus "@baseboard_fab2_lib.baseboard_fab2(sch_1):p3e_cpu0_pe1_ss_r_rxp(6)" )
			)
			( signal "P3E_CPU0_PE1_SS_R_RXP<7>"
				( objectStatus "@baseboard_fab2_lib.baseboard_fab2(sch_1):p3e_cpu0_pe1_ss_r_rxp(7)" )
			)
			( signal "CLK_100M_PCH_SLOTX24_S0_DN"
				( objectStatus "@baseboard_fab2_lib.baseboard_fab2(sch_1):clk_100m_pch_slotx24_s0_dn" )
			)
			( signal "CLK_100M_PCH_SLOTX24_S0_DP"
				( objectStatus "@baseboard_fab2_lib.baseboard_fab2(sch_1):clk_100m_pch_slotx24_s0_dp" )
			)
			( signal "CLK_100M_PCH_SLOTX24_S1_DN"
				( objectStatus "@baseboard_fab2_lib.baseboard_fab2(sch_1):clk_100m_pch_slotx24_s1_dn" )
			)
			( signal "CLK_100M_PCH_SLOTX24_S1_DP"
				( objectStatus "@baseboard_fab2_lib.baseboard_fab2(sch_1):clk_100m_pch_slotx24_s1_dp" )
			)
			( signal "CLK_100M_PCH_SLOTX24_S2_DN"
				( objectStatus "@baseboard_fab2_lib.baseboard_fab2(sch_1):clk_100m_pch_slotx24_s2_dn" )
			)
			( signal "CLK_100M_PCH_SLOTX24_S2_DP"
				( objectStatus "@baseboard_fab2_lib.baseboard_fab2(sch_1):clk_100m_pch_slotx24_s2_dp" )
			)
			( signal "CLK_100M_PCH_SLOTX24_S3_DN"
				( objectStatus "@baseboard_fab2_lib.baseboard_fab2(sch_1):clk_100m_pch_slotx24_s3_dn" )
			)
			( signal "CLK_100M_PCH_SLOTX24_S3_DP"
				( objectStatus "@baseboard_fab2_lib.baseboard_fab2(sch_1):clk_100m_pch_slotx24_s3_dp" )
			)
			( signal "CLK_100M_PCH_SLOTX24_S4_DN"
				( objectStatus "@baseboard_fab2_lib.baseboard_fab2(sch_1):clk_100m_pch_slotx24_s4_dn" )
			)
			( signal "CLK_100M_PCH_SLOTX24_S4_DP"
				( objectStatus "@baseboard_fab2_lib.baseboard_fab2(sch_1):clk_100m_pch_slotx24_s4_dp" )
			)
			( signal "CLK_100M_PCH_SLOTX24_S5_DN"
				( objectStatus "@baseboard_fab2_lib.baseboard_fab2(sch_1):clk_100m_pch_slotx24_s5_dn" )
			)
			( signal "CLK_100M_PCH_SLOTX24_S5_DP"
				( objectStatus "@baseboard_fab2_lib.baseboard_fab2(sch_1):clk_100m_pch_slotx24_s5_dp" )
			)
			( signal "FM_PE_SLOTX24_WAKE_N"
				( objectStatus "@baseboard_fab2_lib.baseboard_fab2(sch_1):fm_pe_slotx24_wake_n" )
			)
			( signal "FM_PRSNT_2_1_N"
				( objectStatus "@baseboard_fab2_lib.baseboard_fab2(sch_1):fm_prsnt_2_1_n" )
			)
			( signal "FM_PRSNT_2_2_N"
				( objectStatus "@baseboard_fab2_lib.baseboard_fab2(sch_1):fm_prsnt_2_2_n" )
			)
			( signal "FM_PRSNT_2_3_N"
				( objectStatus "@baseboard_fab2_lib.baseboard_fab2(sch_1):fm_prsnt_2_3_n" )
			)
			( signal "FM_PRSNT_2_4_N"
				( objectStatus "@baseboard_fab2_lib.baseboard_fab2(sch_1):fm_prsnt_2_4_n" )
			)
			( signal "FM_PRSNT_2_5_N"
				( objectStatus "@baseboard_fab2_lib.baseboard_fab2(sch_1):fm_prsnt_2_5_n" )
			)
			( signal "FM_PWRBRK_SLOT_N"
				( objectStatus "@baseboard_fab2_lib.baseboard_fab2(sch_1):fm_pwrbrk_slot_n" )
			)
			( signal "FM_SLT_CFG0"
				( objectStatus "@baseboard_fab2_lib.baseboard_fab2(sch_1):fm_slt_cfg0" )
			)
			( signal "FM_SLT_CFG1"
				( objectStatus "@baseboard_fab2_lib.baseboard_fab2(sch_1):fm_slt_cfg1" )
			)
			( signal "IRQ_OOB_MGMT_RISER_ALERT_N"
				( objectStatus "@baseboard_fab2_lib.baseboard_fab2(sch_1):irq_oob_mgmt_riser_alert_n" )
			)
			( signal "P12V"
				( attribute "VOLTAGE" "+12."
					( Units "uVoltage" "V" 1.000000)
					( Status sAliasFlattened )
					( Status sAliasConflict )
					( Origin gFrontEnd )
				)
				( objectStatus "@baseboard_fab2_lib.baseboard_fab2(sch_1):p12v" )
			)
			( signal "RST_PCIE_RISER1_PERST_N"
				( objectStatus "@baseboard_fab2_lib.baseboard_fab2(sch_1):rst_pcie_riser1_perst_n" )
			)
			( signal "RST_PCIE_RISER1_PERST_R_N"
				( objectStatus "@baseboard_fab2_lib.baseboard_fab2(sch_1):rst_pcie_riser1_perst_r_n" )
			)
			( signal "SMB_SLOTX24_BMC_STBY_LVC3_SCL"
				( objectStatus "@baseboard_fab2_lib.baseboard_fab2(sch_1):smb_slotx24_bmc_stby_lvc3_scl" )
			)
			( signal "SMB_SLOTX24_BMC_STBY_LVC3_SDA"
				( objectStatus "@baseboard_fab2_lib.baseboard_fab2(sch_1):smb_slotx24_bmc_stby_lvc3_sda" )
			)
			( signal "SMB_SLOTX24_PCH_STBY_LVC3_SCL"
				( objectStatus "@baseboard_fab2_lib.baseboard_fab2(sch_1):smb_slotx24_pch_stby_lvc3_scl" )
			)
			( signal "SMB_SLOTX24_PCH_STBY_LVC3_SDA"
				( objectStatus "@baseboard_fab2_lib.baseboard_fab2(sch_1):smb_slotx24_pch_stby_lvc3_sda" )
			)
			( signal "SMB_SLOTX24_STBY_LVC3_SCL_R2"
				( objectStatus "@baseboard_fab2_lib.baseboard_fab2(sch_1):smb_slotx24_stby_lvc3_scl_r2" )
			)
			( signal "SMB_SLOTX24_STBY_LVC3_SDA_R2"
				( objectStatus "@baseboard_fab2_lib.baseboard_fab2(sch_1):smb_slotx24_stby_lvc3_sda_r2" )
			)
			( signal "FM_PRSNT_2_6_N"
				( objectStatus "@baseboard_fab2_lib.baseboard_fab2(sch_1):fm_prsnt_2_6_n" )
			)
			( signal "GND_SIGNAL1"
				( attribute "VOLTAGE" "0.0V"
					( Units "uVoltage" "V" 1.000000)
					( Status sAliasFlattened )
					( Origin gFrontEnd )
				)
				( objectStatus "@baseboard_fab2_lib.baseboard_fab2(sch_1):gnd_signal1" )
			)
			( signal "GND_SIGNAL2"
				( attribute "VOLTAGE" "0.0V"
					( Units "uVoltage" "V" 1.000000)
					( Status sAliasFlattened )
					( Origin gFrontEnd )
				)
				( objectStatus "@baseboard_fab2_lib.baseboard_fab2(sch_1):gnd_signal2" )
			)
			( signal "L10_Z85_SL"
				( objectStatus "@baseboard_fab2_lib.baseboard_fab2(sch_1):l10_z85_sl" )
			)
			( signal "L12_Z85_SL"
				( objectStatus "@baseboard_fab2_lib.baseboard_fab2(sch_1):l12_z85_sl" )
			)
			( signal "L14_Z100_MS"
				( objectStatus "@baseboard_fab2_lib.baseboard_fab2(sch_1):l14_z100_ms" )
			)
			( signal "L14_Z85_MS"
				( objectStatus "@baseboard_fab2_lib.baseboard_fab2(sch_1):l14_z85_ms" )
			)
			( signal "L1_Z100_MS"
				( objectStatus "@baseboard_fab2_lib.baseboard_fab2(sch_1):l1_z100_ms" )
			)
			( signal "L1_Z85_MS"
				( objectStatus "@baseboard_fab2_lib.baseboard_fab2(sch_1):l1_z85_ms" )
			)
			( signal "L1_Z85_THRU"
				( objectStatus "@baseboard_fab2_lib.baseboard_fab2(sch_1):l1_z85_thru" )
			)
			( signal "L3_Z85_SL"
				( objectStatus "@baseboard_fab2_lib.baseboard_fab2(sch_1):l3_z85_sl" )
			)
			( signal "L5_Z85_SL"
				( objectStatus "@baseboard_fab2_lib.baseboard_fab2(sch_1):l5_z85_sl" )
			)
			( signal "RCC_DFX_1940_1"
				( objectStatus "@baseboard_fab2_lib.baseboard_fab2(sch_1):rcc_dfx_1940_1" )
			)
			( signal "RCC_DFX_1940_2"
				( objectStatus "@baseboard_fab2_lib.baseboard_fab2(sch_1):rcc_dfx_1940_2" )
			)
			( signal "RCC_DFX_1940_3"
				( objectStatus "@baseboard_fab2_lib.baseboard_fab2(sch_1):rcc_dfx_1940_3" )
			)
			( signal "RCC_DFX_1940_4"
				( objectStatus "@baseboard_fab2_lib.baseboard_fab2(sch_1):rcc_dfx_1940_4" )
			)
			( signal "CLK_100M_PCH_XDP_DN"
				( objectStatus "@baseboard_fab2_lib.baseboard_fab2(sch_1):clk_100m_pch_xdp_dn" )
			)
			( signal "CLK_100M_PCH_XDP_DP"
				( objectStatus "@baseboard_fab2_lib.baseboard_fab2(sch_1):clk_100m_pch_xdp_dp" )
			)
			( signal "FM_DEBUG_RST_BTN_N"
				( objectStatus "@baseboard_fab2_lib.baseboard_fab2(sch_1):fm_debug_rst_btn_n" )
			)
			( signal "FM_DEBUG_RST_BTN_R1_N"
				( objectStatus "@baseboard_fab2_lib.baseboard_fab2(sch_1):fm_debug_rst_btn_r1_n" )
			)
			( signal "P1V05_PCH_STBY"
				( attribute "VOLTAGE" "1.05V"
					( Units "uVoltage" "V" 1.000000)
					( Status sAliasFlattened )
					( Origin gFrontEnd )
				)
				( objectStatus "@baseboard_fab2_lib.baseboard_fab2(sch_1):p1v05_pch_stby" )
			)
			( signal "RST_RSMRST_N"
				( objectStatus "@baseboard_fab2_lib.baseboard_fab2(sch_1):rst_rsmrst_n" )
			)
			( signal "SPI_PCH_IO2"
				( objectStatus "@baseboard_fab2_lib.baseboard_fab2(sch_1):spi_pch_io2" )
			)
			( signal "SPI_PCH_MOSI"
				( objectStatus "@baseboard_fab2_lib.baseboard_fab2(sch_1):spi_pch_mosi" )
			)
			( signal "TP_XDP_CPU_OBSDATA_C0"
				( objectStatus "@baseboard_fab2_lib.baseboard_fab2(sch_1):tp_xdp_cpu_obsdata_c0" )
			)
			( signal "TP_XDP_CPU_OBSDATA_C1"
				( objectStatus "@baseboard_fab2_lib.baseboard_fab2(sch_1):tp_xdp_cpu_obsdata_c1" )
			)
			( signal "TP_XDP_CPU_OBSDATA_C2"
				( objectStatus "@baseboard_fab2_lib.baseboard_fab2(sch_1):tp_xdp_cpu_obsdata_c2" )
			)
			( signal "TP_XDP_CPU_OBSDATA_C3"
				( objectStatus "@baseboard_fab2_lib.baseboard_fab2(sch_1):tp_xdp_cpu_obsdata_c3" )
			)
			( signal "TP_XDP_CPU_OBSDATA_D0"
				( objectStatus "@baseboard_fab2_lib.baseboard_fab2(sch_1):tp_xdp_cpu_obsdata_d0" )
			)
			( signal "TP_XDP_CPU_OBSDATA_D1"
				( objectStatus "@baseboard_fab2_lib.baseboard_fab2(sch_1):tp_xdp_cpu_obsdata_d1" )
			)
			( signal "TP_XDP_CPU_OBSDATA_D2"
				( objectStatus "@baseboard_fab2_lib.baseboard_fab2(sch_1):tp_xdp_cpu_obsdata_d2" )
			)
			( signal "TP_XDP_CPU_OBSDATA_D3"
				( objectStatus "@baseboard_fab2_lib.baseboard_fab2(sch_1):tp_xdp_cpu_obsdata_d3" )
			)
			( signal "TP_XDP_CPU_OBSFN_C0"
				( objectStatus "@baseboard_fab2_lib.baseboard_fab2(sch_1):tp_xdp_cpu_obsfn_c0" )
			)
			( signal "TP_XDP_OBSDATA_A0"
				( objectStatus "@baseboard_fab2_lib.baseboard_fab2(sch_1):tp_xdp_obsdata_a0" )
			)
			( signal "TP_XDP_OBSDATA_A1"
				( objectStatus "@baseboard_fab2_lib.baseboard_fab2(sch_1):tp_xdp_obsdata_a1" )
			)
			( signal "TP_XDP_OBSDATA_A2"
				( objectStatus "@baseboard_fab2_lib.baseboard_fab2(sch_1):tp_xdp_obsdata_a2" )
			)
			( signal "TP_XDP_OBSDATA_A3"
				( objectStatus "@baseboard_fab2_lib.baseboard_fab2(sch_1):tp_xdp_obsdata_a3" )
			)
			( signal "TP_XDP_OBSDATA_B0"
				( objectStatus "@baseboard_fab2_lib.baseboard_fab2(sch_1):tp_xdp_obsdata_b0" )
			)
			( signal "TP_XDP_OBSDATA_B1"
				( objectStatus "@baseboard_fab2_lib.baseboard_fab2(sch_1):tp_xdp_obsdata_b1" )
			)
			( signal "TP_XDP_OBSDATA_B2"
				( objectStatus "@baseboard_fab2_lib.baseboard_fab2(sch_1):tp_xdp_obsdata_b2" )
			)
			( signal "TP_XDP_OBSDATA_B3"
				( objectStatus "@baseboard_fab2_lib.baseboard_fab2(sch_1):tp_xdp_obsdata_b3" )
			)
			( signal "TP_XDP_OBSFN_B0"
				( objectStatus "@baseboard_fab2_lib.baseboard_fab2(sch_1):tp_xdp_obsfn_b0" )
			)
			( signal "TP_XDP_OBSFN_B1"
				( objectStatus "@baseboard_fab2_lib.baseboard_fab2(sch_1):tp_xdp_obsfn_b1" )
			)
			( signal "XDP_CPU_GTL_TCK_R2"
				( objectStatus "@baseboard_fab2_lib.baseboard_fab2(sch_1):xdp_cpu_gtl_tck_r2" )
			)
			( signal "XDP_CPU_TCK_BUF"
				( objectStatus "@baseboard_fab2_lib.baseboard_fab2(sch_1):xdp_cpu_tck_buf" )
			)
			( signal "XDP_DEBUG_CONSENT_N"
				( objectStatus "@baseboard_fab2_lib.baseboard_fab2(sch_1):xdp_debug_consent_n" )
			)
			( signal "XDP_ITP_PMODE"
				( objectStatus "@baseboard_fab2_lib.baseboard_fab2(sch_1):xdp_itp_pmode" )
			)
			( signal "XDP_OBSFN_B0_MBP6_N"
				( objectStatus "@baseboard_fab2_lib.baseboard_fab2(sch_1):xdp_obsfn_b0_mbp6_n" )
			)
			( signal "XDP_OBSFN_B1_MBP7_N"
				( objectStatus "@baseboard_fab2_lib.baseboard_fab2(sch_1):xdp_obsfn_b1_mbp7_n" )
			)
			( signal "XDP_PCH_CPU_TCK0"
				( objectStatus "@baseboard_fab2_lib.baseboard_fab2(sch_1):xdp_pch_cpu_tck0" )
			)
			( signal "XDP_PCH_TCK1"
				( objectStatus "@baseboard_fab2_lib.baseboard_fab2(sch_1):xdp_pch_tck1" )
			)
			( signal "XDP_PRDY_N"
				( objectStatus "@baseboard_fab2_lib.baseboard_fab2(sch_1):xdp_prdy_n" )
			)
			( signal "XDP_PREQ_N"
				( objectStatus "@baseboard_fab2_lib.baseboard_fab2(sch_1):xdp_preq_n" )
			)
			( signal "XDP_PWRGD_RST_N"
				( objectStatus "@baseboard_fab2_lib.baseboard_fab2(sch_1):xdp_pwrgd_rst_n" )
			)
			( signal "XDP_RSMRST_N"
				( objectStatus "@baseboard_fab2_lib.baseboard_fab2(sch_1):xdp_rsmrst_n" )
			)
			( signal "XDP_RST_CO_N"
				( objectStatus "@baseboard_fab2_lib.baseboard_fab2(sch_1):xdp_rst_co_n" )
			)
			( signal "XDP_SPI_PCH_MOSI_BOOT_HALT_N"
				( objectStatus "@baseboard_fab2_lib.baseboard_fab2(sch_1):xdp_spi_pch_mosi_boot_halt_n" )
			)
			( signal "XDP_SYSPWROK"
				( objectStatus "@baseboard_fab2_lib.baseboard_fab2(sch_1):xdp_syspwrok" )
			)
			( signal "XDP_TDI"
				( objectStatus "@baseboard_fab2_lib.baseboard_fab2(sch_1):xdp_tdi" )
			)
			( signal "XDP_TDO"
				( objectStatus "@baseboard_fab2_lib.baseboard_fab2(sch_1):xdp_tdo" )
			)
			( signal "XDP_TMS"
				( objectStatus "@baseboard_fab2_lib.baseboard_fab2(sch_1):xdp_tms" )
			)
			( signal "XDP_TRST_N"
				( objectStatus "@baseboard_fab2_lib.baseboard_fab2(sch_1):xdp_trst_n" )
			)
			( signal "PWRGD_PVCCIN_CPU0"
				( objectStatus "@baseboard_fab2_lib.baseboard_fab2(sch_1):pwrgd_pvccin_cpu0" )
			)
			( signal "XDP_CPU_TDO"
				( objectStatus "@baseboard_fab2_lib.baseboard_fab2(sch_1):xdp_cpu_tdo" )
			)
			( signal "FM_CPU0_AND_CPU1_MCP_PRES"
				( objectStatus "@baseboard_fab2_lib.baseboard_fab2(sch_1):fm_cpu0_and_cpu1_mcp_pres" )
			)
			( signal "FM_CPU0_CD_PRES"
				( objectStatus "@baseboard_fab2_lib.baseboard_fab2(sch_1):fm_cpu0_cd_pres" )
			)
			( signal "FM_CPU0_OR_CPU1_MCP_PRES"
				( objectStatus "@baseboard_fab2_lib.baseboard_fab2(sch_1):fm_cpu0_or_cpu1_mcp_pres" )
			)
			( signal "FM_CPU1_CD_PRES"
				( objectStatus "@baseboard_fab2_lib.baseboard_fab2(sch_1):fm_cpu1_cd_pres" )
			)
			( signal "JTAG_MCP_CPU0_TDI_R"
				( objectStatus "@baseboard_fab2_lib.baseboard_fab2(sch_1):jtag_mcp_cpu0_tdi_r" )
			)
			( signal "JTAG_MCP_CPU1_TDI_R"
				( objectStatus "@baseboard_fab2_lib.baseboard_fab2(sch_1):jtag_mcp_cpu1_tdi_r" )
			)
			( signal "JTAG_MCP_MUX_TDI"
				( objectStatus "@baseboard_fab2_lib.baseboard_fab2(sch_1):jtag_mcp_mux_tdi" )
			)
			( signal "JTAG_MCP_MUX_TDO"
				( objectStatus "@baseboard_fab2_lib.baseboard_fab2(sch_1):jtag_mcp_mux_tdo" )
			)
			( signal "JTAG_MCP_TCK_R"
				( objectStatus "@baseboard_fab2_lib.baseboard_fab2(sch_1):jtag_mcp_tck_r" )
			)
			( signal "JTAG_MCP_TMS_R"
				( objectStatus "@baseboard_fab2_lib.baseboard_fab2(sch_1):jtag_mcp_tms_r" )
			)
			( signal "JTAG_MCP_TMS_R1"
				( objectStatus "@baseboard_fab2_lib.baseboard_fab2(sch_1):jtag_mcp_tms_r1" )
			)
			( signal "PWRGD_CPU0_G_R"
				( objectStatus "@baseboard_fab2_lib.baseboard_fab2(sch_1):pwrgd_cpu0_g_r" )
			)
			( signal "TP_JTAG_MCP_IO8_RSVD"
				( objectStatus "@baseboard_fab2_lib.baseboard_fab2(sch_1):tp_jtag_mcp_io8_rsvd" )
			)
			( signal "A_PCH_XCLK_BIASREF"
				( objectStatus "@baseboard_fab2_lib.baseboard_fab2(sch_1):a_pch_xclk_biasref" )
			)
			( signal "CLK_100M_AIRMAX8_PE1_DN"
				( objectStatus "@baseboard_fab2_lib.baseboard_fab2(sch_1):clk_100m_airmax8_pe1_dn" )
			)
			( signal "CLK_100M_AIRMAX8_PE1_DP"
				( objectStatus "@baseboard_fab2_lib.baseboard_fab2(sch_1):clk_100m_airmax8_pe1_dp" )
			)
			( signal "CLK_100M_BMC_PE_DN"
				( objectStatus "@baseboard_fab2_lib.baseboard_fab2(sch_1):clk_100m_bmc_pe_dn" )
			)
			( signal "CLK_100M_BMC_PE_DP"
				( objectStatus "@baseboard_fab2_lib.baseboard_fab2(sch_1):clk_100m_bmc_pe_dp" )
			)
			( signal "CLK_100M_BMC_PE_R_DN"
				( objectStatus "@baseboard_fab2_lib.baseboard_fab2(sch_1):clk_100m_bmc_pe_r_dn" )
			)
			( signal "CLK_100M_BMC_PE_R_DP"
				( objectStatus "@baseboard_fab2_lib.baseboard_fab2(sch_1):clk_100m_bmc_pe_r_dp" )
			)
			( signal "CLK_100M_M2_DN"
				( objectStatus "@baseboard_fab2_lib.baseboard_fab2(sch_1):clk_100m_m2_dn" )
			)
			( signal "CLK_100M_M2_DP"
				( objectStatus "@baseboard_fab2_lib.baseboard_fab2(sch_1):clk_100m_m2_dp" )
			)
			( signal "CLK_100M_MEZZ1_DN"
				( objectStatus "@baseboard_fab2_lib.baseboard_fab2(sch_1):clk_100m_mezz1_dn" )
			)
			( signal "CLK_100M_MEZZ1_DP"
				( objectStatus "@baseboard_fab2_lib.baseboard_fab2(sch_1):clk_100m_mezz1_dp" )
			)
			( signal "CLK_100M_MEZZ2_DN"
				( objectStatus "@baseboard_fab2_lib.baseboard_fab2(sch_1):clk_100m_mezz2_dn" )
			)
			( signal "CLK_100M_MEZZ2_DP"
				( objectStatus "@baseboard_fab2_lib.baseboard_fab2(sch_1):clk_100m_mezz2_dp" )
			)
			( signal "CLK_100M_MEZZ3_DN"
				( objectStatus "@baseboard_fab2_lib.baseboard_fab2(sch_1):clk_100m_mezz3_dn" )
			)
			( signal "CLK_100M_MEZZ3_DP"
				( objectStatus "@baseboard_fab2_lib.baseboard_fab2(sch_1):clk_100m_mezz3_dp" )
			)
			( signal "CLK_100M_MEZZ4_DN"
				( objectStatus "@baseboard_fab2_lib.baseboard_fab2(sch_1):clk_100m_mezz4_dn" )
			)
			( signal "CLK_100M_MEZZ4_DP"
				( objectStatus "@baseboard_fab2_lib.baseboard_fab2(sch_1):clk_100m_mezz4_dp" )
			)
			( signal "CLK_100M_SPRV_DN"
				( objectStatus "@baseboard_fab2_lib.baseboard_fab2(sch_1):clk_100m_sprv_dn" )
			)
			( signal "CLK_100M_SPRV_DP"
				( objectStatus "@baseboard_fab2_lib.baseboard_fab2(sch_1):clk_100m_sprv_dp" )
			)
			( signal "CLK_48M_USB_BMC"
				( objectStatus "@baseboard_fab2_lib.baseboard_fab2(sch_1):clk_48m_usb_bmc" )
			)
			( signal "H_PMSYNC_CLK_24M_R"
				( objectStatus "@baseboard_fab2_lib.baseboard_fab2(sch_1):h_pmsync_clk_24m_r" )
			)
			( signal "TP_CLK_100M_NSSCC0_DN"
				( objectStatus "@baseboard_fab2_lib.baseboard_fab2(sch_1):tp_clk_100m_nsscc0_dn" )
			)
			( signal "TP_CLK_100M_NSSCC0_DP"
				( objectStatus "@baseboard_fab2_lib.baseboard_fab2(sch_1):tp_clk_100m_nsscc0_dp" )
			)
			( signal "TP_CLK_100M_NSSCC1_DN"
				( objectStatus "@baseboard_fab2_lib.baseboard_fab2(sch_1):tp_clk_100m_nsscc1_dn" )
			)
			( signal "TP_CLK_100M_NSSCC1_DP"
				( objectStatus "@baseboard_fab2_lib.baseboard_fab2(sch_1):tp_clk_100m_nsscc1_dp" )
			)
			( signal "TP_CLK_100M_PLAT1_DN"
				( objectStatus "@baseboard_fab2_lib.baseboard_fab2(sch_1):tp_clk_100m_plat1_dn" )
			)
			( signal "TP_CLK_100M_PLAT1_DP"
				( objectStatus "@baseboard_fab2_lib.baseboard_fab2(sch_1):tp_clk_100m_plat1_dp" )
			)
			( signal "TP_CLK_100M_SRC12_DN"
				( objectStatus "@baseboard_fab2_lib.baseboard_fab2(sch_1):tp_clk_100m_src12_dn" )
			)
			( signal "TP_CLK_100M_SRC12_DP"
				( objectStatus "@baseboard_fab2_lib.baseboard_fab2(sch_1):tp_clk_100m_src12_dp" )
			)
			( signal "TP_CLK_100M_SRC13_DN"
				( objectStatus "@baseboard_fab2_lib.baseboard_fab2(sch_1):tp_clk_100m_src13_dn" )
			)
			( signal "TP_CLK_100M_SRC13_DP"
				( objectStatus "@baseboard_fab2_lib.baseboard_fab2(sch_1):tp_clk_100m_src13_dp" )
			)
			( signal "TP_CLK_24M_PMSYNC2"
				( objectStatus "@baseboard_fab2_lib.baseboard_fab2(sch_1):tp_clk_24m_pmsync2" )
			)
			( signal "TP_PCH_RSVD64"
				( objectStatus "@baseboard_fab2_lib.baseboard_fab2(sch_1):tp_pch_rsvd64" )
			)
			( signal "TP_PCH_RSVD65"
				( objectStatus "@baseboard_fab2_lib.baseboard_fab2(sch_1):tp_pch_rsvd65" )
			)
			( signal "XTAL_33K_RTC1"
				( objectStatus "@baseboard_fab2_lib.baseboard_fab2(sch_1):xtal_33k_rtc1" )
			)
			( signal "XTAL_33K_RTC2"
				( objectStatus "@baseboard_fab2_lib.baseboard_fab2(sch_1):xtal_33k_rtc2" )
			)
			( signal "XTAL_PCH_48M_IN"
				( objectStatus "@baseboard_fab2_lib.baseboard_fab2(sch_1):xtal_pch_48m_in" )
			)
			( signal "XTAL_PCH_48M_OUT"
				( objectStatus "@baseboard_fab2_lib.baseboard_fab2(sch_1):xtal_pch_48m_out" )
			)
			( signal "A_USB2_COMP"
				( objectStatus "@baseboard_fab2_lib.baseboard_fab2(sch_1):a_usb2_comp" )
			)
			( signal "A_USB2_VBUS"
				( objectStatus "@baseboard_fab2_lib.baseboard_fab2(sch_1):a_usb2_vbus" )
			)
			( signal "TP_PCH_RSVD55"
				( objectStatus "@baseboard_fab2_lib.baseboard_fab2(sch_1):tp_pch_rsvd55" )
			)
			( signal "TP_USB2_P02_DN"
				( objectStatus "@baseboard_fab2_lib.baseboard_fab2(sch_1):tp_usb2_p02_dn" )
			)
			( signal "TP_USB2_P02_DP"
				( objectStatus "@baseboard_fab2_lib.baseboard_fab2(sch_1):tp_usb2_p02_dp" )
			)
			( signal "TP_USB2_P03_DN"
				( objectStatus "@baseboard_fab2_lib.baseboard_fab2(sch_1):tp_usb2_p03_dn" )
			)
			( signal "TP_USB2_P03_DP"
				( objectStatus "@baseboard_fab2_lib.baseboard_fab2(sch_1):tp_usb2_p03_dp" )
			)
			( signal "TP_USB2_P06_DN"
				( objectStatus "@baseboard_fab2_lib.baseboard_fab2(sch_1):tp_usb2_p06_dn" )
			)
			( signal "TP_USB2_P06_DP"
				( objectStatus "@baseboard_fab2_lib.baseboard_fab2(sch_1):tp_usb2_p06_dp" )
			)
			( signal "TP_USB2_P07_DN"
				( objectStatus "@baseboard_fab2_lib.baseboard_fab2(sch_1):tp_usb2_p07_dn" )
			)
			( signal "TP_USB2_P07_DP"
				( objectStatus "@baseboard_fab2_lib.baseboard_fab2(sch_1):tp_usb2_p07_dp" )
			)
			( signal "TP_USB2_P10_DN"
				( objectStatus "@baseboard_fab2_lib.baseboard_fab2(sch_1):tp_usb2_p10_dn" )
			)
			( signal "TP_USB2_P10_DP"
				( objectStatus "@baseboard_fab2_lib.baseboard_fab2(sch_1):tp_usb2_p10_dp" )
			)
			( signal "TP_USB2_P11_DN"
				( objectStatus "@baseboard_fab2_lib.baseboard_fab2(sch_1):tp_usb2_p11_dn" )
			)
			( signal "TP_USB2_P11_DP"
				( objectStatus "@baseboard_fab2_lib.baseboard_fab2(sch_1):tp_usb2_p11_dp" )
			)
			( signal "TP_USB2_P12_DN"
				( objectStatus "@baseboard_fab2_lib.baseboard_fab2(sch_1):tp_usb2_p12_dn" )
			)
			( signal "TP_USB2_P12_DP"
				( objectStatus "@baseboard_fab2_lib.baseboard_fab2(sch_1):tp_usb2_p12_dp" )
			)
			( signal "TP_USB2_P13_DN"
				( objectStatus "@baseboard_fab2_lib.baseboard_fab2(sch_1):tp_usb2_p13_dn" )
			)
			( signal "TP_USB2_P13_DP"
				( objectStatus "@baseboard_fab2_lib.baseboard_fab2(sch_1):tp_usb2_p13_dp" )
			)
			( signal "TP_USB2_P14_DN"
				( objectStatus "@baseboard_fab2_lib.baseboard_fab2(sch_1):tp_usb2_p14_dn" )
			)
			( signal "TP_USB2_P14_DP"
				( objectStatus "@baseboard_fab2_lib.baseboard_fab2(sch_1):tp_usb2_p14_dp" )
			)
			( signal "TP_USB2_P8_DN"
				( objectStatus "@baseboard_fab2_lib.baseboard_fab2(sch_1):tp_usb2_p8_dn" )
			)
			( signal "TP_USB2_P8_DP"
				( objectStatus "@baseboard_fab2_lib.baseboard_fab2(sch_1):tp_usb2_p8_dp" )
			)
			( signal "TP_USB2_P9_DN"
				( objectStatus "@baseboard_fab2_lib.baseboard_fab2(sch_1):tp_usb2_p9_dn" )
			)
			( signal "TP_USB2_P9_DP"
				( objectStatus "@baseboard_fab2_lib.baseboard_fab2(sch_1):tp_usb2_p9_dp" )
			)
			( signal "TP_USB3_P02_RXN"
				( objectStatus "@baseboard_fab2_lib.baseboard_fab2(sch_1):tp_usb3_p02_rxn" )
			)
			( signal "TP_USB3_P02_RXP"
				( objectStatus "@baseboard_fab2_lib.baseboard_fab2(sch_1):tp_usb3_p02_rxp" )
			)
			( signal "TP_USB3_P02_TXN"
				( objectStatus "@baseboard_fab2_lib.baseboard_fab2(sch_1):tp_usb3_p02_txn" )
			)
			( signal "TP_USB3_P02_TXP"
				( objectStatus "@baseboard_fab2_lib.baseboard_fab2(sch_1):tp_usb3_p02_txp" )
			)
			( signal "TP_USB3_P03_RXN"
				( objectStatus "@baseboard_fab2_lib.baseboard_fab2(sch_1):tp_usb3_p03_rxn" )
			)
			( signal "TP_USB3_P03_RXP"
				( objectStatus "@baseboard_fab2_lib.baseboard_fab2(sch_1):tp_usb3_p03_rxp" )
			)
			( signal "TP_USB3_P03_TXN"
				( objectStatus "@baseboard_fab2_lib.baseboard_fab2(sch_1):tp_usb3_p03_txn" )
			)
			( signal "TP_USB3_P03_TXP"
				( objectStatus "@baseboard_fab2_lib.baseboard_fab2(sch_1):tp_usb3_p03_txp" )
			)
			( signal "TP_USB3_P04_RXN"
				( objectStatus "@baseboard_fab2_lib.baseboard_fab2(sch_1):tp_usb3_p04_rxn" )
			)
			( signal "TP_USB3_P04_RXP"
				( objectStatus "@baseboard_fab2_lib.baseboard_fab2(sch_1):tp_usb3_p04_rxp" )
			)
			( signal "TP_USB3_P04_TXN"
				( objectStatus "@baseboard_fab2_lib.baseboard_fab2(sch_1):tp_usb3_p04_txn" )
			)
			( signal "TP_USB3_P04_TXP"
				( objectStatus "@baseboard_fab2_lib.baseboard_fab2(sch_1):tp_usb3_p04_txp" )
			)
			( signal "TP_USB3_P05_RXN"
				( objectStatus "@baseboard_fab2_lib.baseboard_fab2(sch_1):tp_usb3_p05_rxn" )
			)
			( signal "TP_USB3_P05_RXP"
				( objectStatus "@baseboard_fab2_lib.baseboard_fab2(sch_1):tp_usb3_p05_rxp" )
			)
			( signal "TP_USB3_P05_TXN"
				( objectStatus "@baseboard_fab2_lib.baseboard_fab2(sch_1):tp_usb3_p05_txn" )
			)
			( signal "TP_USB3_P05_TXP"
				( objectStatus "@baseboard_fab2_lib.baseboard_fab2(sch_1):tp_usb3_p05_txp" )
			)
			( signal "TP_USB3_P06_RXN"
				( objectStatus "@baseboard_fab2_lib.baseboard_fab2(sch_1):tp_usb3_p06_rxn" )
			)
			( signal "TP_USB3_P06_RXP"
				( objectStatus "@baseboard_fab2_lib.baseboard_fab2(sch_1):tp_usb3_p06_rxp" )
			)
			( signal "TP_USB3_P06_TXN"
				( objectStatus "@baseboard_fab2_lib.baseboard_fab2(sch_1):tp_usb3_p06_txn" )
			)
			( signal "TP_USB3_P06_TXP"
				( objectStatus "@baseboard_fab2_lib.baseboard_fab2(sch_1):tp_usb3_p06_txp" )
			)
			( signal "USB2_P01_DN"
				( objectStatus "@baseboard_fab2_lib.baseboard_fab2(sch_1):usb2_p01_dn" )
			)
			( signal "USB2_P01_DP"
				( objectStatus "@baseboard_fab2_lib.baseboard_fab2(sch_1):usb2_p01_dp" )
			)
			( signal "USB2_PCH_BMC_P5_DN"
				( objectStatus "@baseboard_fab2_lib.baseboard_fab2(sch_1):usb2_pch_bmc_p5_dn" )
			)
			( signal "USB2_PCH_BMC_P5_DP"
				( objectStatus "@baseboard_fab2_lib.baseboard_fab2(sch_1):usb2_pch_bmc_p5_dp" )
			)
			( signal "USB3_P01_RXN"
				( objectStatus "@baseboard_fab2_lib.baseboard_fab2(sch_1):usb3_p01_rxn" )
			)
			( signal "USB3_P01_RXP"
				( objectStatus "@baseboard_fab2_lib.baseboard_fab2(sch_1):usb3_p01_rxp" )
			)
			( signal "USB3_P01_TXN"
				( objectStatus "@baseboard_fab2_lib.baseboard_fab2(sch_1):usb3_p01_txn" )
			)
			( signal "USB3_P01_TXP"
				( objectStatus "@baseboard_fab2_lib.baseboard_fab2(sch_1):usb3_p01_txp" )
			)
			( signal "USB_PCH_BMC_P4_DN"
				( objectStatus "@baseboard_fab2_lib.baseboard_fab2(sch_1):usb_pch_bmc_p4_dn" )
			)
			( signal "USB_PCH_BMC_P4_DP"
				( objectStatus "@baseboard_fab2_lib.baseboard_fab2(sch_1):usb_pch_bmc_p4_dp" )
			)
			( signal "A_EXTCLKN"
				( objectStatus "@baseboard_fab2_lib.baseboard_fab2(sch_1):a_extclkn" )
			)
			( signal "A_EXTCLKP"
				( objectStatus "@baseboard_fab2_lib.baseboard_fab2(sch_1):a_extclkp" )
			)
			( signal "A_PCIE_RCOMP_N"
				( objectStatus "@baseboard_fab2_lib.baseboard_fab2(sch_1):a_pcie_rcomp_n" )
			)
			( signal "A_PCIE_RCOMP_P"
				( objectStatus "@baseboard_fab2_lib.baseboard_fab2(sch_1):a_pcie_rcomp_p" )
			)
			( signal "A_PCIEUP_RCOMP_N"
				( objectStatus "@baseboard_fab2_lib.baseboard_fab2(sch_1):a_pcieup_rcomp_n" )
			)
			( signal "A_PCIEUP_RCOMP_P"
				( objectStatus "@baseboard_fab2_lib.baseboard_fab2(sch_1):a_pcieup_rcomp_p" )
			)
			( signal "P2E_SSB_BMC_RX_C_DN"
				( objectStatus "@baseboard_fab2_lib.baseboard_fab2(sch_1):p2e_ssb_bmc_rx_c_dn" )
			)
			( signal "P2E_SSB_BMC_RX_C_DP"
				( objectStatus "@baseboard_fab2_lib.baseboard_fab2(sch_1):p2e_ssb_bmc_rx_c_dp" )
			)
			( signal "P2E_SSB_BMC_TX_C_DN"
				( objectStatus "@baseboard_fab2_lib.baseboard_fab2(sch_1):p2e_ssb_bmc_tx_c_dn" )
			)
			( signal "P2E_SSB_BMC_TX_C_DP"
				( objectStatus "@baseboard_fab2_lib.baseboard_fab2(sch_1):p2e_ssb_bmc_tx_c_dp" )
			)
			( signal "P2E_SSB_BMC_TX_DN"
				( objectStatus "@baseboard_fab2_lib.baseboard_fab2(sch_1):p2e_ssb_bmc_tx_dn" )
			)
			( signal "P2E_SSB_BMC_TX_DP"
				( objectStatus "@baseboard_fab2_lib.baseboard_fab2(sch_1):p2e_ssb_bmc_tx_dp" )
			)
			( signal "P3E_PCH_M2_RX_DN<1>"
				( objectStatus "@baseboard_fab2_lib.baseboard_fab2(sch_1):p3e_pch_m2_rx_dn(1)" )
			)
			( signal "P3E_PCH_M2_RX_DN<2>"
				( objectStatus "@baseboard_fab2_lib.baseboard_fab2(sch_1):p3e_pch_m2_rx_dn(2)" )
			)
			( signal "P3E_PCH_M2_RX_DN<3>"
				( objectStatus "@baseboard_fab2_lib.baseboard_fab2(sch_1):p3e_pch_m2_rx_dn(3)" )
			)
			( signal "P3E_PCH_M2_RX_DP<1>"
				( objectStatus "@baseboard_fab2_lib.baseboard_fab2(sch_1):p3e_pch_m2_rx_dp(1)" )
			)
			( signal "P3E_PCH_M2_RX_DP<2>"
				( objectStatus "@baseboard_fab2_lib.baseboard_fab2(sch_1):p3e_pch_m2_rx_dp(2)" )
			)
			( signal "P3E_PCH_M2_RX_DP<3>"
				( objectStatus "@baseboard_fab2_lib.baseboard_fab2(sch_1):p3e_pch_m2_rx_dp(3)" )
			)
			( signal "P3E_PCH_M2_TX_DN<1>"
				( objectStatus "@baseboard_fab2_lib.baseboard_fab2(sch_1):p3e_pch_m2_tx_dn(1)" )
			)
			( signal "P3E_PCH_M2_TX_DN<2>"
				( objectStatus "@baseboard_fab2_lib.baseboard_fab2(sch_1):p3e_pch_m2_tx_dn(2)" )
			)
			( signal "P3E_PCH_M2_TX_DN<3>"
				( objectStatus "@baseboard_fab2_lib.baseboard_fab2(sch_1):p3e_pch_m2_tx_dn(3)" )
			)
			( signal "P3E_PCH_M2_TX_DP<1>"
				( objectStatus "@baseboard_fab2_lib.baseboard_fab2(sch_1):p3e_pch_m2_tx_dp(1)" )
			)
			( signal "P3E_PCH_M2_TX_DP<2>"
				( objectStatus "@baseboard_fab2_lib.baseboard_fab2(sch_1):p3e_pch_m2_tx_dp(2)" )
			)
			( signal "P3E_PCH_M2_TX_DP<3>"
				( objectStatus "@baseboard_fab2_lib.baseboard_fab2(sch_1):p3e_pch_m2_tx_dp(3)" )
			)
			( signal "P3E_PCH_RX_0_DN"
				( objectStatus "@baseboard_fab2_lib.baseboard_fab2(sch_1):p3e_pch_rx_0_dn" )
			)
			( signal "P3E_PCH_RX_0_DP"
				( objectStatus "@baseboard_fab2_lib.baseboard_fab2(sch_1):p3e_pch_rx_0_dp" )
			)
			( signal "P3E_PCH_TX_0_DN"
				( objectStatus "@baseboard_fab2_lib.baseboard_fab2(sch_1):p3e_pch_tx_0_dn" )
			)
			( signal "P3E_PCH_TX_0_DP"
				( objectStatus "@baseboard_fab2_lib.baseboard_fab2(sch_1):p3e_pch_tx_0_dp" )
			)
			( signal "PE_PCH_SPRV_RX_C_DN"
				( objectStatus "@baseboard_fab2_lib.baseboard_fab2(sch_1):pe_pch_sprv_rx_c_dn" )
			)
			( signal "PE_PCH_SPRV_RX_C_DP"
				( objectStatus "@baseboard_fab2_lib.baseboard_fab2(sch_1):pe_pch_sprv_rx_c_dp" )
			)
			( signal "PE_PCH_SPRV_TX_DN"
				( objectStatus "@baseboard_fab2_lib.baseboard_fab2(sch_1):pe_pch_sprv_tx_dn" )
			)
			( signal "PE_PCH_SPRV_TX_DP"
				( objectStatus "@baseboard_fab2_lib.baseboard_fab2(sch_1):pe_pch_sprv_tx_dp" )
			)
			( signal "SATA6G_PCH_PCIE_UP_SATA_RXN<0>"
				( objectStatus "@baseboard_fab2_lib.baseboard_fab2(sch_1):sata6g_pch_pcie_up_sata_rxn(0)" )
			)
			( signal "SATA6G_PCH_PCIE_UP_SATA_RXN<1>"
				( objectStatus "@baseboard_fab2_lib.baseboard_fab2(sch_1):sata6g_pch_pcie_up_sata_rxn(1)" )
			)
			( signal "SATA6G_PCH_PCIE_UP_SATA_RXN<2>"
				( objectStatus "@baseboard_fab2_lib.baseboard_fab2(sch_1):sata6g_pch_pcie_up_sata_rxn(2)" )
			)
			( signal "SATA6G_PCH_PCIE_UP_SATA_RXN<3>"
				( objectStatus "@baseboard_fab2_lib.baseboard_fab2(sch_1):sata6g_pch_pcie_up_sata_rxn(3)" )
			)
			( signal "SATA6G_PCH_PCIE_UP_SATA_RXN<4>"
				( objectStatus "@baseboard_fab2_lib.baseboard_fab2(sch_1):sata6g_pch_pcie_up_sata_rxn(4)" )
			)
			( signal "SATA6G_PCH_PCIE_UP_SATA_RXN<5>"
				( objectStatus "@baseboard_fab2_lib.baseboard_fab2(sch_1):sata6g_pch_pcie_up_sata_rxn(5)" )
			)
			( signal "SATA6G_PCH_PCIE_UP_SATA_RXN<6>"
				( objectStatus "@baseboard_fab2_lib.baseboard_fab2(sch_1):sata6g_pch_pcie_up_sata_rxn(6)" )
			)
			( signal "SATA6G_PCH_PCIE_UP_SATA_RXN<7>"
				( objectStatus "@baseboard_fab2_lib.baseboard_fab2(sch_1):sata6g_pch_pcie_up_sata_rxn(7)" )
			)
			( signal "SATA6G_PCH_PCIE_UP_SATA_RXP<0>"
				( objectStatus "@baseboard_fab2_lib.baseboard_fab2(sch_1):sata6g_pch_pcie_up_sata_rxp(0)" )
			)
			( signal "SATA6G_PCH_PCIE_UP_SATA_RXP<1>"
				( objectStatus "@baseboard_fab2_lib.baseboard_fab2(sch_1):sata6g_pch_pcie_up_sata_rxp(1)" )
			)
			( signal "SATA6G_PCH_PCIE_UP_SATA_RXP<2>"
				( objectStatus "@baseboard_fab2_lib.baseboard_fab2(sch_1):sata6g_pch_pcie_up_sata_rxp(2)" )
			)
			( signal "SATA6G_PCH_PCIE_UP_SATA_RXP<3>"
				( objectStatus "@baseboard_fab2_lib.baseboard_fab2(sch_1):sata6g_pch_pcie_up_sata_rxp(3)" )
			)
			( signal "SATA6G_PCH_PCIE_UP_SATA_RXP<4>"
				( objectStatus "@baseboard_fab2_lib.baseboard_fab2(sch_1):sata6g_pch_pcie_up_sata_rxp(4)" )
			)
			( signal "SATA6G_PCH_PCIE_UP_SATA_RXP<5>"
				( objectStatus "@baseboard_fab2_lib.baseboard_fab2(sch_1):sata6g_pch_pcie_up_sata_rxp(5)" )
			)
			( signal "SATA6G_PCH_PCIE_UP_SATA_RXP<6>"
				( objectStatus "@baseboard_fab2_lib.baseboard_fab2(sch_1):sata6g_pch_pcie_up_sata_rxp(6)" )
			)
			( signal "SATA6G_PCH_PCIE_UP_SATA_RXP<7>"
				( objectStatus "@baseboard_fab2_lib.baseboard_fab2(sch_1):sata6g_pch_pcie_up_sata_rxp(7)" )
			)
			( signal "SATA6G_PCH_PCIE_UP_SATA_TXN<0>"
				( objectStatus "@baseboard_fab2_lib.baseboard_fab2(sch_1):sata6g_pch_pcie_up_sata_txn(0)" )
			)
			( signal "SATA6G_PCH_PCIE_UP_SATA_TXN<1>"
				( objectStatus "@baseboard_fab2_lib.baseboard_fab2(sch_1):sata6g_pch_pcie_up_sata_txn(1)" )
			)
			( signal "SATA6G_PCH_PCIE_UP_SATA_TXN<2>"
				( objectStatus "@baseboard_fab2_lib.baseboard_fab2(sch_1):sata6g_pch_pcie_up_sata_txn(2)" )
			)
			( signal "SATA6G_PCH_PCIE_UP_SATA_TXN<3>"
				( objectStatus "@baseboard_fab2_lib.baseboard_fab2(sch_1):sata6g_pch_pcie_up_sata_txn(3)" )
			)
			( signal "SATA6G_PCH_PCIE_UP_SATA_TXN<4>"
				( objectStatus "@baseboard_fab2_lib.baseboard_fab2(sch_1):sata6g_pch_pcie_up_sata_txn(4)" )
			)
			( signal "SATA6G_PCH_PCIE_UP_SATA_TXN<5>"
				( objectStatus "@baseboard_fab2_lib.baseboard_fab2(sch_1):sata6g_pch_pcie_up_sata_txn(5)" )
			)
			( signal "SATA6G_PCH_PCIE_UP_SATA_TXN<6>"
				( objectStatus "@baseboard_fab2_lib.baseboard_fab2(sch_1):sata6g_pch_pcie_up_sata_txn(6)" )
			)
			( signal "SATA6G_PCH_PCIE_UP_SATA_TXN<7>"
				( objectStatus "@baseboard_fab2_lib.baseboard_fab2(sch_1):sata6g_pch_pcie_up_sata_txn(7)" )
			)
			( signal "SATA6G_PCH_PCIE_UP_SATA_TXP<0>"
				( objectStatus "@baseboard_fab2_lib.baseboard_fab2(sch_1):sata6g_pch_pcie_up_sata_txp(0)" )
			)
			( signal "SATA6G_PCH_PCIE_UP_SATA_TXP<1>"
				( objectStatus "@baseboard_fab2_lib.baseboard_fab2(sch_1):sata6g_pch_pcie_up_sata_txp(1)" )
			)
			( signal "SATA6G_PCH_PCIE_UP_SATA_TXP<2>"
				( objectStatus "@baseboard_fab2_lib.baseboard_fab2(sch_1):sata6g_pch_pcie_up_sata_txp(2)" )
			)
			( signal "SATA6G_PCH_PCIE_UP_SATA_TXP<3>"
				( objectStatus "@baseboard_fab2_lib.baseboard_fab2(sch_1):sata6g_pch_pcie_up_sata_txp(3)" )
			)
			( signal "SATA6G_PCH_PCIE_UP_SATA_TXP<4>"
				( objectStatus "@baseboard_fab2_lib.baseboard_fab2(sch_1):sata6g_pch_pcie_up_sata_txp(4)" )
			)
			( signal "SATA6G_PCH_PCIE_UP_SATA_TXP<5>"
				( objectStatus "@baseboard_fab2_lib.baseboard_fab2(sch_1):sata6g_pch_pcie_up_sata_txp(5)" )
			)
			( signal "SATA6G_PCH_PCIE_UP_SATA_TXP<6>"
				( objectStatus "@baseboard_fab2_lib.baseboard_fab2(sch_1):sata6g_pch_pcie_up_sata_txp(6)" )
			)
			( signal "SATA6G_PCH_PCIE_UP_SATA_TXP<7>"
				( objectStatus "@baseboard_fab2_lib.baseboard_fab2(sch_1):sata6g_pch_pcie_up_sata_txp(7)" )
			)
			( signal "SATA6G_RX_DN<0>"
				( objectStatus "@baseboard_fab2_lib.baseboard_fab2(sch_1):sata6g_rx_dn(0)" )
			)
			( signal "SATA6G_RX_DN<1>"
				( objectStatus "@baseboard_fab2_lib.baseboard_fab2(sch_1):sata6g_rx_dn(1)" )
			)
			( signal "SATA6G_RX_DN<2>"
				( objectStatus "@baseboard_fab2_lib.baseboard_fab2(sch_1):sata6g_rx_dn(2)" )
			)
			( signal "SATA6G_RX_DN<3>"
				( objectStatus "@baseboard_fab2_lib.baseboard_fab2(sch_1):sata6g_rx_dn(3)" )
			)
			( signal "SATA6G_RX_DP<0>"
				( objectStatus "@baseboard_fab2_lib.baseboard_fab2(sch_1):sata6g_rx_dp(0)" )
			)
			( signal "SATA6G_RX_DP<1>"
				( objectStatus "@baseboard_fab2_lib.baseboard_fab2(sch_1):sata6g_rx_dp(1)" )
			)
			( signal "SATA6G_RX_DP<2>"
				( objectStatus "@baseboard_fab2_lib.baseboard_fab2(sch_1):sata6g_rx_dp(2)" )
			)
			( signal "SATA6G_RX_DP<3>"
				( objectStatus "@baseboard_fab2_lib.baseboard_fab2(sch_1):sata6g_rx_dp(3)" )
			)
			( signal "SATA6G_S0_RX_DN"
				( objectStatus "@baseboard_fab2_lib.baseboard_fab2(sch_1):sata6g_s0_rx_dn" )
			)
			( signal "SATA6G_S0_RX_DP"
				( objectStatus "@baseboard_fab2_lib.baseboard_fab2(sch_1):sata6g_s0_rx_dp" )
			)
			( signal "SATA6G_S0_TX_DN"
				( objectStatus "@baseboard_fab2_lib.baseboard_fab2(sch_1):sata6g_s0_tx_dn" )
			)
			( signal "SATA6G_S0_TX_DP"
				( objectStatus "@baseboard_fab2_lib.baseboard_fab2(sch_1):sata6g_s0_tx_dp" )
			)
			( signal "SATA6G_S1_RX_DN"
				( objectStatus "@baseboard_fab2_lib.baseboard_fab2(sch_1):sata6g_s1_rx_dn" )
			)
			( signal "SATA6G_S1_RX_DP"
				( objectStatus "@baseboard_fab2_lib.baseboard_fab2(sch_1):sata6g_s1_rx_dp" )
			)
			( signal "SATA6G_S1_TX_DN"
				( objectStatus "@baseboard_fab2_lib.baseboard_fab2(sch_1):sata6g_s1_tx_dn" )
			)
			( signal "SATA6G_S1_TX_DP"
				( objectStatus "@baseboard_fab2_lib.baseboard_fab2(sch_1):sata6g_s1_tx_dp" )
			)
			( signal "SATA6G_TX_DN<0>"
				( objectStatus "@baseboard_fab2_lib.baseboard_fab2(sch_1):sata6g_tx_dn(0)" )
			)
			( signal "SATA6G_TX_DN<1>"
				( objectStatus "@baseboard_fab2_lib.baseboard_fab2(sch_1):sata6g_tx_dn(1)" )
			)
			( signal "SATA6G_TX_DN<2>"
				( objectStatus "@baseboard_fab2_lib.baseboard_fab2(sch_1):sata6g_tx_dn(2)" )
			)
			( signal "SATA6G_TX_DN<3>"
				( objectStatus "@baseboard_fab2_lib.baseboard_fab2(sch_1):sata6g_tx_dn(3)" )
			)
			( signal "SATA6G_TX_DP<0>"
				( objectStatus "@baseboard_fab2_lib.baseboard_fab2(sch_1):sata6g_tx_dp(0)" )
			)
			( signal "SATA6G_TX_DP<1>"
				( objectStatus "@baseboard_fab2_lib.baseboard_fab2(sch_1):sata6g_tx_dp(1)" )
			)
			( signal "SATA6G_TX_DP<2>"
				( objectStatus "@baseboard_fab2_lib.baseboard_fab2(sch_1):sata6g_tx_dp(2)" )
			)
			( signal "SATA6G_TX_DP<3>"
				( objectStatus "@baseboard_fab2_lib.baseboard_fab2(sch_1):sata6g_tx_dp(3)" )
			)
			( signal "TP_PCH_RSVD47"
				( objectStatus "@baseboard_fab2_lib.baseboard_fab2(sch_1):tp_pch_rsvd47" )
			)
			( signal "TP_PCH_RSVD48"
				( objectStatus "@baseboard_fab2_lib.baseboard_fab2(sch_1):tp_pch_rsvd48" )
			)
			( signal "TP_PCH_RSVD49"
				( objectStatus "@baseboard_fab2_lib.baseboard_fab2(sch_1):tp_pch_rsvd49" )
			)
			( signal "TP_PCH_RSVD50"
				( objectStatus "@baseboard_fab2_lib.baseboard_fab2(sch_1):tp_pch_rsvd50" )
			)
			( signal "TP_PCH_RSVD51"
				( objectStatus "@baseboard_fab2_lib.baseboard_fab2(sch_1):tp_pch_rsvd51" )
			)
			( signal "TP_PCH_RSVD52"
				( objectStatus "@baseboard_fab2_lib.baseboard_fab2(sch_1):tp_pch_rsvd52" )
			)
			( signal "DMI_CPU0_PCH_RX_DN<0>"
				( objectStatus "@baseboard_fab2_lib.baseboard_fab2(sch_1):dmi_cpu0_pch_rx_dn(0)" )
			)
			( signal "DMI_CPU0_PCH_RX_DN<1>"
				( objectStatus "@baseboard_fab2_lib.baseboard_fab2(sch_1):dmi_cpu0_pch_rx_dn(1)" )
			)
			( signal "DMI_CPU0_PCH_RX_DN<2>"
				( objectStatus "@baseboard_fab2_lib.baseboard_fab2(sch_1):dmi_cpu0_pch_rx_dn(2)" )
			)
			( signal "DMI_CPU0_PCH_RX_DN<3>"
				( objectStatus "@baseboard_fab2_lib.baseboard_fab2(sch_1):dmi_cpu0_pch_rx_dn(3)" )
			)
			( signal "DMI_CPU0_PCH_RX_DP<0>"
				( objectStatus "@baseboard_fab2_lib.baseboard_fab2(sch_1):dmi_cpu0_pch_rx_dp(0)" )
			)
			( signal "DMI_CPU0_PCH_RX_DP<1>"
				( objectStatus "@baseboard_fab2_lib.baseboard_fab2(sch_1):dmi_cpu0_pch_rx_dp(1)" )
			)
			( signal "DMI_CPU0_PCH_RX_DP<2>"
				( objectStatus "@baseboard_fab2_lib.baseboard_fab2(sch_1):dmi_cpu0_pch_rx_dp(2)" )
			)
			( signal "DMI_CPU0_PCH_RX_DP<3>"
				( objectStatus "@baseboard_fab2_lib.baseboard_fab2(sch_1):dmi_cpu0_pch_rx_dp(3)" )
			)
			( signal "DMI_CPU0_PCH_TX_C_DN<0>"
				( objectStatus "@baseboard_fab2_lib.baseboard_fab2(sch_1):dmi_cpu0_pch_tx_c_dn(0)" )
			)
			( signal "DMI_CPU0_PCH_TX_C_DN<1>"
				( objectStatus "@baseboard_fab2_lib.baseboard_fab2(sch_1):dmi_cpu0_pch_tx_c_dn(1)" )
			)
			( signal "DMI_CPU0_PCH_TX_C_DN<2>"
				( objectStatus "@baseboard_fab2_lib.baseboard_fab2(sch_1):dmi_cpu0_pch_tx_c_dn(2)" )
			)
			( signal "DMI_CPU0_PCH_TX_C_DN<3>"
				( objectStatus "@baseboard_fab2_lib.baseboard_fab2(sch_1):dmi_cpu0_pch_tx_c_dn(3)" )
			)
			( signal "DMI_CPU0_PCH_TX_C_DP<0>"
				( objectStatus "@baseboard_fab2_lib.baseboard_fab2(sch_1):dmi_cpu0_pch_tx_c_dp(0)" )
			)
			( signal "DMI_CPU0_PCH_TX_C_DP<1>"
				( objectStatus "@baseboard_fab2_lib.baseboard_fab2(sch_1):dmi_cpu0_pch_tx_c_dp(1)" )
			)
			( signal "DMI_CPU0_PCH_TX_C_DP<2>"
				( objectStatus "@baseboard_fab2_lib.baseboard_fab2(sch_1):dmi_cpu0_pch_tx_c_dp(2)" )
			)
			( signal "DMI_CPU0_PCH_TX_C_DP<3>"
				( objectStatus "@baseboard_fab2_lib.baseboard_fab2(sch_1):dmi_cpu0_pch_tx_c_dp(3)" )
			)
			( signal "A_KR0_RBIAS"
				( objectStatus "@baseboard_fab2_lib.baseboard_fab2(sch_1):a_kr0_rbias" )
			)
			( signal "A_KR1_RBIAS"
				( objectStatus "@baseboard_fab2_lib.baseboard_fab2(sch_1):a_kr1_rbias" )
			)
			( signal "FM_10GBE_LOM_DISABLE_N"
				( objectStatus "@baseboard_fab2_lib.baseboard_fab2(sch_1):fm_10gbe_lom_disable_n" )
			)
			( signal "FM_1GB_LOM_DISABLE_N"
				( objectStatus "@baseboard_fab2_lib.baseboard_fab2(sch_1):fm_1gb_lom_disable_n" )
			)
			( signal "FM_BATTERY_SENSE_EN"
				( objectStatus "@baseboard_fab2_lib.baseboard_fab2(sch_1):fm_battery_sense_en" )
			)
			( signal "FM_BMC_CPLD_MP_RST_N"
				( objectStatus "@baseboard_fab2_lib.baseboard_fab2(sch_1):fm_bmc_cpld_mp_rst_n" )
			)
			( signal "FM_GBE_LOM_DISABLE_N"
				( objectStatus "@baseboard_fab2_lib.baseboard_fab2(sch_1):fm_gbe_lom_disable_n" )
			)
			( signal "FM_PCH_LVC1_THERMTRIP_N"
				( objectStatus "@baseboard_fab2_lib.baseboard_fab2(sch_1):fm_pch_lvc1_thermtrip_n" )
			)
			( signal "FM_PCH_PWRBTN_N"
				( objectStatus "@baseboard_fab2_lib.baseboard_fab2(sch_1):fm_pch_pwrbtn_n" )
			)
			( signal "FM_SLP_SUS_N"
				( objectStatus "@baseboard_fab2_lib.baseboard_fab2(sch_1):fm_slp_sus_n" )
			)
			( signal "FM_SLPS3_N"
				( objectStatus "@baseboard_fab2_lib.baseboard_fab2(sch_1):fm_slps3_n" )
			)
			( signal "FM_SLPS4_N"
				( objectStatus "@baseboard_fab2_lib.baseboard_fab2(sch_1):fm_slps4_n" )
			)
			( signal "H_PM_SYNC1_GTL_R"
				( objectStatus "@baseboard_fab2_lib.baseboard_fab2(sch_1):h_pm_sync1_gtl_r" )
			)
			( signal "IRQ_LVC3_WAKE_N"
				( objectStatus "@baseboard_fab2_lib.baseboard_fab2(sch_1):irq_lvc3_wake_n" )
			)
			( signal "IRQ_SML1_PMBUS_ALERT_N"
				( objectStatus "@baseboard_fab2_lib.baseboard_fab2(sch_1):irq_sml1_pmbus_alert_n" )
			)
			( signal "KR_P0_OCP_RX_C_DN"
				( objectStatus "@baseboard_fab2_lib.baseboard_fab2(sch_1):kr_p0_ocp_rx_c_dn" )
			)
			( signal "KR_P0_OCP_RX_C_DP"
				( objectStatus "@baseboard_fab2_lib.baseboard_fab2(sch_1):kr_p0_ocp_rx_c_dp" )
			)
			( signal "KR_P0_OCP_TX_DN"
				( objectStatus "@baseboard_fab2_lib.baseboard_fab2(sch_1):kr_p0_ocp_tx_dn" )
			)
			( signal "KR_P0_OCP_TX_DP"
				( objectStatus "@baseboard_fab2_lib.baseboard_fab2(sch_1):kr_p0_ocp_tx_dp" )
			)
			( signal "KR_P1_OCP_RX_C_DN"
				( objectStatus "@baseboard_fab2_lib.baseboard_fab2(sch_1):kr_p1_ocp_rx_c_dn" )
			)
			( signal "KR_P1_OCP_RX_C_DP"
				( objectStatus "@baseboard_fab2_lib.baseboard_fab2(sch_1):kr_p1_ocp_rx_c_dp" )
			)
			( signal "KR_P1_OCP_TX_DN"
				( objectStatus "@baseboard_fab2_lib.baseboard_fab2(sch_1):kr_p1_ocp_tx_dn" )
			)
			( signal "KR_P1_OCP_TX_DP"
				( objectStatus "@baseboard_fab2_lib.baseboard_fab2(sch_1):kr_p1_ocp_tx_dp" )
			)
			( signal "KR_P2_OCP_RX_C_DN"
				( objectStatus "@baseboard_fab2_lib.baseboard_fab2(sch_1):kr_p2_ocp_rx_c_dn" )
			)
			( signal "KR_P2_OCP_RX_C_DP"
				( objectStatus "@baseboard_fab2_lib.baseboard_fab2(sch_1):kr_p2_ocp_rx_c_dp" )
			)
			( signal "KR_P2_OCP_TX_DN"
				( objectStatus "@baseboard_fab2_lib.baseboard_fab2(sch_1):kr_p2_ocp_tx_dn" )
			)
			( signal "KR_P2_OCP_TX_DP"
				( objectStatus "@baseboard_fab2_lib.baseboard_fab2(sch_1):kr_p2_ocp_tx_dp" )
			)
			( signal "KR_P3_OCP_RX_C_DN"
				( objectStatus "@baseboard_fab2_lib.baseboard_fab2(sch_1):kr_p3_ocp_rx_c_dn" )
			)
			( signal "KR_P3_OCP_RX_C_DP"
				( objectStatus "@baseboard_fab2_lib.baseboard_fab2(sch_1):kr_p3_ocp_rx_c_dp" )
			)
			( signal "KR_P3_OCP_TX_DN"
				( objectStatus "@baseboard_fab2_lib.baseboard_fab2(sch_1):kr_p3_ocp_tx_dn" )
			)
			( signal "KR_P3_OCP_TX_DP"
				( objectStatus "@baseboard_fab2_lib.baseboard_fab2(sch_1):kr_p3_ocp_tx_dp" )
			)
			( signal "P1V05_PCH_STBY_KR_PLL"
				( attribute "VOLTAGE" "1.05V"
					( Units "uVoltage" "V" 1.000000)
					( Status sAliasFlattened )
					( Origin gFrontEnd )
				)
				( objectStatus "@baseboard_fab2_lib.baseboard_fab2(sch_1):p1v05_pch_stby_kr_pll" )
			)
			( signal "PECI_PCH"
				( objectStatus "@baseboard_fab2_lib.baseboard_fab2(sch_1):peci_pch" )
			)
			( signal "PWRGD_DSW_PWROK"
				( objectStatus "@baseboard_fab2_lib.baseboard_fab2(sch_1):pwrgd_dsw_pwrok" )
			)
			( signal "PWRGD_PCH_PWROK"
				( objectStatus "@baseboard_fab2_lib.baseboard_fab2(sch_1):pwrgd_pch_pwrok" )
			)
			( signal "PWRGD_SYS_PWROK"
				( objectStatus "@baseboard_fab2_lib.baseboard_fab2(sch_1):pwrgd_sys_pwrok" )
			)
			( signal "RST_BMC_SRST_N"
				( objectStatus "@baseboard_fab2_lib.baseboard_fab2(sch_1):rst_bmc_srst_n" )
			)
			( signal "RST_BMC_SRST_R_N"
				( objectStatus "@baseboard_fab2_lib.baseboard_fab2(sch_1):rst_bmc_srst_r_n" )
			)
			( signal "RST_BMC_SYSRST_BTN_OUT_B_N"
				( objectStatus "@baseboard_fab2_lib.baseboard_fab2(sch_1):rst_bmc_sysrst_btn_out_b_n" )
			)
			( signal "RST_PCH_SYSRST_BTN_OUT_N"
				( objectStatus "@baseboard_fab2_lib.baseboard_fab2(sch_1):rst_pch_sysrst_btn_out_n" )
			)
			( signal "TP_10GBE_KR0_MON_DN"
				( objectStatus "@baseboard_fab2_lib.baseboard_fab2(sch_1):tp_10gbe_kr0_mon_dn" )
			)
			( signal "TP_10GBE_KR0_MON_DP"
				( objectStatus "@baseboard_fab2_lib.baseboard_fab2(sch_1):tp_10gbe_kr0_mon_dp" )
			)
			( signal "TP_10GBE_KR1_MON_DN"
				( objectStatus "@baseboard_fab2_lib.baseboard_fab2(sch_1):tp_10gbe_kr1_mon_dn" )
			)
			( signal "TP_10GBE_KR1_MON_DP"
				( objectStatus "@baseboard_fab2_lib.baseboard_fab2(sch_1):tp_10gbe_kr1_mon_dp" )
			)
			( signal "TP_CPU_PCH_TRIGGER_IN"
				( objectStatus "@baseboard_fab2_lib.baseboard_fab2(sch_1):tp_cpu_pch_trigger_in" )
			)
			( signal "TP_CPU_PCH_TRIGGER_OUT"
				( objectStatus "@baseboard_fab2_lib.baseboard_fab2(sch_1):tp_cpu_pch_trigger_out" )
			)
			( signal "TP_PCH_RSVD32"
				( objectStatus "@baseboard_fab2_lib.baseboard_fab2(sch_1):tp_pch_rsvd32" )
			)
			( signal "TP_PCH_RSVD33"
				( objectStatus "@baseboard_fab2_lib.baseboard_fab2(sch_1):tp_pch_rsvd33" )
			)
			( signal "TP_PCH_RSVD34"
				( objectStatus "@baseboard_fab2_lib.baseboard_fab2(sch_1):tp_pch_rsvd34" )
			)
			( signal "TP_PCH_RSVD35"
				( objectStatus "@baseboard_fab2_lib.baseboard_fab2(sch_1):tp_pch_rsvd35" )
			)
			( signal "TP_PCH_RSVD36"
				( objectStatus "@baseboard_fab2_lib.baseboard_fab2(sch_1):tp_pch_rsvd36" )
			)
			( signal "TP_PCH_RSVD37"
				( objectStatus "@baseboard_fab2_lib.baseboard_fab2(sch_1):tp_pch_rsvd37" )
			)
			( signal "TP_PCH_RSVD38"
				( objectStatus "@baseboard_fab2_lib.baseboard_fab2(sch_1):tp_pch_rsvd38" )
			)
			( signal "TP_PCH_RSVD41"
				( objectStatus "@baseboard_fab2_lib.baseboard_fab2(sch_1):tp_pch_rsvd41" )
			)
			( signal "TP_PCH_RSVD42"
				( objectStatus "@baseboard_fab2_lib.baseboard_fab2(sch_1):tp_pch_rsvd42" )
			)
			( signal "TP_PCH_RSVD45"
				( objectStatus "@baseboard_fab2_lib.baseboard_fab2(sch_1):tp_pch_rsvd45" )
			)
			( signal "TP_PCH_RSVD53"
				( objectStatus "@baseboard_fab2_lib.baseboard_fab2(sch_1):tp_pch_rsvd53" )
			)
			( signal "TP_PCH_RSVD54"
				( objectStatus "@baseboard_fab2_lib.baseboard_fab2(sch_1):tp_pch_rsvd54" )
			)
			( signal "TP_PLTRST_CPU_N"
				( objectStatus "@baseboard_fab2_lib.baseboard_fab2(sch_1):tp_pltrst_cpu_n" )
			)
			( signal "TP_PM_SYNC_GTL"
				( objectStatus "@baseboard_fab2_lib.baseboard_fab2(sch_1):tp_pm_sync_gtl" )
			)
			( signal "TP_SLP_LAN_N"
				( objectStatus "@baseboard_fab2_lib.baseboard_fab2(sch_1):tp_slp_lan_n" )
			)
			( signal "XDP_PCH_PWR_DEBUG_N"
				( objectStatus "@baseboard_fab2_lib.baseboard_fab2(sch_1):xdp_pch_pwr_debug_n" )
			)
			( signal "XTAL_KR_25M_IN"
				( objectStatus "@baseboard_fab2_lib.baseboard_fab2(sch_1):xtal_kr_25m_in" )
			)
			( signal "XTAL_KR_25M_OUT"
				( objectStatus "@baseboard_fab2_lib.baseboard_fab2(sch_1):xtal_kr_25m_out" )
			)
			( signal "CLK_24M_BMC_LPC"
				( objectStatus "@baseboard_fab2_lib.baseboard_fab2(sch_1):clk_24m_bmc_lpc" )
			)
			( signal "CLK_24M_BMC_LPC_R"
				( objectStatus "@baseboard_fab2_lib.baseboard_fab2(sch_1):clk_24m_bmc_lpc_r" )
			)
			( signal "FM_ADR_MODE_SEL"
				( objectStatus "@baseboard_fab2_lib.baseboard_fab2(sch_1):fm_adr_mode_sel" )
			)
			( signal "FM_ADR_MODE_SEL_R"
				( objectStatus "@baseboard_fab2_lib.baseboard_fab2(sch_1):fm_adr_mode_sel_r" )
			)
			( signal "FM_BB_BMC_MP_GPIO"
				( objectStatus "@baseboard_fab2_lib.baseboard_fab2(sch_1):fm_bb_bmc_mp_gpio" )
			)
			( signal "FM_BIOS_POST_CMPLT_N"
				( objectStatus "@baseboard_fab2_lib.baseboard_fab2(sch_1):fm_bios_post_cmplt_n" )
			)
			( signal "FM_BIOS_PREFRB2_GOOD"
				( objectStatus "@baseboard_fab2_lib.baseboard_fab2(sch_1):fm_bios_prefrb2_good" )
			)
			( signal "FM_BIOS_TOP_SWAP_SPKR"
				( objectStatus "@baseboard_fab2_lib.baseboard_fab2(sch_1):fm_bios_top_swap_spkr" )
			)
			( signal "FM_BMC_CPLD_GPO"
				( objectStatus "@baseboard_fab2_lib.baseboard_fab2(sch_1):fm_bmc_cpld_gpo" )
			)
			( signal "FM_BMC_ENABLE_N"
				( objectStatus "@baseboard_fab2_lib.baseboard_fab2(sch_1):fm_bmc_enable_n" )
			)
			( signal "FM_BMC_FAULT_LED_N"
				( objectStatus "@baseboard_fab2_lib.baseboard_fab2(sch_1):fm_bmc_fault_led_n" )
			)
			( signal "FM_BMC_HEARTBEAT_N"
				( objectStatus "@baseboard_fab2_lib.baseboard_fab2(sch_1):fm_bmc_heartbeat_n" )
			)
			( signal "FM_BMC_READY_N"
				( objectStatus "@baseboard_fab2_lib.baseboard_fab2(sch_1):fm_bmc_ready_n" )
			)
			( signal "FM_BOARD_REV_ID0"
				( objectStatus "@baseboard_fab2_lib.baseboard_fab2(sch_1):fm_board_rev_id0" )
			)
			( signal "FM_BOARD_REV_ID1"
				( objectStatus "@baseboard_fab2_lib.baseboard_fab2(sch_1):fm_board_rev_id1" )
			)
			( signal "FM_BOARD_REV_ID2"
				( objectStatus "@baseboard_fab2_lib.baseboard_fab2(sch_1):fm_board_rev_id2" )
			)
			( signal "FM_CPLD_BMC_PWRDN_N"
				( objectStatus "@baseboard_fab2_lib.baseboard_fab2(sch_1):fm_cpld_bmc_pwrdn_n" )
			)
			( signal "FM_CPU0_THERMTRIP_LATCH_LVT3_N"
				( objectStatus "@baseboard_fab2_lib.baseboard_fab2(sch_1):fm_cpu0_thermtrip_latch_lvt3_n" )
			)
			( signal "FM_CPU_BMC_INIT"
				( objectStatus "@baseboard_fab2_lib.baseboard_fab2(sch_1):fm_cpu_bmc_init" )
			)
			( signal "FM_CPU_CATERR_DLY_LVT3_N"
				( objectStatus "@baseboard_fab2_lib.baseboard_fab2(sch_1):fm_cpu_caterr_dly_lvt3_n" )
			)
			( signal "FM_CPU_CATERR_DLY_LVT3_R_N"
				( objectStatus "@baseboard_fab2_lib.baseboard_fab2(sch_1):fm_cpu_caterr_dly_lvt3_r_n" )
			)
			( signal "FM_FAST_PROCHOT_EN_N"
				( objectStatus "@baseboard_fab2_lib.baseboard_fab2(sch_1):fm_fast_prochot_en_n" )
			)
			( signal "FM_GLOBAL_RST_WARN_N"
				( objectStatus "@baseboard_fab2_lib.baseboard_fab2(sch_1):fm_global_rst_warn_n" )
			)
			( signal "FM_MB_SLOT_ID0"
				( objectStatus "@baseboard_fab2_lib.baseboard_fab2(sch_1):fm_mb_slot_id0" )
			)
			( signal "FM_MB_SLOT_ID1"
				( objectStatus "@baseboard_fab2_lib.baseboard_fab2(sch_1):fm_mb_slot_id1" )
			)
			( signal "FM_MB_SLOT_ID2"
				( objectStatus "@baseboard_fab2_lib.baseboard_fab2(sch_1):fm_mb_slot_id2" )
			)
			( signal "FM_ME_RECOVER_N"
				( objectStatus "@baseboard_fab2_lib.baseboard_fab2(sch_1):fm_me_recover_n" )
			)
			( signal "FM_OCP_MEZZA_PRES_N"
				( objectStatus "@baseboard_fab2_lib.baseboard_fab2(sch_1):fm_ocp_mezza_pres_n" )
			)
			( signal "FM_PASSWORD_CLEAR_N"
				( objectStatus "@baseboard_fab2_lib.baseboard_fab2(sch_1):fm_password_clear_n" )
			)
			( signal "FM_PCH_BMC_THERMTRIP_EXI_STRAP_"
				( objectStatus "@baseboard_fab2_lib.baseboard_fab2(sch_1):fm_pch_bmc_thermtrip_exi_strap_n" )
			)
			( signal "FM_PCH_PLD_DATA"
				( objectStatus "@baseboard_fab2_lib.baseboard_fab2(sch_1):fm_pch_pld_data" )
			)
			( signal "FM_PCH_PLD_DATA_R"
				( objectStatus "@baseboard_fab2_lib.baseboard_fab2(sch_1):fm_pch_pld_data_r" )
			)
			( signal "FM_PCH_PWRBTN_OUT_N"
				( objectStatus "@baseboard_fab2_lib.baseboard_fab2(sch_1):fm_pch_pwrbtn_out_n" )
			)
			( signal "FM_PCH_SATA_RAID_KEY"
				( objectStatus "@baseboard_fab2_lib.baseboard_fab2(sch_1):fm_pch_sata_raid_key" )
			)
			( signal "FM_PMBUS_ALERT_BUF_EN_N"
				( objectStatus "@baseboard_fab2_lib.baseboard_fab2(sch_1):fm_pmbus_alert_buf_en_n" )
			)
			( signal "FM_POST_CARD_PRES_BMC_N"
				( objectStatus "@baseboard_fab2_lib.baseboard_fab2(sch_1):fm_post_card_pres_bmc_n" )
			)
			( signal "FM_PWR_BTN_N"
				( objectStatus "@baseboard_fab2_lib.baseboard_fab2(sch_1):fm_pwr_btn_n" )
			)
			( signal "FM_PWR_LED"
				( objectStatus "@baseboard_fab2_lib.baseboard_fab2(sch_1):fm_pwr_led" )
			)
			( signal "FM_PWR_LED_A"
				( objectStatus "@baseboard_fab2_lib.baseboard_fab2(sch_1):fm_pwr_led_a" )
			)
			( signal "FM_PWR_LED_K"
				( objectStatus "@baseboard_fab2_lib.baseboard_fab2(sch_1):fm_pwr_led_k" )
			)
			( signal "FM_PWR_LED_N"
				( objectStatus "@baseboard_fab2_lib.baseboard_fab2(sch_1):fm_pwr_led_n" )
			)
			( signal "FM_QAT_EN_N"
				( objectStatus "@baseboard_fab2_lib.baseboard_fab2(sch_1):fm_qat_en_n" )
			)
			( signal "FM_SLT_CFG2_R"
				( objectStatus "@baseboard_fab2_lib.baseboard_fab2(sch_1):fm_slt_cfg2_r" )
			)
			( signal "FM_TPM_PRES_N"
				( objectStatus "@baseboard_fab2_lib.baseboard_fab2(sch_1):fm_tpm_pres_n" )
			)
			( signal "FM_UART_ALERT_N"
				( objectStatus "@baseboard_fab2_lib.baseboard_fab2(sch_1):fm_uart_alert_n" )
			)
			( signal "FM_UART_PRES_N"
				( objectStatus "@baseboard_fab2_lib.baseboard_fab2(sch_1):fm_uart_pres_n" )
			)
			( signal "FM_USB_P0_EN_BOOT_BIOS_STRAP_N"
				( objectStatus "@baseboard_fab2_lib.baseboard_fab2(sch_1):fm_usb_p0_en_boot_bios_strap_n" )
			)
			( signal "FM_UV_ADR_TRIGGER_EN"
				( objectStatus "@baseboard_fab2_lib.baseboard_fab2(sch_1):fm_uv_adr_trigger_en" )
			)
			( signal "FM_XRC_PRESENT_N"
				( objectStatus "@baseboard_fab2_lib.baseboard_fab2(sch_1):fm_xrc_present_n" )
			)
			( signal "FM_XRC_READY_N"
				( objectStatus "@baseboard_fab2_lib.baseboard_fab2(sch_1):fm_xrc_ready_n" )
			)
			( signal "FP_NMI_BTN_N"
				( objectStatus "@baseboard_fab2_lib.baseboard_fab2(sch_1):fp_nmi_btn_n" )
			)
			( signal "H_CPU0_FAST_WAKE_LVT3_N"
				( objectStatus "@baseboard_fab2_lib.baseboard_fab2(sch_1):h_cpu0_fast_wake_lvt3_n" )
			)
			( signal "IRQ_BMC_PCH_NMI_STBY_R_N"
				( objectStatus "@baseboard_fab2_lib.baseboard_fab2(sch_1):irq_bmc_pch_nmi_stby_r_n" )
			)
			( signal "IRQ_BMC_PCH_SCI_LPC_N"
				( objectStatus "@baseboard_fab2_lib.baseboard_fab2(sch_1):irq_bmc_pch_sci_lpc_n" )
			)
			( signal "IRQ_BMC_PCH_SMI_LPC_N"
				( objectStatus "@baseboard_fab2_lib.baseboard_fab2(sch_1):irq_bmc_pch_smi_lpc_n" )
			)
			( signal "IRQ_FORCE_NM_THROTTLE_N"
				( objectStatus "@baseboard_fab2_lib.baseboard_fab2(sch_1):irq_force_nm_throttle_n" )
			)
			( signal "IRQ_HSC_FAULT_N"
				( objectStatus "@baseboard_fab2_lib.baseboard_fab2(sch_1):irq_hsc_fault_n" )
			)
			( signal "IRQ_LOM_ALERT_N"
				( objectStatus "@baseboard_fab2_lib.baseboard_fab2(sch_1):irq_lom_alert_n" )
			)
			( signal "IRQ_LPC_SERIRQ_N"
				( objectStatus "@baseboard_fab2_lib.baseboard_fab2(sch_1):irq_lpc_serirq_n" )
			)
			( signal "IRQ_MEZZ_LAN_ALERT_N"
				( objectStatus "@baseboard_fab2_lib.baseboard_fab2(sch_1):irq_mezz_lan_alert_n" )
			)
			( signal "IRQ_PCH_NIC_ALERT_N"
				( objectStatus "@baseboard_fab2_lib.baseboard_fab2(sch_1):irq_pch_nic_alert_n" )
			)
			( signal "IRQ_PIRQA_SPI_TPM_N"
				( objectStatus "@baseboard_fab2_lib.baseboard_fab2(sch_1):irq_pirqa_spi_tpm_n" )
			)
			( signal "IRQ_SML0_ALERT_N"
				( objectStatus "@baseboard_fab2_lib.baseboard_fab2(sch_1):irq_sml0_alert_n" )
			)
			( signal "IRQ_VM_INT_N"
				( objectStatus "@baseboard_fab2_lib.baseboard_fab2(sch_1):irq_vm_int_n" )
			)
			( signal "LPC_LAD0_IO0"
				( objectStatus "@baseboard_fab2_lib.baseboard_fab2(sch_1):lpc_lad0_io0" )
			)
			( signal "LPC_LAD1_IO1"
				( objectStatus "@baseboard_fab2_lib.baseboard_fab2(sch_1):lpc_lad1_io1" )
			)
			( signal "LPC_LAD2_IO2"
				( objectStatus "@baseboard_fab2_lib.baseboard_fab2(sch_1):lpc_lad2_io2" )
			)
			( signal "LPC_LAD3_IO3"
				( objectStatus "@baseboard_fab2_lib.baseboard_fab2(sch_1):lpc_lad3_io3" )
			)
			( signal "LPC_LFRAME_N_CS0_N"
				( objectStatus "@baseboard_fab2_lib.baseboard_fab2(sch_1):lpc_lframe_n_cs0_n" )
			)
			( signal "PU_FM_RCIN_N"
				( objectStatus "@baseboard_fab2_lib.baseboard_fab2(sch_1):pu_fm_rcin_n" )
			)
			( signal "PU_IRQ_PCH_SCI_WHEA_N"
				( objectStatus "@baseboard_fab2_lib.baseboard_fab2(sch_1):pu_irq_pch_sci_whea_n" )
			)
			( signal "PU_IRQ_VRALERT_N"
				( objectStatus "@baseboard_fab2_lib.baseboard_fab2(sch_1):pu_irq_vralert_n" )
			)
			( signal "PU_LPC_CLKRUN_N"
				( objectStatus "@baseboard_fab2_lib.baseboard_fab2(sch_1):pu_lpc_clkrun_n" )
			)
			( signal "PU_LPC_PME_N"
				( objectStatus "@baseboard_fab2_lib.baseboard_fab2(sch_1):pu_lpc_pme_n" )
			)
			( signal "PU_PCH_TLS_ENABLE_STRAP"
				( objectStatus "@baseboard_fab2_lib.baseboard_fab2(sch_1):pu_pch_tls_enable_strap" )
			)
			( signal "RST_PLTRST_N"
				( objectStatus "@baseboard_fab2_lib.baseboard_fab2(sch_1):rst_pltrst_n" )
			)
			( signal "RST_SYSTEM_BTN_N"
				( objectStatus "@baseboard_fab2_lib.baseboard_fab2(sch_1):rst_system_btn_n" )
			)
			( signal "SGPIO_PCH_SSATA_DOUT0"
				( objectStatus "@baseboard_fab2_lib.baseboard_fab2(sch_1):sgpio_pch_ssata_dout0" )
			)
			( signal "SMB_HOST_STBY_LVC3_SCL_R1"
				( objectStatus "@baseboard_fab2_lib.baseboard_fab2(sch_1):smb_host_stby_lvc3_scl_r1" )
			)
			( signal "SMB_HOST_STBY_LVC3_SDA_R1"
				( objectStatus "@baseboard_fab2_lib.baseboard_fab2(sch_1):smb_host_stby_lvc3_sda_r1" )
			)
			( signal "SMB_PMBUS_BMC_STBY_LVC3_SCL_R1"
				( objectStatus "@baseboard_fab2_lib.baseboard_fab2(sch_1):smb_pmbus_bmc_stby_lvc3_scl_r1" )
			)
			( signal "SMB_PMBUS_BMC_STBY_LVC3_SDA_R1"
				( objectStatus "@baseboard_fab2_lib.baseboard_fab2(sch_1):smb_pmbus_bmc_stby_lvc3_sda_r1" )
			)
			( signal "SMB_SLOTX24_STBY_LVC3_SCL_R1"
				( objectStatus "@baseboard_fab2_lib.baseboard_fab2(sch_1):smb_slotx24_stby_lvc3_scl_r1" )
			)
			( signal "SMB_SLOTX24_STBY_LVC3_SDA_R1"
				( objectStatus "@baseboard_fab2_lib.baseboard_fab2(sch_1):smb_slotx24_stby_lvc3_sda_r1" )
			)
			( signal "SMB_SMLINK0_STBY_LVC3_SCL_R1"
				( objectStatus "@baseboard_fab2_lib.baseboard_fab2(sch_1):smb_smlink0_stby_lvc3_scl_r1" )
			)
			( signal "SMB_SMLINK0_STBY_LVC3_SDA_R1"
				( objectStatus "@baseboard_fab2_lib.baseboard_fab2(sch_1):smb_smlink0_stby_lvc3_sda_r1" )
			)
			( signal "SP2_BMC_CM_UART_RX"
				( objectStatus "@baseboard_fab2_lib.baseboard_fab2(sch_1):sp2_bmc_cm_uart_rx" )
			)
			( signal "SP2_BMC_CM_UART_TX"
				( objectStatus "@baseboard_fab2_lib.baseboard_fab2(sch_1):sp2_bmc_cm_uart_tx" )
			)
			( signal "TP_IE_FM_UV_THRESHOLD_SET"
				( objectStatus "@baseboard_fab2_lib.baseboard_fab2(sch_1):tp_ie_fm_uv_threshold_set" )
			)
			( signal "TP_PCH_GPP_D12"
				( objectStatus "@baseboard_fab2_lib.baseboard_fab2(sch_1):tp_pch_gpp_d12" )
			)
			( signal "VID_PCH_CORE_PVNN_AUX_VID_0"
				( objectStatus "@baseboard_fab2_lib.baseboard_fab2(sch_1):vid_pch_core_pvnn_aux_vid_0" )
			)
			( signal "VID_PCH_CORE_PVNN_AUX_VID_1"
				( objectStatus "@baseboard_fab2_lib.baseboard_fab2(sch_1):vid_pch_core_pvnn_aux_vid_1" )
			)
			( signal "A_RCOMP_3P3"
				( objectStatus "@baseboard_fab2_lib.baseboard_fab2(sch_1):a_rcomp_3p3" )
			)
			( signal "FAN_PWM_OUT_SYS0"
				( objectStatus "@baseboard_fab2_lib.baseboard_fab2(sch_1):fan_pwm_out_sys0" )
			)
			( signal "FAN_PWM_OUT_SYS1"
				( objectStatus "@baseboard_fab2_lib.baseboard_fab2(sch_1):fan_pwm_out_sys1" )
			)
			( signal "FAN_TACH0"
				( objectStatus "@baseboard_fab2_lib.baseboard_fab2(sch_1):fan_tach0" )
			)
			( signal "FAN_TACH1"
				( objectStatus "@baseboard_fab2_lib.baseboard_fab2(sch_1):fan_tach1" )
			)
			( signal "FAN_TACH2"
				( objectStatus "@baseboard_fab2_lib.baseboard_fab2(sch_1):fan_tach2" )
			)
			( signal "FAN_TACH3"
				( objectStatus "@baseboard_fab2_lib.baseboard_fab2(sch_1):fan_tach3" )
			)
			( signal "FM_ADR_COMPLETE_R1"
				( objectStatus "@baseboard_fab2_lib.baseboard_fab2(sch_1):fm_adr_complete_r1" )
			)
			( signal "FM_BACKUP_BIOS_SEL_N"
				( objectStatus "@baseboard_fab2_lib.baseboard_fab2(sch_1):fm_backup_bios_sel_n" )
			)
			( signal "FM_BIOS_MRC_DEBUG_MSG_DIS_N"
				( objectStatus "@baseboard_fab2_lib.baseboard_fab2(sch_1):fm_bios_mrc_debug_msg_dis_n" )
			)
			( signal "FM_BIOS_SMI_ACTIVE_N"
				( objectStatus "@baseboard_fab2_lib.baseboard_fab2(sch_1):fm_bios_smi_active_n" )
			)
			( signal "FM_BIOS_TOP_SWAP"
				( objectStatus "@baseboard_fab2_lib.baseboard_fab2(sch_1):fm_bios_top_swap" )
			)
			( signal "FM_BIOS_USB_RECOVERY"
				( objectStatus "@baseboard_fab2_lib.baseboard_fab2(sch_1):fm_bios_usb_recovery" )
			)
			( signal "FM_BMC_NMI_N"
				( objectStatus "@baseboard_fab2_lib.baseboard_fab2(sch_1):fm_bmc_nmi_n" )
			)
			( signal "FM_BOARD_SKU_ID0"
				( objectStatus "@baseboard_fab2_lib.baseboard_fab2(sch_1):fm_board_sku_id0" )
			)
			( signal "FM_BOARD_SKU_ID1"
				( objectStatus "@baseboard_fab2_lib.baseboard_fab2(sch_1):fm_board_sku_id1" )
			)
			( signal "FM_BOARD_SKU_ID2"
				( objectStatus "@baseboard_fab2_lib.baseboard_fab2(sch_1):fm_board_sku_id2" )
			)
			( signal "FM_BOARD_SKU_ID3"
				( objectStatus "@baseboard_fab2_lib.baseboard_fab2(sch_1):fm_board_sku_id3" )
			)
			( signal "FM_BOARD_SKU_ID4"
				( objectStatus "@baseboard_fab2_lib.baseboard_fab2(sch_1):fm_board_sku_id4" )
			)
			( signal "FM_CPLD_ADR_TRIGGER_N"
				( objectStatus "@baseboard_fab2_lib.baseboard_fab2(sch_1):fm_cpld_adr_trigger_n" )
			)
			( signal "FM_CPLD_ADR_TRIGGER_R_N"
				( objectStatus "@baseboard_fab2_lib.baseboard_fab2(sch_1):fm_cpld_adr_trigger_r_n" )
			)
			( signal "FM_CPU0_FIVR_FAULT_LVT3_N"
				( objectStatus "@baseboard_fab2_lib.baseboard_fab2(sch_1):fm_cpu0_fivr_fault_lvt3_n" )
			)
			( signal "FM_CPU0_RC_EN"
				( objectStatus "@baseboard_fab2_lib.baseboard_fab2(sch_1):fm_cpu0_rc_en" )
			)
			( signal "FM_CPU1_FIVR_FAULT_LVT3_N"
				( objectStatus "@baseboard_fab2_lib.baseboard_fab2(sch_1):fm_cpu1_fivr_fault_lvt3_n" )
			)
			( signal "FM_CPU1_RC_EN"
				( objectStatus "@baseboard_fab2_lib.baseboard_fab2(sch_1):fm_cpu1_rc_en" )
			)
			( signal "FM_CPU1_THERMTRIP_LATCH_LVT3_N"
				( objectStatus "@baseboard_fab2_lib.baseboard_fab2(sch_1):fm_cpu1_thermtrip_latch_lvt3_n" )
			)
			( signal "FM_FORCE_ADR_N"
				( objectStatus "@baseboard_fab2_lib.baseboard_fab2(sch_1):fm_force_adr_n" )
			)
			( signal "FM_GBE0_LVC3_MOD_ABS"
				( objectStatus "@baseboard_fab2_lib.baseboard_fab2(sch_1):fm_gbe0_lvc3_mod_abs" )
			)
			( signal "FM_GBE1_LVC3_MOD_ABS"
				( objectStatus "@baseboard_fab2_lib.baseboard_fab2(sch_1):fm_gbe1_lvc3_mod_abs" )
			)
			( signal "FM_GBE2_LVC3_MOD_ABS"
				( objectStatus "@baseboard_fab2_lib.baseboard_fab2(sch_1):fm_gbe2_lvc3_mod_abs" )
			)
			( signal "FM_GBE3_LVC3_MOD_ABS"
				( objectStatus "@baseboard_fab2_lib.baseboard_fab2(sch_1):fm_gbe3_lvc3_mod_abs" )
			)
			( signal "FM_HSC_TIMER_EXP_N"
				( objectStatus "@baseboard_fab2_lib.baseboard_fab2(sch_1):fm_hsc_timer_exp_n" )
			)
			( signal "FM_IE_DISABLE_N"
				( objectStatus "@baseboard_fab2_lib.baseboard_fab2(sch_1):fm_ie_disable_n" )
			)
			( signal "FM_MEM_THERM_EVENT_PCH_N"
				( objectStatus "@baseboard_fab2_lib.baseboard_fab2(sch_1):fm_mem_therm_event_pch_n" )
			)
			( signal "FM_MP_PS_FAIL_N"
				( objectStatus "@baseboard_fab2_lib.baseboard_fab2(sch_1):fm_mp_ps_fail_n" )
			)
			( signal "FM_MP_PS_REDUNDANT_LOST_N"
				( objectStatus "@baseboard_fab2_lib.baseboard_fab2(sch_1):fm_mp_ps_redundant_lost_n" )
			)
			( signal "FM_NMI_EVENT_N"
				( objectStatus "@baseboard_fab2_lib.baseboard_fab2(sch_1):fm_nmi_event_n" )
			)
			( signal "FM_OC0_USB_N"
				( objectStatus "@baseboard_fab2_lib.baseboard_fab2(sch_1):fm_oc0_usb_n" )
			)
			( signal "FM_OC_DETECT_EN_N"
				( objectStatus "@baseboard_fab2_lib.baseboard_fab2(sch_1):fm_oc_detect_en_n" )
			)
			( signal "FM_PCH_BMC_THERMTRIP_N"
				( objectStatus "@baseboard_fab2_lib.baseboard_fab2(sch_1):fm_pch_bmc_thermtrip_n" )
			)
			( signal "FM_SOL_UART_CH_SEL"
				( objectStatus "@baseboard_fab2_lib.baseboard_fab2(sch_1):fm_sol_uart_ch_sel" )
			)
			( signal "FM_SSATA_PCIE_M2_SEL"
				( objectStatus "@baseboard_fab2_lib.baseboard_fab2(sch_1):fm_ssata_pcie_m2_sel" )
			)
			( signal "FM_UARTSW_LSB_N"
				( objectStatus "@baseboard_fab2_lib.baseboard_fab2(sch_1):fm_uartsw_lsb_n" )
			)
			( signal "FM_UARTSW_MSB_N"
				( objectStatus "@baseboard_fab2_lib.baseboard_fab2(sch_1):fm_uartsw_msb_n" )
			)
			( signal "FP_PWR_ID_LED_N"
				( objectStatus "@baseboard_fab2_lib.baseboard_fab2(sch_1):fp_pwr_id_led_n" )
			)
			( signal "IRQ_BMC_PCH_NMI_STBY_N"
				( objectStatus "@baseboard_fab2_lib.baseboard_fab2(sch_1):irq_bmc_pch_nmi_stby_n" )
			)
			( signal "IRQ_BOARD_BMC_ALERT_N"
				( objectStatus "@baseboard_fab2_lib.baseboard_fab2(sch_1):irq_board_bmc_alert_n" )
			)
			( signal "IRQ_OC_DETECT_N"
				( objectStatus "@baseboard_fab2_lib.baseboard_fab2(sch_1):irq_oc_detect_n" )
			)
			( signal "IRQ_UV_DETECT_N"
				( objectStatus "@baseboard_fab2_lib.baseboard_fab2(sch_1):irq_uv_detect_n" )
			)
			( signal "JTAG_PCH_GBE_CLK"
				( objectStatus "@baseboard_fab2_lib.baseboard_fab2(sch_1):jtag_pch_gbe_clk" )
			)
			( signal "JTAG_PCH_GBE_TDI"
				( objectStatus "@baseboard_fab2_lib.baseboard_fab2(sch_1):jtag_pch_gbe_tdi" )
			)
			( signal "JTAG_PCH_GBE_TDO"
				( objectStatus "@baseboard_fab2_lib.baseboard_fab2(sch_1):jtag_pch_gbe_tdo" )
			)
			( signal "JTAG_PCH_GBE_TMS"
				( objectStatus "@baseboard_fab2_lib.baseboard_fab2(sch_1):jtag_pch_gbe_tms" )
			)
			( signal "JTAG_PCH_GBE_TRST_N"
				( objectStatus "@baseboard_fab2_lib.baseboard_fab2(sch_1):jtag_pch_gbe_trst_n" )
			)
			( signal "JTAG_PCH_PLD_TCK"
				( objectStatus "@baseboard_fab2_lib.baseboard_fab2(sch_1):jtag_pch_pld_tck" )
			)
			( signal "JTAG_PCH_PLD_TDI"
				( objectStatus "@baseboard_fab2_lib.baseboard_fab2(sch_1):jtag_pch_pld_tdi" )
			)
			( signal "JTAG_PCH_PLD_TDO"
				( objectStatus "@baseboard_fab2_lib.baseboard_fab2(sch_1):jtag_pch_pld_tdo" )
			)
			( signal "JTAG_PCH_PLD_TMS"
				( objectStatus "@baseboard_fab2_lib.baseboard_fab2(sch_1):jtag_pch_pld_tms" )
			)
			( signal "LED_GBE_P0_0"
				( objectStatus "@baseboard_fab2_lib.baseboard_fab2(sch_1):led_gbe_p0_0" )
			)
			( signal "LED_GBE_P0_1"
				( objectStatus "@baseboard_fab2_lib.baseboard_fab2(sch_1):led_gbe_p0_1" )
			)
			( signal "LED_GBE_P1_0"
				( objectStatus "@baseboard_fab2_lib.baseboard_fab2(sch_1):led_gbe_p1_0" )
			)
			( signal "LED_GBE_P1_1"
				( objectStatus "@baseboard_fab2_lib.baseboard_fab2(sch_1):led_gbe_p1_1" )
			)
			( signal "LED_GBE_P2_0"
				( objectStatus "@baseboard_fab2_lib.baseboard_fab2(sch_1):led_gbe_p2_0" )
			)
			( signal "LED_GBE_P2_1"
				( objectStatus "@baseboard_fab2_lib.baseboard_fab2(sch_1):led_gbe_p2_1" )
			)
			( signal "LED_GBE_P3_0"
				( objectStatus "@baseboard_fab2_lib.baseboard_fab2(sch_1):led_gbe_p3_0" )
			)
			( signal "LED_GBE_P3_1"
				( objectStatus "@baseboard_fab2_lib.baseboard_fab2(sch_1):led_gbe_p3_1" )
			)
			( signal "LED_PCH_SATA_HDD_N"
				( objectStatus "@baseboard_fab2_lib.baseboard_fab2(sch_1):led_pch_sata_hdd_n" )
			)
			( signal "LED_PCH_SSATA_HDD_N"
				( objectStatus "@baseboard_fab2_lib.baseboard_fab2(sch_1):led_pch_ssata_hdd_n" )
			)
			( signal "LED_POSTCODE_0"
				( objectStatus "@baseboard_fab2_lib.baseboard_fab2(sch_1):led_postcode_0" )
			)
			( signal "LED_POSTCODE_1"
				( objectStatus "@baseboard_fab2_lib.baseboard_fab2(sch_1):led_postcode_1" )
			)
			( signal "LED_POSTCODE_2"
				( objectStatus "@baseboard_fab2_lib.baseboard_fab2(sch_1):led_postcode_2" )
			)
			( signal "LED_POSTCODE_3"
				( objectStatus "@baseboard_fab2_lib.baseboard_fab2(sch_1):led_postcode_3" )
			)
			( signal "LED_POSTCODE_4"
				( objectStatus "@baseboard_fab2_lib.baseboard_fab2(sch_1):led_postcode_4" )
			)
			( signal "LED_POSTCODE_5"
				( objectStatus "@baseboard_fab2_lib.baseboard_fab2(sch_1):led_postcode_5" )
			)
			( signal "LED_POSTCODE_6"
				( objectStatus "@baseboard_fab2_lib.baseboard_fab2(sch_1):led_postcode_6" )
			)
			( signal "LED_POSTCODE_7"
				( objectStatus "@baseboard_fab2_lib.baseboard_fab2(sch_1):led_postcode_7" )
			)
			( signal "PU_10GBE_LOM_PCI_DISABLE_N"
				( objectStatus "@baseboard_fab2_lib.baseboard_fab2(sch_1):pu_10gbe_lom_pci_disable_n" )
			)
			( signal "PU_ADR_TIMER_HOLD_OFF_N"
				( objectStatus "@baseboard_fab2_lib.baseboard_fab2(sch_1):pu_adr_timer_hold_off_n" )
			)
			( signal "SGPIO_PCH_SATA_CLOCK"
				( objectStatus "@baseboard_fab2_lib.baseboard_fab2(sch_1):sgpio_pch_sata_clock" )
			)
			( signal "SGPIO_PCH_SATA_DOUT0"
				( objectStatus "@baseboard_fab2_lib.baseboard_fab2(sch_1):sgpio_pch_sata_dout0" )
			)
			( signal "SGPIO_PCH_SATA_LOAD"
				( objectStatus "@baseboard_fab2_lib.baseboard_fab2(sch_1):sgpio_pch_sata_load" )
			)
			( signal "SGPIO_PCH_SSATA_CLOCK"
				( objectStatus "@baseboard_fab2_lib.baseboard_fab2(sch_1):sgpio_pch_ssata_clock" )
			)
			( signal "SGPIO_PCH_SSATA_LOAD"
				( objectStatus "@baseboard_fab2_lib.baseboard_fab2(sch_1):sgpio_pch_ssata_load" )
			)
			( signal "SMB_LAN_STBY_LVC3_SCL_R1"
				( objectStatus "@baseboard_fab2_lib.baseboard_fab2(sch_1):smb_lan_stby_lvc3_scl_r1" )
			)
			( signal "SMB_LAN_STBY_LVC3_SCL_R2"
				( objectStatus "@baseboard_fab2_lib.baseboard_fab2(sch_1):smb_lan_stby_lvc3_scl_r2" )
			)
			( signal "SMB_LAN_STBY_LVC3_SDA_R1"
				( objectStatus "@baseboard_fab2_lib.baseboard_fab2(sch_1):smb_lan_stby_lvc3_sda_r1" )
			)
			( signal "SMB_LAN_STBY_LVC3_SDA_R2"
				( objectStatus "@baseboard_fab2_lib.baseboard_fab2(sch_1):smb_lan_stby_lvc3_sda_r2" )
			)
			( signal "SMB_PCH_MEZZ_LOM0_SCL"
				( objectStatus "@baseboard_fab2_lib.baseboard_fab2(sch_1):smb_pch_mezz_lom0_scl" )
			)
			( signal "SMB_PCH_MEZZ_LOM0_SDA"
				( objectStatus "@baseboard_fab2_lib.baseboard_fab2(sch_1):smb_pch_mezz_lom0_sda" )
			)
			( signal "SMB_PCH_MEZZ_LOM1_SCL"
				( objectStatus "@baseboard_fab2_lib.baseboard_fab2(sch_1):smb_pch_mezz_lom1_scl" )
			)
			( signal "SMB_PCH_MEZZ_LOM1_SDA"
				( objectStatus "@baseboard_fab2_lib.baseboard_fab2(sch_1):smb_pch_mezz_lom1_sda" )
			)
			( signal "SMB_PCH_MEZZ_LOM2_SCL"
				( objectStatus "@baseboard_fab2_lib.baseboard_fab2(sch_1):smb_pch_mezz_lom2_scl" )
			)
			( signal "SMB_PCH_MEZZ_LOM2_SDA"
				( objectStatus "@baseboard_fab2_lib.baseboard_fab2(sch_1):smb_pch_mezz_lom2_sda" )
			)
			( signal "SMB_PCH_MEZZ_LOM3_SCL"
				( objectStatus "@baseboard_fab2_lib.baseboard_fab2(sch_1):smb_pch_mezz_lom3_scl" )
			)
			( signal "SMB_PCH_MEZZ_LOM3_SDA"
				( objectStatus "@baseboard_fab2_lib.baseboard_fab2(sch_1):smb_pch_mezz_lom3_sda" )
			)
			( signal "SMB_SENSOR_STBY_LVC3_SCL_R1"
				( objectStatus "@baseboard_fab2_lib.baseboard_fab2(sch_1):smb_sensor_stby_lvc3_scl_r1" )
			)
			( signal "SMB_SENSOR_STBY_LVC3_SDA_R1"
				( objectStatus "@baseboard_fab2_lib.baseboard_fab2(sch_1):smb_sensor_stby_lvc3_sda_r1" )
			)
			( signal "SMB_VR_STBY_LVC3_SCL_R1"
				( objectStatus "@baseboard_fab2_lib.baseboard_fab2(sch_1):smb_vr_stby_lvc3_scl_r1" )
			)
			( signal "SMB_VR_STBY_LVC3_SDA_R1"
				( objectStatus "@baseboard_fab2_lib.baseboard_fab2(sch_1):smb_vr_stby_lvc3_sda_r1" )
			)
			( signal "TP_PCH_GPP_F12"
				( objectStatus "@baseboard_fab2_lib.baseboard_fab2(sch_1):tp_pch_gpp_f12" )
			)
			( signal "TP_PCH_GPP_J17"
				( objectStatus "@baseboard_fab2_lib.baseboard_fab2(sch_1):tp_pch_gpp_j17" )
			)
			( signal "TP_PCH_GPP_J19"
				( objectStatus "@baseboard_fab2_lib.baseboard_fab2(sch_1):tp_pch_gpp_j19" )
			)
			( signal "TP_PCH_GPP_J21"
				( objectStatus "@baseboard_fab2_lib.baseboard_fab2(sch_1):tp_pch_gpp_j21" )
			)
			( signal "TP_PCH_GPP_J23"
				( objectStatus "@baseboard_fab2_lib.baseboard_fab2(sch_1):tp_pch_gpp_j23" )
			)
			( signal "A_1P8_3P3_RCOMP"
				( objectStatus "@baseboard_fab2_lib.baseboard_fab2(sch_1):a_1p8_3p3_rcomp" )
			)
			( signal "FM_FLASH_DESC_OVERRIDE"
				( objectStatus "@baseboard_fab2_lib.baseboard_fab2(sch_1):fm_flash_desc_override" )
			)
			( signal "FM_INTRUDER_HDR_PCH_N"
				( objectStatus "@baseboard_fab2_lib.baseboard_fab2(sch_1):fm_intruder_hdr_pch_n" )
			)
			( signal "FM_OCP_MEZZB_PRES_N"
				( objectStatus "@baseboard_fab2_lib.baseboard_fab2(sch_1):fm_ocp_mezzb_pres_n" )
			)
			( signal "FM_OCP_MEZZC_PRES_N"
				( objectStatus "@baseboard_fab2_lib.baseboard_fab2(sch_1):fm_ocp_mezzc_pres_n" )
			)
			( signal "FM_PCH_PRSNT_N"
				( objectStatus "@baseboard_fab2_lib.baseboard_fab2(sch_1):fm_pch_prsnt_n" )
			)
			( signal "FM_SINT_PRSNT_N"
				( objectStatus "@baseboard_fab2_lib.baseboard_fab2(sch_1):fm_sint_prsnt_n" )
			)
			( signal "FM_WBG_PRSNT_N"
				( objectStatus "@baseboard_fab2_lib.baseboard_fab2(sch_1):fm_wbg_prsnt_n" )
			)
			( signal "FM_CPU_ERR1_PCH_N"
				( objectStatus "@baseboard_fab2_lib.baseboard_fab2(sch_1):fm_cpu_err1_pch_n" )
			)
			( signal "FM_CPU_ERR0_PCH_N"
				( objectStatus "@baseboard_fab2_lib.baseboard_fab2(sch_1):fm_cpu_err0_pch_n" )
			)
			( signal "FM_CPU1_PROCHOT_PCH_N"
				( objectStatus "@baseboard_fab2_lib.baseboard_fab2(sch_1):fm_cpu1_prochot_pch_n" )
			)
			( signal "RMII_BMC_PCH_SPRNGVLLE_CRSDV"
				( objectStatus "@baseboard_fab2_lib.baseboard_fab2(sch_1):rmii_bmc_pch_sprngvlle_crsdv" )
			)
			( signal "RMII_BMC_PCH_SPRNGVLLE_CRSDV_R1"
				( objectStatus "@baseboard_fab2_lib.baseboard_fab2(sch_1):rmii_bmc_pch_sprngvlle_crsdv_r1" )
			)
			( signal "RMII_BMC_PCH_SPRNGVLLE_RXER"
				( objectStatus "@baseboard_fab2_lib.baseboard_fab2(sch_1):rmii_bmc_pch_sprngvlle_rxer" )
			)
			( signal "RMII_BMC_PCH_SPRNGVLLE_RXER_R"
				( objectStatus "@baseboard_fab2_lib.baseboard_fab2(sch_1):rmii_bmc_pch_sprngvlle_rxer_r" )
			)
			( signal "RMII_BMC_PCH_SPRNGVLLE_TXD0"
				( objectStatus "@baseboard_fab2_lib.baseboard_fab2(sch_1):rmii_bmc_pch_sprngvlle_txd0" )
			)
			( signal "RMII_BMC_PCH_SPRNGVLLE_TXD1"
				( objectStatus "@baseboard_fab2_lib.baseboard_fab2(sch_1):rmii_bmc_pch_sprngvlle_txd1" )
			)
			( signal "RMII_BMC_PCH_SPRNGVLLE_TXEN"
				( objectStatus "@baseboard_fab2_lib.baseboard_fab2(sch_1):rmii_bmc_pch_sprngvlle_txen" )
			)
			( signal "RMII_PCH_SPRNGVLLE_ARB_IN"
				( objectStatus "@baseboard_fab2_lib.baseboard_fab2(sch_1):rmii_pch_sprngvlle_arb_in" )
			)
			( signal "RMII_PCH_SPRNGVLLE_ARB_OUT"
				( objectStatus "@baseboard_fab2_lib.baseboard_fab2(sch_1):rmii_pch_sprngvlle_arb_out" )
			)
			( signal "RMII_PCH_SPRNGVLLE_ARB_OUT_R"
				( objectStatus "@baseboard_fab2_lib.baseboard_fab2(sch_1):rmii_pch_sprngvlle_arb_out_r" )
			)
			( signal "RMII_SPRNGVLLE_BMC_PCH_RXD0"
				( objectStatus "@baseboard_fab2_lib.baseboard_fab2(sch_1):rmii_sprngvlle_bmc_pch_rxd0" )
			)
			( signal "RMII_SPRNGVLLE_BMC_PCH_RXD0_R1"
				( objectStatus "@baseboard_fab2_lib.baseboard_fab2(sch_1):rmii_sprngvlle_bmc_pch_rxd0_r1" )
			)
			( signal "RMII_SPRNGVLLE_BMC_PCH_RXD1"
				( objectStatus "@baseboard_fab2_lib.baseboard_fab2(sch_1):rmii_sprngvlle_bmc_pch_rxd1" )
			)
			( signal "RMII_SPRNGVLLE_BMC_PCH_RXD1_R1"
				( objectStatus "@baseboard_fab2_lib.baseboard_fab2(sch_1):rmii_sprngvlle_bmc_pch_rxd1_r1" )
			)
			( signal "RST_PCIE_PCH_PERST_N"
				( objectStatus "@baseboard_fab2_lib.baseboard_fab2(sch_1):rst_pcie_pch_perst_n" )
			)
			( signal "RST_RTCRST_N"
				( objectStatus "@baseboard_fab2_lib.baseboard_fab2(sch_1):rst_rtcrst_n" )
			)
			( signal "RST_SRTCRST_N"
				( objectStatus "@baseboard_fab2_lib.baseboard_fab2(sch_1):rst_srtcrst_n" )
			)
			( signal "SPI_PCH_CLK"
				( objectStatus "@baseboard_fab2_lib.baseboard_fab2(sch_1):spi_pch_clk" )
			)
			( signal "SPI_PCH_CS0_N"
				( objectStatus "@baseboard_fab2_lib.baseboard_fab2(sch_1):spi_pch_cs0_n" )
			)
			( signal "SPI_PCH_CS0_R_N"
				( objectStatus "@baseboard_fab2_lib.baseboard_fab2(sch_1):spi_pch_cs0_r_n" )
			)
			( signal "SPI_PCH_IO3"
				( objectStatus "@baseboard_fab2_lib.baseboard_fab2(sch_1):spi_pch_io3" )
			)
			( signal "SPI_PCH_MISO"
				( objectStatus "@baseboard_fab2_lib.baseboard_fab2(sch_1):spi_pch_miso" )
			)
			( signal "SPI_PCH_MOSI_R"
				( objectStatus "@baseboard_fab2_lib.baseboard_fab2(sch_1):spi_pch_mosi_r" )
			)
			( signal "SPI_PCH_TPM_CS_N"
				( objectStatus "@baseboard_fab2_lib.baseboard_fab2(sch_1):spi_pch_tpm_cs_n" )
			)
			( signal "TP_PCH_DISPA_BCLK"
				( objectStatus "@baseboard_fab2_lib.baseboard_fab2(sch_1):tp_pch_dispa_bclk" )
			)
			( signal "TP_PCH_DISPA_SDI"
				( objectStatus "@baseboard_fab2_lib.baseboard_fab2(sch_1):tp_pch_dispa_sdi" )
			)
			( signal "TP_PCH_DISPA_SDO"
				( objectStatus "@baseboard_fab2_lib.baseboard_fab2(sch_1):tp_pch_dispa_sdo" )
			)
			( signal "TP_PCH_GPP_L10"
				( objectStatus "@baseboard_fab2_lib.baseboard_fab2(sch_1):tp_pch_gpp_l10" )
			)
			( signal "TP_PCH_GPP_L11"
				( objectStatus "@baseboard_fab2_lib.baseboard_fab2(sch_1):tp_pch_gpp_l11" )
			)
			( signal "TP_PCH_HDA_BCLK"
				( objectStatus "@baseboard_fab2_lib.baseboard_fab2(sch_1):tp_pch_hda_bclk" )
			)
			( signal "TP_PCH_HDA_SDI_0"
				( objectStatus "@baseboard_fab2_lib.baseboard_fab2(sch_1):tp_pch_hda_sdi_0" )
			)
			( signal "TP_PCH_HDA_SDI_1"
				( objectStatus "@baseboard_fab2_lib.baseboard_fab2(sch_1):tp_pch_hda_sdi_1" )
			)
			( signal "TP_PCH_HDA_SYNC"
				( objectStatus "@baseboard_fab2_lib.baseboard_fab2(sch_1):tp_pch_hda_sync" )
			)
			( signal "TP_PCH_HSA_RST_N"
				( objectStatus "@baseboard_fab2_lib.baseboard_fab2(sch_1):tp_pch_hsa_rst_n" )
			)
			( signal "TP_PCH_RSVD0"
				( objectStatus "@baseboard_fab2_lib.baseboard_fab2(sch_1):tp_pch_rsvd0" )
			)
			( signal "TP_PCH_RSVD1"
				( objectStatus "@baseboard_fab2_lib.baseboard_fab2(sch_1):tp_pch_rsvd1" )
			)
			( signal "TP_PCH_RSVD12"
				( objectStatus "@baseboard_fab2_lib.baseboard_fab2(sch_1):tp_pch_rsvd12" )
			)
			( signal "TP_PCH_RSVD13"
				( objectStatus "@baseboard_fab2_lib.baseboard_fab2(sch_1):tp_pch_rsvd13" )
			)
			( signal "TP_PCH_RSVD14"
				( objectStatus "@baseboard_fab2_lib.baseboard_fab2(sch_1):tp_pch_rsvd14" )
			)
			( signal "TP_PCH_RSVD15"
				( objectStatus "@baseboard_fab2_lib.baseboard_fab2(sch_1):tp_pch_rsvd15" )
			)
			( signal "TP_PCH_RSVD16"
				( objectStatus "@baseboard_fab2_lib.baseboard_fab2(sch_1):tp_pch_rsvd16" )
			)
			( signal "TP_PCH_RSVD17"
				( objectStatus "@baseboard_fab2_lib.baseboard_fab2(sch_1):tp_pch_rsvd17" )
			)
			( signal "TP_PCH_RSVD18"
				( objectStatus "@baseboard_fab2_lib.baseboard_fab2(sch_1):tp_pch_rsvd18" )
			)
			( signal "TP_PCH_RSVD19"
				( objectStatus "@baseboard_fab2_lib.baseboard_fab2(sch_1):tp_pch_rsvd19" )
			)
			( signal "TP_PCH_RSVD2"
				( objectStatus "@baseboard_fab2_lib.baseboard_fab2(sch_1):tp_pch_rsvd2" )
			)
			( signal "TP_PCH_RSVD20"
				( objectStatus "@baseboard_fab2_lib.baseboard_fab2(sch_1):tp_pch_rsvd20" )
			)
			( signal "TP_PCH_RSVD21"
				( objectStatus "@baseboard_fab2_lib.baseboard_fab2(sch_1):tp_pch_rsvd21" )
			)
			( signal "TP_PCH_RSVD22"
				( objectStatus "@baseboard_fab2_lib.baseboard_fab2(sch_1):tp_pch_rsvd22" )
			)
			( signal "TP_PCH_RSVD23"
				( objectStatus "@baseboard_fab2_lib.baseboard_fab2(sch_1):tp_pch_rsvd23" )
			)
			( signal "TP_PCH_RSVD24"
				( objectStatus "@baseboard_fab2_lib.baseboard_fab2(sch_1):tp_pch_rsvd24" )
			)
			( signal "TP_PCH_RSVD25"
				( objectStatus "@baseboard_fab2_lib.baseboard_fab2(sch_1):tp_pch_rsvd25" )
			)
			( signal "TP_PCH_RSVD26"
				( objectStatus "@baseboard_fab2_lib.baseboard_fab2(sch_1):tp_pch_rsvd26" )
			)
			( signal "TP_PCH_RSVD27"
				( objectStatus "@baseboard_fab2_lib.baseboard_fab2(sch_1):tp_pch_rsvd27" )
			)
			( signal "TP_PCH_RSVD3"
				( objectStatus "@baseboard_fab2_lib.baseboard_fab2(sch_1):tp_pch_rsvd3" )
			)
			( signal "TP_PCH_RSVD4"
				( objectStatus "@baseboard_fab2_lib.baseboard_fab2(sch_1):tp_pch_rsvd4" )
			)
			( signal "TP_PCH_RSVD46"
				( objectStatus "@baseboard_fab2_lib.baseboard_fab2(sch_1):tp_pch_rsvd46" )
			)
			( signal "TP_PCH_RSVD5"
				( objectStatus "@baseboard_fab2_lib.baseboard_fab2(sch_1):tp_pch_rsvd5" )
			)
			( signal "TP_PCH_RSVD6"
				( objectStatus "@baseboard_fab2_lib.baseboard_fab2(sch_1):tp_pch_rsvd6" )
			)
			( signal "TP_PCH_RSVD7"
				( objectStatus "@baseboard_fab2_lib.baseboard_fab2(sch_1):tp_pch_rsvd7" )
			)
			( signal "TP_PCH_RSVD8"
				( objectStatus "@baseboard_fab2_lib.baseboard_fab2(sch_1):tp_pch_rsvd8" )
			)
			( signal "TP_PCH_RSVD9"
				( objectStatus "@baseboard_fab2_lib.baseboard_fab2(sch_1):tp_pch_rsvd9" )
			)
			( signal "TP_SPI_PCH_CS1_R1_N"
				( objectStatus "@baseboard_fab2_lib.baseboard_fab2(sch_1):tp_spi_pch_cs1_r1_n" )
			)
			( signal "A_PVCCRTC_EXT_CAP"
				( objectStatus "@baseboard_fab2_lib.baseboard_fab2(sch_1):a_pvccrtc_ext_cap" )
			)
			( signal "P1V05_PCH_STBY_ISCLK_PLL"
				( attribute "VOLTAGE" "1.05V"
					( Units "uVoltage" "V" 1.000000)
					( Status sAliasFlattened )
					( Origin gFrontEnd )
				)
				( objectStatus "@baseboard_fab2_lib.baseboard_fab2(sch_1):p1v05_pch_stby_isclk_pll" )
			)
			( signal "P1V05_PCH_STBY_VCCA_PLL0"
				( attribute "VOLTAGE" "1.05V"
					( Units "uVoltage" "V" 1.000000)
					( Status sAliasFlattened )
					( Origin gFrontEnd )
				)
				( objectStatus "@baseboard_fab2_lib.baseboard_fab2(sch_1):p1v05_pch_stby_vcca_pll0" )
			)
			( signal "P1V05_PCH_STBY_VCCA_PLL1"
				( attribute "VOLTAGE" "1.05V"
					( Units "uVoltage" "V" 1.000000)
					( Status sAliasFlattened )
					( Origin gFrontEnd )
				)
				( objectStatus "@baseboard_fab2_lib.baseboard_fab2(sch_1):p1v05_pch_stby_vcca_pll1" )
			)
			( signal "P1V05_PCH_STBY_VCCA_XTAL"
				( attribute "VOLTAGE" "1.05V"
					( Units "uVoltage" "V" 1.000000)
					( Status sAliasFlattened )
					( Origin gFrontEnd )
				)
				( objectStatus "@baseboard_fab2_lib.baseboard_fab2(sch_1):p1v05_pch_stby_vcca_xtal" )
			)
			( signal "P1V05_PCH_STBY_WM20_PLL"
				( attribute "VOLTAGE" "1.05V"
					( Units "uVoltage" "V" 1.000000)
					( Status sAliasFlattened )
					( Origin gFrontEnd )
				)
				( objectStatus "@baseboard_fab2_lib.baseboard_fab2(sch_1):p1v05_pch_stby_wm20_pll" )
			)
			( signal "P1V05_PCH_STBY_WM26_PLL"
				( attribute "VOLTAGE" "1.05V"
					( Units "uVoltage" "V" 1.000000)
					( Status sAliasFlattened )
					( Origin gFrontEnd )
				)
				( objectStatus "@baseboard_fab2_lib.baseboard_fab2(sch_1):p1v05_pch_stby_wm26_pll" )
			)
			( signal "P1V8_PCH_STBY"
				( attribute "VOLTAGE" "1.8V"
					( Units "uVoltage" "V" 1.000000)
					( Status sAliasFlattened )
					( Origin gFrontEnd )
				)
				( objectStatus "@baseboard_fab2_lib.baseboard_fab2(sch_1):p1v8_pch_stby" )
			)
			( signal "P3V3_RTC_STBY"
				( attribute "VOLTAGE" "3.3V"
					( Units "uVoltage" "V" 1.000000)
					( Status sAliasFlattened )
					( Origin gFrontEnd )
				)
				( objectStatus "@baseboard_fab2_lib.baseboard_fab2(sch_1):p3v3_rtc_stby" )
			)
			( signal "TP_PCH_RSVD28"
				( objectStatus "@baseboard_fab2_lib.baseboard_fab2(sch_1):tp_pch_rsvd28" )
			)
			( signal "TP_PCH_RSVD29"
				( objectStatus "@baseboard_fab2_lib.baseboard_fab2(sch_1):tp_pch_rsvd29" )
			)
			( signal "TP_PCH_RSVD30"
				( objectStatus "@baseboard_fab2_lib.baseboard_fab2(sch_1):tp_pch_rsvd30" )
			)
			( signal "TP_PCH_RSVD31"
				( objectStatus "@baseboard_fab2_lib.baseboard_fab2(sch_1):tp_pch_rsvd31" )
			)
			( signal "TP_PCH_RSVD58"
				( objectStatus "@baseboard_fab2_lib.baseboard_fab2(sch_1):tp_pch_rsvd58" )
			)
			( signal "TP_PCH_RSVD59"
				( objectStatus "@baseboard_fab2_lib.baseboard_fab2(sch_1):tp_pch_rsvd59" )
			)
			( signal "PVNN_PCH_STBY"
				( attribute "VOLTAGE" "1.0V"
					( Units "uVoltage" "V" 1.000000)
					( Status sAliasFlattened )
					( Origin gFrontEnd )
				)
				( objectStatus "@baseboard_fab2_lib.baseboard_fab2(sch_1):pvnn_pch_stby" )
			)
			( signal "VSENSE_PVNN_PCH_STBY_FPK"
				( objectStatus "@baseboard_fab2_lib.baseboard_fab2(sch_1):vsense_pvnn_pch_stby_fpk" )
			)
			( signal "VSENSE_PVNN_PCH_STBY_QAT"
				( objectStatus "@baseboard_fab2_lib.baseboard_fab2(sch_1):vsense_pvnn_pch_stby_qat" )
			)
			( signal "RST_RSMRST_DLY"
				( objectStatus "@baseboard_fab2_lib.baseboard_fab2(sch_1):rst_rsmrst_dly" )
			)
			( signal "FM_CPLD_UART_CH_LOCK_N"
				( objectStatus "@baseboard_fab2_lib.baseboard_fab2(sch_1):fm_cpld_uart_ch_lock_n" )
			)
			( signal "FM_DIS_ADR_DLY"
				( objectStatus "@baseboard_fab2_lib.baseboard_fab2(sch_1):fm_dis_adr_dly" )
			)
			( signal "FM_PCH_SATA_RAID_KEY_R"
				( objectStatus "@baseboard_fab2_lib.baseboard_fab2(sch_1):fm_pch_sata_raid_key_r" )
			)
			( signal "PU_KEY_CONN_PIN2_R"
				( objectStatus "@baseboard_fab2_lib.baseboard_fab2(sch_1):pu_key_conn_pin2_r" )
			)
			( signal "TP_JUMPER_BLOCK_1_7"
				( objectStatus "@baseboard_fab2_lib.baseboard_fab2(sch_1):\tp_jumper_block_ 1_7\" )
			)
			( signal "TP_JUMPER_BLOCK_1_1"
				( objectStatus "@baseboard_fab2_lib.baseboard_fab2(sch_1):tp_jumper_block_1_1" )
			)
			( signal "TP_JUMPER_BLOCK_1_2"
				( objectStatus "@baseboard_fab2_lib.baseboard_fab2(sch_1):tp_jumper_block_1_2" )
			)
			( signal "TP_JUMPER_BLOCK_1_8"
				( objectStatus "@baseboard_fab2_lib.baseboard_fab2(sch_1):tp_jumper_block_1_8" )
			)
			( signal "FM_THERMTRIP_DLY"
				( objectStatus "@baseboard_fab2_lib.baseboard_fab2(sch_1):fm_thermtrip_dly" )
			)
			( signal "FM_THERMTRIP_DLY_R"
				( objectStatus "@baseboard_fab2_lib.baseboard_fab2(sch_1):fm_thermtrip_dly_r" )
			)
			( signal "RST_PLTRST_BUF_N"
				( objectStatus "@baseboard_fab2_lib.baseboard_fab2(sch_1):rst_pltrst_buf_n" )
			)
			( signal "FM_BIOS_TOP_SWAP_SPKR_R"
				( objectStatus "@baseboard_fab2_lib.baseboard_fab2(sch_1):fm_bios_top_swap_spkr_r" )
			)
			( signal "PD_ME_RCVR_N"
				( objectStatus "@baseboard_fab2_lib.baseboard_fab2(sch_1):pd_me_rcvr_n" )
			)
			( signal "PD_PASSWORD_CLEAR"
				( objectStatus "@baseboard_fab2_lib.baseboard_fab2(sch_1):pd_password_clear" )
			)
			( signal "PU_BIOS_RECOVER_BOOT"
				( objectStatus "@baseboard_fab2_lib.baseboard_fab2(sch_1):pu_bios_recover_boot" )
			)
			( signal "PU_BIOS_USB_RECOVERY"
				( objectStatus "@baseboard_fab2_lib.baseboard_fab2(sch_1):pu_bios_usb_recovery" )
			)
			( signal "RST_PLTRST_TOP_SWAP"
				( objectStatus "@baseboard_fab2_lib.baseboard_fab2(sch_1):rst_pltrst_top_swap" )
			)
			( signal "TP_BIOS_RECOVER_BOOT"
				( objectStatus "@baseboard_fab2_lib.baseboard_fab2(sch_1):tp_bios_recover_boot" )
			)
			( signal "TP_BIOS_USB_RECOVERY"
				( objectStatus "@baseboard_fab2_lib.baseboard_fab2(sch_1):tp_bios_usb_recovery" )
			)
			( signal "TP_ME_RCVR_BOOT"
				( objectStatus "@baseboard_fab2_lib.baseboard_fab2(sch_1):tp_me_rcvr_boot" )
			)
			( signal "TP_PASSWORD_CLEAR"
				( objectStatus "@baseboard_fab2_lib.baseboard_fab2(sch_1):tp_password_clear" )
			)
			( signal "FM_BMC_DISABLE"
				( objectStatus "@baseboard_fab2_lib.baseboard_fab2(sch_1):fm_bmc_disable" )
			)
			( signal "FM_ROMA<0>"
				( objectStatus "@baseboard_fab2_lib.baseboard_fab2(sch_1):fm_roma(0)" )
			)
			( signal "PD_IE_DEBUG_MODE"
				( objectStatus "@baseboard_fab2_lib.baseboard_fab2(sch_1):pd_ie_debug_mode" )
			)
			( signal "PD_RST_RTCRST_N"
				( objectStatus "@baseboard_fab2_lib.baseboard_fab2(sch_1):pd_rst_rtcrst_n" )
			)
			( signal "TP_BMC_DISABLE"
				( objectStatus "@baseboard_fab2_lib.baseboard_fab2(sch_1):tp_bmc_disable" )
			)
			( signal "TP_IE_DEBUG_MODE"
				( objectStatus "@baseboard_fab2_lib.baseboard_fab2(sch_1):tp_ie_debug_mode" )
			)
			( signal "TP_JUMPER_BLOCK_2_10"
				( objectStatus "@baseboard_fab2_lib.baseboard_fab2(sch_1):tp_jumper_block_2_10" )
			)
			( signal "TP_JUMPER_BLOCK_2_12"
				( objectStatus "@baseboard_fab2_lib.baseboard_fab2(sch_1):tp_jumper_block_2_12" )
			)
			( signal "TP_JUMPER_BLOCK_2_8"
				( objectStatus "@baseboard_fab2_lib.baseboard_fab2(sch_1):tp_jumper_block_2_8" )
			)
			( signal "TP_RST_RTCRST_N"
				( objectStatus "@baseboard_fab2_lib.baseboard_fab2(sch_1):tp_rst_rtcrst_n" )
			)
			( signal "SMB_BMC_PMBUS_STBY_LVC3_SCL"
				( objectStatus "@baseboard_fab2_lib.baseboard_fab2(sch_1):smb_bmc_pmbus_stby_lvc3_scl" )
			)
			( signal "SMB_BMC_PMBUS_STBY_LVC3_SDA"
				( objectStatus "@baseboard_fab2_lib.baseboard_fab2(sch_1):smb_bmc_pmbus_stby_lvc3_sda" )
			)
			( signal "SMB_LAN_STBY_LVC3_SCL"
				( objectStatus "@baseboard_fab2_lib.baseboard_fab2(sch_1):smb_lan_stby_lvc3_scl" )
			)
			( signal "SMB_LAN_STBY_LVC3_SDA"
				( objectStatus "@baseboard_fab2_lib.baseboard_fab2(sch_1):smb_lan_stby_lvc3_sda" )
			)
			( signal "SMB_SENSOR_PCH_STBY_LVC3_SCL"
				( objectStatus "@baseboard_fab2_lib.baseboard_fab2(sch_1):smb_sensor_pch_stby_lvc3_scl" )
			)
			( signal "SMB_SENSOR_PCH_STBY_LVC3_SDA"
				( objectStatus "@baseboard_fab2_lib.baseboard_fab2(sch_1):smb_sensor_pch_stby_lvc3_sda" )
			)
			( signal "SMB_SMLINK0_STBY_LVC3_SCL"
				( objectStatus "@baseboard_fab2_lib.baseboard_fab2(sch_1):smb_smlink0_stby_lvc3_scl" )
			)
			( signal "SMB_SMLINK0_STBY_LVC3_SDA"
				( objectStatus "@baseboard_fab2_lib.baseboard_fab2(sch_1):smb_smlink0_stby_lvc3_sda" )
			)
			( signal "SMB_VR_STBY_LVC3_SCL"
				( objectStatus "@baseboard_fab2_lib.baseboard_fab2(sch_1):smb_vr_stby_lvc3_scl" )
			)
			( signal "SMB_VR_STBY_LVC3_SDA"
				( objectStatus "@baseboard_fab2_lib.baseboard_fab2(sch_1):smb_vr_stby_lvc3_sda" )
			)
			( signal "A_CBOT"
				( objectStatus "@baseboard_fab2_lib.baseboard_fab2(sch_1):a_cbot" )
			)
			( signal "A_CTOP"
				( objectStatus "@baseboard_fab2_lib.baseboard_fab2(sch_1):a_ctop" )
			)
			( signal "FM_PE_SPRV_WAKE_N"
				( objectStatus "@baseboard_fab2_lib.baseboard_fab2(sch_1):fm_pe_sprv_wake_n" )
			)
			( signal "LED_LAN_0_N"
				( objectStatus "@baseboard_fab2_lib.baseboard_fab2(sch_1):led_lan_0_n" )
			)
			( signal "LED_LAN_1_N"
				( objectStatus "@baseboard_fab2_lib.baseboard_fab2(sch_1):led_lan_1_n" )
			)
			( signal "LED_LAN_2_N"
				( objectStatus "@baseboard_fab2_lib.baseboard_fab2(sch_1):led_lan_2_n" )
			)
			( signal "NC_SPRNGVLLE_22"
				( objectStatus "@baseboard_fab2_lib.baseboard_fab2(sch_1):nc_sprngvlle_22" )
			)
			( signal "NIC_MDI_SPRV_RJ45_0_DN"
				( objectStatus "@baseboard_fab2_lib.baseboard_fab2(sch_1):nic_mdi_sprv_rj45_0_dn" )
			)
			( signal "NIC_MDI_SPRV_RJ45_0_DP"
				( objectStatus "@baseboard_fab2_lib.baseboard_fab2(sch_1):nic_mdi_sprv_rj45_0_dp" )
			)
			( signal "NIC_MDI_SPRV_RJ45_1_DN"
				( objectStatus "@baseboard_fab2_lib.baseboard_fab2(sch_1):nic_mdi_sprv_rj45_1_dn" )
			)
			( signal "NIC_MDI_SPRV_RJ45_1_DP"
				( objectStatus "@baseboard_fab2_lib.baseboard_fab2(sch_1):nic_mdi_sprv_rj45_1_dp" )
			)
			( signal "NIC_SER_N_MDI_3_DN"
				( objectStatus "@baseboard_fab2_lib.baseboard_fab2(sch_1):nic_ser_n_mdi_3_dn" )
			)
			( signal "NIC_SER_P_MDI_3_DP"
				( objectStatus "@baseboard_fab2_lib.baseboard_fab2(sch_1):nic_ser_p_mdi_3_dp" )
			)
			( signal "NIC_SET_N_MDI_2_DN"
				( objectStatus "@baseboard_fab2_lib.baseboard_fab2(sch_1):nic_set_n_mdi_2_dn" )
			)
			( signal "NIC_SET_P_MDI_2_DP"
				( objectStatus "@baseboard_fab2_lib.baseboard_fab2(sch_1):nic_set_p_mdi_2_dp" )
			)
			( signal "P0V9_LAN"
				( attribute "VOLTAGE" "0.9V"
					( Units "uVoltage" "V" 1.000000)
					( Status sAliasFlattened )
					( Origin gFrontEnd )
				)
				( objectStatus "@baseboard_fab2_lib.baseboard_fab2(sch_1):p0v9_lan" )
			)
			( signal "P0V9_LAN_I210"
				( attribute "VOLTAGE" "0.9"
					( Units "uVoltage" "V" 1.000000)
					( Status sAliasFlattened )
					( Origin gFrontEnd )
				)
				( objectStatus "@baseboard_fab2_lib.baseboard_fab2(sch_1):p0v9_lan_i210" )
			)
			( signal "P1V5_LAN"
				( attribute "VOLTAGE" "1.5V"
					( Units "uVoltage" "V" 1.000000)
					( Status sAliasFlattened )
					( Origin gFrontEnd )
				)
				( objectStatus "@baseboard_fab2_lib.baseboard_fab2(sch_1):p1v5_lan" )
			)
			( signal "P1V5_LAN_I210"
				( attribute "VOLTAGE" "1.5"
					( Units "uVoltage" "V" 1.000000)
					( Status sAliasFlattened )
					( Origin gFrontEnd )
				)
				( objectStatus "@baseboard_fab2_lib.baseboard_fab2(sch_1):p1v5_lan_i210" )
			)
			( signal "P3V3_STBY_P1V5_LAN_I210"
				( attribute "VOLTAGE" "3.3"
					( Units "uVoltage" "V" 1.000000)
					( Status sAliasFlattened )
					( Origin gFrontEnd )
				)
				( objectStatus "@baseboard_fab2_lib.baseboard_fab2(sch_1):p3v3_stby_p1v5_lan_i210" )
			)
			( signal "PD_SPRV_RSET"
				( objectStatus "@baseboard_fab2_lib.baseboard_fab2(sch_1):pd_sprv_rset" )
			)
			( signal "PE_PCH_SPRV_RX_DN"
				( objectStatus "@baseboard_fab2_lib.baseboard_fab2(sch_1):pe_pch_sprv_rx_dn" )
			)
			( signal "PE_PCH_SPRV_RX_DP"
				( objectStatus "@baseboard_fab2_lib.baseboard_fab2(sch_1):pe_pch_sprv_rx_dp" )
			)
			( signal "PE_PCH_SPRV_TX_C_DN"
				( objectStatus "@baseboard_fab2_lib.baseboard_fab2(sch_1):pe_pch_sprv_tx_c_dn" )
			)
			( signal "PE_PCH_SPRV_TX_C_DP"
				( objectStatus "@baseboard_fab2_lib.baseboard_fab2(sch_1):pe_pch_sprv_tx_c_dp" )
			)
			( signal "PU_JTAG_SPRV_TCK"
				( objectStatus "@baseboard_fab2_lib.baseboard_fab2(sch_1):pu_jtag_sprv_tck" )
			)
			( signal "PU_JTAG_SPRV_TDI"
				( objectStatus "@baseboard_fab2_lib.baseboard_fab2(sch_1):pu_jtag_sprv_tdi" )
			)
			( signal "PU_JTAG_SPRV_TDO"
				( objectStatus "@baseboard_fab2_lib.baseboard_fab2(sch_1):pu_jtag_sprv_tdo" )
			)
			( signal "PU_JTAG_SPRV_TMS"
				( objectStatus "@baseboard_fab2_lib.baseboard_fab2(sch_1):pu_jtag_sprv_tms" )
			)
			( signal "PU_SPRV_LAN_PWR_GOOD"
				( objectStatus "@baseboard_fab2_lib.baseboard_fab2(sch_1):pu_sprv_lan_pwr_good" )
			)
			( signal "RMII_BMC_PCH_SPRNGVLLE_CRSDV_R"
				( objectStatus "@baseboard_fab2_lib.baseboard_fab2(sch_1):rmii_bmc_pch_sprngvlle_crsdv_r" )
			)
			( signal "RMII_PCH_SPRNGVLLE_ARB_IN_R"
				( objectStatus "@baseboard_fab2_lib.baseboard_fab2(sch_1):rmii_pch_sprngvlle_arb_in_r" )
			)
			( signal "RMII_SPRNGVLLE_BMC_PCH_RXD0_R"
				( objectStatus "@baseboard_fab2_lib.baseboard_fab2(sch_1):rmii_sprngvlle_bmc_pch_rxd0_r" )
			)
			( signal "RMII_SPRNGVLLE_BMC_PCH_RXD1_R"
				( objectStatus "@baseboard_fab2_lib.baseboard_fab2(sch_1):rmii_sprngvlle_bmc_pch_rxd1_r" )
			)
			( signal "RST_PLTRST_SPRV_R_N"
				( objectStatus "@baseboard_fab2_lib.baseboard_fab2(sch_1):rst_pltrst_sprv_r_n" )
			)
			( signal "SMB_SPRINGVILLE_STBY_LVC3_SCL"
				( objectStatus "@baseboard_fab2_lib.baseboard_fab2(sch_1):smb_springville_stby_lvc3_scl" )
			)
			( signal "SMB_SPRINGVILLE_STBY_LVC3_SDA"
				( objectStatus "@baseboard_fab2_lib.baseboard_fab2(sch_1):smb_springville_stby_lvc3_sda" )
			)
			( signal "SPI_NIC_CS_N"
				( objectStatus "@baseboard_fab2_lib.baseboard_fab2(sch_1):spi_nic_cs_n" )
			)
			( signal "SPI_NIC_CS_R_N"
				( objectStatus "@baseboard_fab2_lib.baseboard_fab2(sch_1):spi_nic_cs_r_n" )
			)
			( signal "SPI_NIC_MISO"
				( objectStatus "@baseboard_fab2_lib.baseboard_fab2(sch_1):spi_nic_miso" )
			)
			( signal "SPI_NIC_MOSI"
				( objectStatus "@baseboard_fab2_lib.baseboard_fab2(sch_1):spi_nic_mosi" )
			)
			( signal "SPI_NIC_MOSI_R"
				( objectStatus "@baseboard_fab2_lib.baseboard_fab2(sch_1):spi_nic_mosi_r" )
			)
			( signal "SPI_NIC_SCLK"
				( objectStatus "@baseboard_fab2_lib.baseboard_fab2(sch_1):spi_nic_sclk" )
			)
			( signal "SPI_NIC_SCLK_R"
				( objectStatus "@baseboard_fab2_lib.baseboard_fab2(sch_1):spi_nic_sclk_r" )
			)
			( signal "TP_SPRV_SDP0"
				( objectStatus "@baseboard_fab2_lib.baseboard_fab2(sch_1):tp_sprv_sdp0" )
			)
			( signal "TP_SPRV_SDP1"
				( objectStatus "@baseboard_fab2_lib.baseboard_fab2(sch_1):tp_sprv_sdp1" )
			)
			( signal "TP_SPRV_SDP2"
				( objectStatus "@baseboard_fab2_lib.baseboard_fab2(sch_1):tp_sprv_sdp2" )
			)
			( signal "TP_SPRV_SDP3"
				( objectStatus "@baseboard_fab2_lib.baseboard_fab2(sch_1):tp_sprv_sdp3" )
			)
			( signal "XTAL_25MHZ_IN"
				( objectStatus "@baseboard_fab2_lib.baseboard_fab2(sch_1):xtal_25mhz_in" )
			)
			( signal "XTAL_25MHZ_IN_R"
				( objectStatus "@baseboard_fab2_lib.baseboard_fab2(sch_1):xtal_25mhz_in_r" )
			)
			( signal "XTAL_25MHZ_OUT"
				( objectStatus "@baseboard_fab2_lib.baseboard_fab2(sch_1):xtal_25mhz_out" )
			)
			( signal "XTAL_25MHZ_OUT_R"
				( objectStatus "@baseboard_fab2_lib.baseboard_fab2(sch_1):xtal_25mhz_out_r" )
			)
			( signal "PU_NV_HOLD_N"
				( objectStatus "@baseboard_fab2_lib.baseboard_fab2(sch_1):pu_nv_hold_n" )
			)
			( signal "PU_NV_WP_N"
				( objectStatus "@baseboard_fab2_lib.baseboard_fab2(sch_1):pu_nv_wp_n" )
			)
			( signal "SPI_NIC_MISO_R"
				( objectStatus "@baseboard_fab2_lib.baseboard_fab2(sch_1):spi_nic_miso_r" )
			)
			( signal "GND_LAN_TRCT1234_C"
				( objectStatus "@baseboard_fab2_lib.baseboard_fab2(sch_1):gnd_lan_trct1234_c" )
			)
			( signal "GND_NIC"
				( attribute "VOLTAGE" "0.0V"
					( Units "uVoltage" "V" 1.000000)
					( Status sAliasFlattened )
					( Origin gFrontEnd )
				)
				( objectStatus "@baseboard_fab2_lib.baseboard_fab2(sch_1):gnd_nic" )
			)
			( signal "LED_LAN_0_R_N"
				( objectStatus "@baseboard_fab2_lib.baseboard_fab2(sch_1):led_lan_0_r_n" )
			)
			( signal "LED_LAN_1_R_N"
				( objectStatus "@baseboard_fab2_lib.baseboard_fab2(sch_1):led_lan_1_r_n" )
			)
			( signal "LED_LAN_2_R_N"
				( objectStatus "@baseboard_fab2_lib.baseboard_fab2(sch_1):led_lan_2_r_n" )
			)
			( signal "NIC_LED_ACT_ANODE_R"
				( objectStatus "@baseboard_fab2_lib.baseboard_fab2(sch_1):nic_led_act_anode_r" )
			)
			( signal "NIC_MDI_MNG_RX_DN"
				( objectStatus "@baseboard_fab2_lib.baseboard_fab2(sch_1):nic_mdi_mng_rx_dn" )
			)
			( signal "NIC_MDI_MNG_RX_DP"
				( objectStatus "@baseboard_fab2_lib.baseboard_fab2(sch_1):nic_mdi_mng_rx_dp" )
			)
			( signal "NIC_MDI_MNG_TX_DN"
				( objectStatus "@baseboard_fab2_lib.baseboard_fab2(sch_1):nic_mdi_mng_tx_dn" )
			)
			( signal "NIC_MDI_MNG_TX_DP"
				( objectStatus "@baseboard_fab2_lib.baseboard_fab2(sch_1):nic_mdi_mng_tx_dp" )
			)
			( signal "NIC_MDI_SPRV_RJ45_0_R_DN"
				( objectStatus "@baseboard_fab2_lib.baseboard_fab2(sch_1):nic_mdi_sprv_rj45_0_r_dn" )
			)
			( signal "NIC_MDI_SPRV_RJ45_0_R_DP"
				( objectStatus "@baseboard_fab2_lib.baseboard_fab2(sch_1):nic_mdi_sprv_rj45_0_r_dp" )
			)
			( signal "NIC_MDI_SPRV_RJ45_1_R_DN"
				( objectStatus "@baseboard_fab2_lib.baseboard_fab2(sch_1):nic_mdi_sprv_rj45_1_r_dn" )
			)
			( signal "NIC_MDI_SPRV_RJ45_1_R_DP"
				( objectStatus "@baseboard_fab2_lib.baseboard_fab2(sch_1):nic_mdi_sprv_rj45_1_r_dp" )
			)
			( signal "NIC_MDI_SPRV_RJ45_2_R_DN"
				( objectStatus "@baseboard_fab2_lib.baseboard_fab2(sch_1):nic_mdi_sprv_rj45_2_r_dn" )
			)
			( signal "NIC_MDI_SPRV_RJ45_2_R_DP"
				( objectStatus "@baseboard_fab2_lib.baseboard_fab2(sch_1):nic_mdi_sprv_rj45_2_r_dp" )
			)
			( signal "NIC_MDI_SPRV_RJ45_3_R_DN"
				( objectStatus "@baseboard_fab2_lib.baseboard_fab2(sch_1):nic_mdi_sprv_rj45_3_r_dn" )
			)
			( signal "NIC_MDI_SPRV_RJ45_3_R_DP"
				( objectStatus "@baseboard_fab2_lib.baseboard_fab2(sch_1):nic_mdi_sprv_rj45_3_r_dp" )
			)
			( signal "FM_ALL_WAKE_N"
				( objectStatus "@baseboard_fab2_lib.baseboard_fab2(sch_1):fm_all_wake_n" )
			)
			( signal "FM_PE_BMC_WAKE_N"
				( objectStatus "@baseboard_fab2_lib.baseboard_fab2(sch_1):fm_pe_bmc_wake_n" )
			)
			( signal "FM_PE_M2_WAKE_N"
				( objectStatus "@baseboard_fab2_lib.baseboard_fab2(sch_1):fm_pe_m2_wake_n" )
			)
			( signal "FM_PE_OCP_WAKE_N"
				( objectStatus "@baseboard_fab2_lib.baseboard_fab2(sch_1):fm_pe_ocp_wake_n" )
			)
			( signal "IRQ_LVC3_WAKE_R_N"
				( objectStatus "@baseboard_fab2_lib.baseboard_fab2(sch_1):irq_lvc3_wake_r_n" )
			)
			( signal "PU_TRI_STATE_EN"
				( objectStatus "@baseboard_fab2_lib.baseboard_fab2(sch_1):pu_tri_state_en" )
			)
			( signal "M_BMC_DDR3_DQ<0>"
				( objectStatus "@baseboard_fab2_lib.baseboard_fab2(sch_1):m_bmc_ddr3_dq(0)" )
			)
			( signal "M_BMC_DDR3_DQ<1>"
				( objectStatus "@baseboard_fab2_lib.baseboard_fab2(sch_1):m_bmc_ddr3_dq(1)" )
			)
			( signal "M_BMC_DDR3_DQ<2>"
				( objectStatus "@baseboard_fab2_lib.baseboard_fab2(sch_1):m_bmc_ddr3_dq(2)" )
			)
			( signal "M_BMC_DDR3_DQ<3>"
				( objectStatus "@baseboard_fab2_lib.baseboard_fab2(sch_1):m_bmc_ddr3_dq(3)" )
			)
			( signal "M_BMC_DDR3_DQ<4>"
				( objectStatus "@baseboard_fab2_lib.baseboard_fab2(sch_1):m_bmc_ddr3_dq(4)" )
			)
			( signal "M_BMC_DDR3_DQ<5>"
				( objectStatus "@baseboard_fab2_lib.baseboard_fab2(sch_1):m_bmc_ddr3_dq(5)" )
			)
			( signal "M_BMC_DDR3_DQ<6>"
				( objectStatus "@baseboard_fab2_lib.baseboard_fab2(sch_1):m_bmc_ddr3_dq(6)" )
			)
			( signal "M_BMC_DDR3_DQ<7>"
				( objectStatus "@baseboard_fab2_lib.baseboard_fab2(sch_1):m_bmc_ddr3_dq(7)" )
			)
			( signal "M_BMC_DDR3_DQ<8>"
				( objectStatus "@baseboard_fab2_lib.baseboard_fab2(sch_1):m_bmc_ddr3_dq(8)" )
			)
			( signal "M_BMC_DDR3_DQ<9>"
				( objectStatus "@baseboard_fab2_lib.baseboard_fab2(sch_1):m_bmc_ddr3_dq(9)" )
			)
			( signal "M_BMC_DDR3_DQ<10>"
				( objectStatus "@baseboard_fab2_lib.baseboard_fab2(sch_1):m_bmc_ddr3_dq(10)" )
			)
			( signal "M_BMC_DDR3_DQ<11>"
				( objectStatus "@baseboard_fab2_lib.baseboard_fab2(sch_1):m_bmc_ddr3_dq(11)" )
			)
			( signal "M_BMC_DDR3_DQ<12>"
				( objectStatus "@baseboard_fab2_lib.baseboard_fab2(sch_1):m_bmc_ddr3_dq(12)" )
			)
			( signal "M_BMC_DDR3_DQ<13>"
				( objectStatus "@baseboard_fab2_lib.baseboard_fab2(sch_1):m_bmc_ddr3_dq(13)" )
			)
			( signal "M_BMC_DDR3_DQ<14>"
				( objectStatus "@baseboard_fab2_lib.baseboard_fab2(sch_1):m_bmc_ddr3_dq(14)" )
			)
			( signal "M_BMC_DDR3_DQ<15>"
				( objectStatus "@baseboard_fab2_lib.baseboard_fab2(sch_1):m_bmc_ddr3_dq(15)" )
			)
			( signal "M_BMC_DDR3_MA<0>"
				( objectStatus "@baseboard_fab2_lib.baseboard_fab2(sch_1):m_bmc_ddr3_ma(0)" )
			)
			( signal "M_BMC_DDR3_MA<1>"
				( objectStatus "@baseboard_fab2_lib.baseboard_fab2(sch_1):m_bmc_ddr3_ma(1)" )
			)
			( signal "M_BMC_DDR3_MA<2>"
				( objectStatus "@baseboard_fab2_lib.baseboard_fab2(sch_1):m_bmc_ddr3_ma(2)" )
			)
			( signal "M_BMC_DDR3_MA<3>"
				( objectStatus "@baseboard_fab2_lib.baseboard_fab2(sch_1):m_bmc_ddr3_ma(3)" )
			)
			( signal "M_BMC_DDR3_MA<4>"
				( objectStatus "@baseboard_fab2_lib.baseboard_fab2(sch_1):m_bmc_ddr3_ma(4)" )
			)
			( signal "M_BMC_DDR3_MA<5>"
				( objectStatus "@baseboard_fab2_lib.baseboard_fab2(sch_1):m_bmc_ddr3_ma(5)" )
			)
			( signal "M_BMC_DDR3_MA<6>"
				( objectStatus "@baseboard_fab2_lib.baseboard_fab2(sch_1):m_bmc_ddr3_ma(6)" )
			)
			( signal "M_BMC_DDR3_MA<7>"
				( objectStatus "@baseboard_fab2_lib.baseboard_fab2(sch_1):m_bmc_ddr3_ma(7)" )
			)
			( signal "M_BMC_DDR3_MA<8>"
				( objectStatus "@baseboard_fab2_lib.baseboard_fab2(sch_1):m_bmc_ddr3_ma(8)" )
			)
			( signal "M_BMC_DDR3_MA<9>"
				( objectStatus "@baseboard_fab2_lib.baseboard_fab2(sch_1):m_bmc_ddr3_ma(9)" )
			)
			( signal "M_BMC_DDR3_MA<10>"
				( objectStatus "@baseboard_fab2_lib.baseboard_fab2(sch_1):m_bmc_ddr3_ma(10)" )
			)
			( signal "M_BMC_DDR3_MA<11>"
				( objectStatus "@baseboard_fab2_lib.baseboard_fab2(sch_1):m_bmc_ddr3_ma(11)" )
			)
			( signal "M_BMC_DDR3_MA<12>"
				( objectStatus "@baseboard_fab2_lib.baseboard_fab2(sch_1):m_bmc_ddr3_ma(12)" )
			)
			( signal "M_BMC_DDR3_MA<13>"
				( objectStatus "@baseboard_fab2_lib.baseboard_fab2(sch_1):m_bmc_ddr3_ma(13)" )
			)
			( signal "M_BMC_DDR3_MA<14>"
				( objectStatus "@baseboard_fab2_lib.baseboard_fab2(sch_1):m_bmc_ddr3_ma(14)" )
			)
			( signal "M_BMC_DDR3_MBA_0"
				( objectStatus "@baseboard_fab2_lib.baseboard_fab2(sch_1):m_bmc_ddr3_mba_0" )
			)
			( signal "M_BMC_DDR3_MBA_1"
				( objectStatus "@baseboard_fab2_lib.baseboard_fab2(sch_1):m_bmc_ddr3_mba_1" )
			)
			( signal "M_BMC_DDR3_MBA_2"
				( objectStatus "@baseboard_fab2_lib.baseboard_fab2(sch_1):m_bmc_ddr3_mba_2" )
			)
			( signal "M_BMC_DDR3_MCAS_N"
				( objectStatus "@baseboard_fab2_lib.baseboard_fab2(sch_1):m_bmc_ddr3_mcas_n" )
			)
			( signal "M_BMC_DDR3_MCK_N"
				( objectStatus "@baseboard_fab2_lib.baseboard_fab2(sch_1):m_bmc_ddr3_mck_n" )
			)
			( signal "M_BMC_DDR3_MCK_P"
				( objectStatus "@baseboard_fab2_lib.baseboard_fab2(sch_1):m_bmc_ddr3_mck_p" )
			)
			( signal "M_BMC_DDR3_MCKE"
				( objectStatus "@baseboard_fab2_lib.baseboard_fab2(sch_1):m_bmc_ddr3_mcke" )
			)
			( signal "M_BMC_DDR3_MCS_N"
				( objectStatus "@baseboard_fab2_lib.baseboard_fab2(sch_1):m_bmc_ddr3_mcs_n" )
			)
			( signal "M_BMC_DDR3_MDM_0"
				( objectStatus "@baseboard_fab2_lib.baseboard_fab2(sch_1):m_bmc_ddr3_mdm_0" )
			)
			( signal "M_BMC_DDR3_MDM_1"
				( objectStatus "@baseboard_fab2_lib.baseboard_fab2(sch_1):m_bmc_ddr3_mdm_1" )
			)
			( signal "M_BMC_DDR3_MDQS_0_DN"
				( objectStatus "@baseboard_fab2_lib.baseboard_fab2(sch_1):m_bmc_ddr3_mdqs_0_dn" )
			)
			( signal "M_BMC_DDR3_MDQS_0_DP"
				( objectStatus "@baseboard_fab2_lib.baseboard_fab2(sch_1):m_bmc_ddr3_mdqs_0_dp" )
			)
			( signal "M_BMC_DDR3_MDQS_1_DN"
				( objectStatus "@baseboard_fab2_lib.baseboard_fab2(sch_1):m_bmc_ddr3_mdqs_1_dn" )
			)
			( signal "M_BMC_DDR3_MDQS_1_DP"
				( objectStatus "@baseboard_fab2_lib.baseboard_fab2(sch_1):m_bmc_ddr3_mdqs_1_dp" )
			)
			( signal "M_BMC_DDR3_MODT"
				( objectStatus "@baseboard_fab2_lib.baseboard_fab2(sch_1):m_bmc_ddr3_modt" )
			)
			( signal "M_BMC_DDR3_MRAS_N"
				( objectStatus "@baseboard_fab2_lib.baseboard_fab2(sch_1):m_bmc_ddr3_mras_n" )
			)
			( signal "M_BMC_DDR3_MVREF"
				( objectStatus "@baseboard_fab2_lib.baseboard_fab2(sch_1):m_bmc_ddr3_mvref" )
			)
			( signal "M_BMC_DDR3_MWE_N"
				( objectStatus "@baseboard_fab2_lib.baseboard_fab2(sch_1):m_bmc_ddr3_mwe_n" )
			)
			( signal "TP_M_BMC_DDR3_MIOZ"
				( objectStatus "@baseboard_fab2_lib.baseboard_fab2(sch_1):tp_m_bmc_ddr3_mioz" )
			)
			( signal "A_DACRSET"
				( objectStatus "@baseboard_fab2_lib.baseboard_fab2(sch_1):a_dacrset" )
			)
			( signal "A_USB2VRES"
				( objectStatus "@baseboard_fab2_lib.baseboard_fab2(sch_1):a_usb2vres" )
			)
			( signal "IRQ_LPC_SERIRQ_R"
				( objectStatus "@baseboard_fab2_lib.baseboard_fab2(sch_1):irq_lpc_serirq_r" )
			)
			( signal "JTAG_BMC_TCK"
				( objectStatus "@baseboard_fab2_lib.baseboard_fab2(sch_1):jtag_bmc_tck" )
			)
			( signal "JTAG_BMC_TDI"
				( objectStatus "@baseboard_fab2_lib.baseboard_fab2(sch_1):jtag_bmc_tdi" )
			)
			( signal "JTAG_BMC_TDO"
				( objectStatus "@baseboard_fab2_lib.baseboard_fab2(sch_1):jtag_bmc_tdo" )
			)
			( signal "JTAG_BMC_TMS"
				( objectStatus "@baseboard_fab2_lib.baseboard_fab2(sch_1):jtag_bmc_tms" )
			)
			( signal "JTAG_BMC_TRST_N"
				( objectStatus "@baseboard_fab2_lib.baseboard_fab2(sch_1):jtag_bmc_trst_n" )
			)
			( signal "LPC_LAD0_IO0_R"
				( objectStatus "@baseboard_fab2_lib.baseboard_fab2(sch_1):lpc_lad0_io0_r" )
			)
			( signal "LPC_LAD1_IO1_R"
				( objectStatus "@baseboard_fab2_lib.baseboard_fab2(sch_1):lpc_lad1_io1_r" )
			)
			( signal "LPC_LAD2_IO2_R"
				( objectStatus "@baseboard_fab2_lib.baseboard_fab2(sch_1):lpc_lad2_io2_r" )
			)
			( signal "LPC_LAD3_IO3_R"
				( objectStatus "@baseboard_fab2_lib.baseboard_fab2(sch_1):lpc_lad3_io3_r" )
			)
			( signal "LPC_LFRAME_N_CS0_R_N"
				( objectStatus "@baseboard_fab2_lib.baseboard_fab2(sch_1):lpc_lframe_n_cs0_r_n" )
			)
			( signal "PD_USB_BMC_P1_DN"
				( objectStatus "@baseboard_fab2_lib.baseboard_fab2(sch_1):pd_usb_bmc_p1_dn" )
			)
			( signal "PD_USB_BMC_P1_DP"
				( objectStatus "@baseboard_fab2_lib.baseboard_fab2(sch_1):pd_usb_bmc_p1_dp" )
			)
			( signal "RST_BMC_LVC3_N"
				( objectStatus "@baseboard_fab2_lib.baseboard_fab2(sch_1):rst_bmc_lvc3_n" )
			)
			( signal "SGPIO_BMC_CLK"
				( objectStatus "@baseboard_fab2_lib.baseboard_fab2(sch_1):sgpio_bmc_clk" )
			)
			( signal "SGPIO_BMC_CLK_R"
				( objectStatus "@baseboard_fab2_lib.baseboard_fab2(sch_1):sgpio_bmc_clk_r" )
			)
			( signal "SGPIO_BMC_DIN"
				( objectStatus "@baseboard_fab2_lib.baseboard_fab2(sch_1):sgpio_bmc_din" )
			)
			( signal "SGPIO_BMC_DOUT"
				( objectStatus "@baseboard_fab2_lib.baseboard_fab2(sch_1):sgpio_bmc_dout" )
			)
			( signal "SGPIO_BMC_DOUT_R"
				( objectStatus "@baseboard_fab2_lib.baseboard_fab2(sch_1):sgpio_bmc_dout_r" )
			)
			( signal "SGPIO_BMC_LD_N"
				( objectStatus "@baseboard_fab2_lib.baseboard_fab2(sch_1):sgpio_bmc_ld_n" )
			)
			( signal "SGPIO_BMC_LD_R_N"
				( objectStatus "@baseboard_fab2_lib.baseboard_fab2(sch_1):sgpio_bmc_ld_r_n" )
			)
			( signal "SMB_BMC_PMBUS_STBY_LVC3_SCL_R"
				( objectStatus "@baseboard_fab2_lib.baseboard_fab2(sch_1):smb_bmc_pmbus_stby_lvc3_scl_r" )
			)
			( signal "SMB_BMC_PMBUS_STBY_LVC3_SDA_R"
				( objectStatus "@baseboard_fab2_lib.baseboard_fab2(sch_1):smb_bmc_pmbus_stby_lvc3_sda_r" )
			)
			( signal "SMB_HOST_STBY_LVC3_SCL_R"
				( objectStatus "@baseboard_fab2_lib.baseboard_fab2(sch_1):smb_host_stby_lvc3_scl_r" )
			)
			( signal "SMB_HOST_STBY_LVC3_SDA_R"
				( objectStatus "@baseboard_fab2_lib.baseboard_fab2(sch_1):smb_host_stby_lvc3_sda_r" )
			)
			( signal "SMB_LAN_STBY_LVC3_SCL_R"
				( objectStatus "@baseboard_fab2_lib.baseboard_fab2(sch_1):smb_lan_stby_lvc3_scl_r" )
			)
			( signal "SMB_LAN_STBY_LVC3_SDA_R"
				( objectStatus "@baseboard_fab2_lib.baseboard_fab2(sch_1):smb_lan_stby_lvc3_sda_r" )
			)
			( signal "SMB_OCP_FRU_STBY_LVC3_SCL_R"
				( objectStatus "@baseboard_fab2_lib.baseboard_fab2(sch_1):smb_ocp_fru_stby_lvc3_scl_r" )
			)
			( signal "SMB_OCP_FRU_STBY_LVC3_SDA_R"
				( objectStatus "@baseboard_fab2_lib.baseboard_fab2(sch_1):smb_ocp_fru_stby_lvc3_sda_r" )
			)
			( signal "SMB_OCP_LAN_STBY_LVC3_SCL_R"
				( objectStatus "@baseboard_fab2_lib.baseboard_fab2(sch_1):smb_ocp_lan_stby_lvc3_scl_r" )
			)
			( signal "SMB_OCP_LAN_STBY_LVC3_SDA_R"
				( objectStatus "@baseboard_fab2_lib.baseboard_fab2(sch_1):smb_ocp_lan_stby_lvc3_sda_r" )
			)
			( signal "SMB_SENSOR_BMC_STBY_LVC3_SCL"
				( objectStatus "@baseboard_fab2_lib.baseboard_fab2(sch_1):smb_sensor_bmc_stby_lvc3_scl" )
			)
			( signal "SMB_SENSOR_BMC_STBY_LVC3_SDA"
				( objectStatus "@baseboard_fab2_lib.baseboard_fab2(sch_1):smb_sensor_bmc_stby_lvc3_sda" )
			)
			( signal "SMB_SLOTX24_STBY_LVC3_SCL_R"
				( objectStatus "@baseboard_fab2_lib.baseboard_fab2(sch_1):smb_slotx24_stby_lvc3_scl_r" )
			)
			( signal "SMB_SLOTX24_STBY_LVC3_SDA_R"
				( objectStatus "@baseboard_fab2_lib.baseboard_fab2(sch_1):smb_slotx24_stby_lvc3_sda_r" )
			)
			( signal "SMB_SMLINK0_STBY_LVC3_SCL_R"
				( objectStatus "@baseboard_fab2_lib.baseboard_fab2(sch_1):smb_smlink0_stby_lvc3_scl_r" )
			)
			( signal "SMB_SMLINK0_STBY_LVC3_SDA_R"
				( objectStatus "@baseboard_fab2_lib.baseboard_fab2(sch_1):smb_smlink0_stby_lvc3_sda_r" )
			)
			( signal "SMB_VR_STBY_LVC3_SCL_R"
				( objectStatus "@baseboard_fab2_lib.baseboard_fab2(sch_1):smb_vr_stby_lvc3_scl_r" )
			)
			( signal "SMB_VR_STBY_LVC3_SDA_R"
				( objectStatus "@baseboard_fab2_lib.baseboard_fab2(sch_1):smb_vr_stby_lvc3_sda_r" )
			)
			( signal "SPI_BMC_CLK"
				( objectStatus "@baseboard_fab2_lib.baseboard_fab2(sch_1):spi_bmc_clk" )
			)
			( signal "SPI_BMC_CS0_N"
				( objectStatus "@baseboard_fab2_lib.baseboard_fab2(sch_1):spi_bmc_cs0_n" )
			)
			( signal "SPI_BMC_DI"
				( objectStatus "@baseboard_fab2_lib.baseboard_fab2(sch_1):spi_bmc_di" )
			)
			( signal "SPI_BMC_DO"
				( objectStatus "@baseboard_fab2_lib.baseboard_fab2(sch_1):spi_bmc_do" )
			)
			( signal "TP_DACB"
				( objectStatus "@baseboard_fab2_lib.baseboard_fab2(sch_1):tp_dacb" )
			)
			( signal "TP_DACG"
				( objectStatus "@baseboard_fab2_lib.baseboard_fab2(sch_1):tp_dacg" )
			)
			( signal "TP_DACR"
				( objectStatus "@baseboard_fab2_lib.baseboard_fab2(sch_1):tp_dacr" )
			)
			( signal "TP_DDCCLK_GPIOJ6"
				( objectStatus "@baseboard_fab2_lib.baseboard_fab2(sch_1):tp_ddcclk_gpioj6" )
			)
			( signal "TP_DDCDAT_GPIOJ7"
				( objectStatus "@baseboard_fab2_lib.baseboard_fab2(sch_1):tp_ddcdat_gpioj7" )
			)
			( signal "TP_JTAG_BMC_RTCK"
				( objectStatus "@baseboard_fab2_lib.baseboard_fab2(sch_1):tp_jtag_bmc_rtck" )
			)
			( signal "TP_SPI_PCH_BIOS_CLK_R"
				( objectStatus "@baseboard_fab2_lib.baseboard_fab2(sch_1):tp_spi_pch_bios_clk_r" )
			)
			( signal "TP_SPI_PCH_BIOS_CS0_R_N"
				( objectStatus "@baseboard_fab2_lib.baseboard_fab2(sch_1):tp_spi_pch_bios_cs0_r_n" )
			)
			( signal "TP_SPI_PCH_BIOS_MISO_R"
				( objectStatus "@baseboard_fab2_lib.baseboard_fab2(sch_1):tp_spi_pch_bios_miso_r" )
			)
			( signal "TP_SPI_PCH_BIOS_MOSI_R"
				( objectStatus "@baseboard_fab2_lib.baseboard_fab2(sch_1):tp_spi_pch_bios_mosi_r" )
			)
			( signal "TP_VGAHS_GPIOJ4"
				( objectStatus "@baseboard_fab2_lib.baseboard_fab2(sch_1):tp_vgahs_gpioj4" )
			)
			( signal "TP_VGAVS_GPIOJ5"
				( objectStatus "@baseboard_fab2_lib.baseboard_fab2(sch_1):tp_vgavs_gpioj5" )
			)
			( signal "CLK_24M_25M_BMC_CLKIN"
				( objectStatus "@baseboard_fab2_lib.baseboard_fab2(sch_1):clk_24m_25m_bmc_clkin" )
			)
			( signal "CLK_24M_BMC_CLKIN_R"
				( objectStatus "@baseboard_fab2_lib.baseboard_fab2(sch_1):clk_24m_bmc_clkin_r" )
			)
			( signal "FM_BMC_ONCTL_N"
				( objectStatus "@baseboard_fab2_lib.baseboard_fab2(sch_1):fm_bmc_onctl_n" )
			)
			( signal "FM_BMC_ONCTL_R_N"
				( objectStatus "@baseboard_fab2_lib.baseboard_fab2(sch_1):fm_bmc_onctl_r_n" )
			)
			( signal "FM_BMC_PWRBTN_OUT_N"
				( objectStatus "@baseboard_fab2_lib.baseboard_fab2(sch_1):fm_bmc_pwrbtn_out_n" )
			)
			( signal "FM_BMC_SYS_THROTTLE_R_N"
				( objectStatus "@baseboard_fab2_lib.baseboard_fab2(sch_1):fm_bmc_sys_throttle_r_n" )
			)
			( signal "FM_CPU0_FIVR_FAULT_LVT3_R_N"
				( objectStatus "@baseboard_fab2_lib.baseboard_fab2(sch_1):fm_cpu0_fivr_fault_lvt3_r_n" )
			)
			( signal "FM_CPU1_FIVR_FAULT_LVT3_R_N"
				( objectStatus "@baseboard_fab2_lib.baseboard_fab2(sch_1):fm_cpu1_fivr_fault_lvt3_r_n" )
			)
			( signal "H_CPU0_MEMABC_MEMHOT_LVT3_BMC_N"
				( objectStatus "@baseboard_fab2_lib.baseboard_fab2(sch_1):h_cpu0_memabc_memhot_lvt3_bmc_n" )
			)
			( signal "H_CPU0_MEMDEF_MEMHOT_LVT3_BMC_N"
				( objectStatus "@baseboard_fab2_lib.baseboard_fab2(sch_1):h_cpu0_memdef_memhot_lvt3_bmc_n" )
			)
			( signal "H_CPU1_MEMGHJ_MEMHOT_LVT3_BMC_N"
				( objectStatus "@baseboard_fab2_lib.baseboard_fab2(sch_1):h_cpu1_memghj_memhot_lvt3_bmc_n" )
			)
			( signal "H_CPU1_MEMKLM_MEMHOT_LVT3_BMC_N"
				( objectStatus "@baseboard_fab2_lib.baseboard_fab2(sch_1):h_cpu1_memklm_memhot_lvt3_bmc_n" )
			)
			( signal "P2E_SSB_BMC_RX_DN"
				( objectStatus "@baseboard_fab2_lib.baseboard_fab2(sch_1):p2e_ssb_bmc_rx_dn" )
			)
			( signal "P2E_SSB_BMC_RX_DP"
				( objectStatus "@baseboard_fab2_lib.baseboard_fab2(sch_1):p2e_ssb_bmc_rx_dp" )
			)
			( signal "PD_PEREXT"
				( objectStatus "@baseboard_fab2_lib.baseboard_fab2(sch_1):pd_perext" )
			)
			( signal "PD_SP_ENTEST"
				( objectStatus "@baseboard_fab2_lib.baseboard_fab2(sch_1):pd_sp_entest" )
			)
			( signal "PECI_BMC"
				( objectStatus "@baseboard_fab2_lib.baseboard_fab2(sch_1):peci_bmc" )
			)
			( signal "PECI_BMC_R"
				( objectStatus "@baseboard_fab2_lib.baseboard_fab2(sch_1):peci_bmc_r" )
			)
			( signal "PU_24M_OSC_OE"
				( objectStatus "@baseboard_fab2_lib.baseboard_fab2(sch_1):pu_24m_osc_oe" )
			)
			( signal "RST_BMC_SYSRST_BTN_OUT_N"
				( objectStatus "@baseboard_fab2_lib.baseboard_fab2(sch_1):rst_bmc_sysrst_btn_out_n" )
			)
			( signal "SP1_BMC_HOST_UART_RX"
				( objectStatus "@baseboard_fab2_lib.baseboard_fab2(sch_1):sp1_bmc_host_uart_rx" )
			)
			( signal "SP1_BMC_HOST_UART_TX"
				( objectStatus "@baseboard_fab2_lib.baseboard_fab2(sch_1):sp1_bmc_host_uart_tx" )
			)
			( signal "TP_GPIOE7_RXD3"
				( objectStatus "@baseboard_fab2_lib.baseboard_fab2(sch_1):tp_gpioe7_rxd3" )
			)
			( signal "TP_GPIOM5_NRTS2_VPIB7"
				( objectStatus "@baseboard_fab2_lib.baseboard_fab2(sch_1):tp_gpiom5_nrts2_vpib7" )
			)
			( signal "UART_BMC_RXD5"
				( objectStatus "@baseboard_fab2_lib.baseboard_fab2(sch_1):uart_bmc_rxd5" )
			)
			( signal "UART_BMC_TXD5"
				( objectStatus "@baseboard_fab2_lib.baseboard_fab2(sch_1):uart_bmc_txd5" )
			)
			( signal "FM_FLASH_DESC_OVERRIDE_R"
				( objectStatus "@baseboard_fab2_lib.baseboard_fab2(sch_1):fm_flash_desc_override_r" )
			)
			( signal "FM_ROMA<1>"
				( objectStatus "@baseboard_fab2_lib.baseboard_fab2(sch_1):fm_roma(1)" )
			)
			( signal "FM_ROMA<2>"
				( objectStatus "@baseboard_fab2_lib.baseboard_fab2(sch_1):fm_roma(2)" )
			)
			( signal "FM_ROMA<3>"
				( objectStatus "@baseboard_fab2_lib.baseboard_fab2(sch_1):fm_roma(3)" )
			)
			( signal "FM_ROMA<4>"
				( objectStatus "@baseboard_fab2_lib.baseboard_fab2(sch_1):fm_roma(4)" )
			)
			( signal "FM_ROMA<5>"
				( objectStatus "@baseboard_fab2_lib.baseboard_fab2(sch_1):fm_roma(5)" )
			)
			( signal "FM_ROMA<6>"
				( objectStatus "@baseboard_fab2_lib.baseboard_fab2(sch_1):fm_roma(6)" )
			)
			( signal "FM_ROMA<7>"
				( objectStatus "@baseboard_fab2_lib.baseboard_fab2(sch_1):fm_roma(7)" )
			)
			( signal "FM_ROMA<8>"
				( objectStatus "@baseboard_fab2_lib.baseboard_fab2(sch_1):fm_roma(8)" )
			)
			( signal "FM_ROMA<9>"
				( objectStatus "@baseboard_fab2_lib.baseboard_fab2(sch_1):fm_roma(9)" )
			)
			( signal "FM_ROMA<10>"
				( objectStatus "@baseboard_fab2_lib.baseboard_fab2(sch_1):fm_roma(10)" )
			)
			( signal "FM_ROMA<11>"
				( objectStatus "@baseboard_fab2_lib.baseboard_fab2(sch_1):fm_roma(11)" )
			)
			( signal "FM_ROMA<12>"
				( objectStatus "@baseboard_fab2_lib.baseboard_fab2(sch_1):fm_roma(12)" )
			)
			( signal "FM_ROMA<13>"
				( objectStatus "@baseboard_fab2_lib.baseboard_fab2(sch_1):fm_roma(13)" )
			)
			( signal "FM_ROMA<14>"
				( objectStatus "@baseboard_fab2_lib.baseboard_fab2(sch_1):fm_roma(14)" )
			)
			( signal "FM_ROMA<15>"
				( objectStatus "@baseboard_fab2_lib.baseboard_fab2(sch_1):fm_roma(15)" )
			)
			( signal "FM_ROMA<16>"
				( objectStatus "@baseboard_fab2_lib.baseboard_fab2(sch_1):fm_roma(16)" )
			)
			( signal "FM_ROMA<17>"
				( objectStatus "@baseboard_fab2_lib.baseboard_fab2(sch_1):fm_roma(17)" )
			)
			( signal "FM_ROMA<18>"
				( objectStatus "@baseboard_fab2_lib.baseboard_fab2(sch_1):fm_roma(18)" )
			)
			( signal "FM_ROMA<19>"
				( objectStatus "@baseboard_fab2_lib.baseboard_fab2(sch_1):fm_roma(19)" )
			)
			( signal "FM_ROMA<20>"
				( objectStatus "@baseboard_fab2_lib.baseboard_fab2(sch_1):fm_roma(20)" )
			)
			( signal "FM_ROMA<21>"
				( objectStatus "@baseboard_fab2_lib.baseboard_fab2(sch_1):fm_roma(21)" )
			)
			( signal "FM_ROMA<22>"
				( objectStatus "@baseboard_fab2_lib.baseboard_fab2(sch_1):fm_roma(22)" )
			)
			( signal "FM_ROMA<23>"
				( objectStatus "@baseboard_fab2_lib.baseboard_fab2(sch_1):fm_roma(23)" )
			)
			( signal "SPI_BMC_BT_CLK"
				( objectStatus "@baseboard_fab2_lib.baseboard_fab2(sch_1):spi_bmc_bt_clk" )
			)
			( signal "SPI_BMC_BT_CLK_R"
				( objectStatus "@baseboard_fab2_lib.baseboard_fab2(sch_1):spi_bmc_bt_clk_r" )
			)
			( signal "SPI_BMC_BT_CS_N"
				( objectStatus "@baseboard_fab2_lib.baseboard_fab2(sch_1):spi_bmc_bt_cs_n" )
			)
			( signal "SPI_BMC_BT_CS_R_N"
				( objectStatus "@baseboard_fab2_lib.baseboard_fab2(sch_1):spi_bmc_bt_cs_r_n" )
			)
			( signal "SPI_BMC_BT_DI"
				( objectStatus "@baseboard_fab2_lib.baseboard_fab2(sch_1):spi_bmc_bt_di" )
			)
			( signal "SPI_BMC_BT_DO"
				( objectStatus "@baseboard_fab2_lib.baseboard_fab2(sch_1):spi_bmc_bt_do" )
			)
			( signal "SPI_BMC_BT_DO_R"
				( objectStatus "@baseboard_fab2_lib.baseboard_fab2(sch_1):spi_bmc_bt_do_r" )
			)
			( signal "TP_GPIOR5_ROMA25_VPOR7"
				( objectStatus "@baseboard_fab2_lib.baseboard_fab2(sch_1):tp_gpior5_roma25_vpor7" )
			)
			( signal "TP_SPI_BMC_BT_D2"
				( objectStatus "@baseboard_fab2_lib.baseboard_fab2(sch_1):tp_spi_bmc_bt_d2" )
			)
			( signal "A_P12V_STBY_SCALED"
				( attribute "VOLTAGE" "+2V"
					( Units "uVoltage" "V" 1.000000)
					( Status sAliasFlattened )
					( Origin gFrontEnd )
				)
				( objectStatus "@baseboard_fab2_lib.baseboard_fab2(sch_1):a_p12v_stby_scaled" )
			)
			( signal "A_P1V05_STBY_PCH_SENSOR"
				( attribute "VOLTAGE" "+1.2V"
					( Units "uVoltage" "V" 1.000000)
					( Status sAliasFlattened )
					( Origin gFrontEnd )
				)
				( objectStatus "@baseboard_fab2_lib.baseboard_fab2(sch_1):a_p1v05_stby_pch_sensor" )
			)
			( signal "A_P3V3_SCALED"
				( attribute "VOLTAGE" "+2V"
					( Units "uVoltage" "V" 1.000000)
					( Status sAliasFlattened )
					( Origin gFrontEnd )
				)
				( objectStatus "@baseboard_fab2_lib.baseboard_fab2(sch_1):a_p3v3_scaled" )
			)
			( signal "A_P3V3_STBY_SCALED"
				( attribute "VOLTAGE" "+1.8V"
					( Units "uVoltage" "V" 1.000000)
					( Status sAliasFlattened )
					( Origin gFrontEnd )
				)
				( objectStatus "@baseboard_fab2_lib.baseboard_fab2(sch_1):a_p3v3_stby_scaled" )
			)
			( signal "A_P3V_BAT_SCALED"
				( attribute "VOLTAGE" "+1V"
					( Units "uVoltage" "V" 1.000000)
					( Status sAliasFlattened )
					( Origin gFrontEnd )
				)
				( objectStatus "@baseboard_fab2_lib.baseboard_fab2(sch_1):a_p3v_bat_scaled" )
			)
			( signal "A_P5V_SCALED"
				( attribute "VOLTAGE" "+2V"
					( Units "uVoltage" "V" 1.000000)
					( Status sAliasFlattened )
					( Origin gFrontEnd )
				)
				( objectStatus "@baseboard_fab2_lib.baseboard_fab2(sch_1):a_p5v_scaled" )
			)
			( signal "A_P5V_STBY_SCALED"
				( attribute "VOLTAGE" "+2V"
					( Units "uVoltage" "V" 1.000000)
					( Status sAliasFlattened )
					( Origin gFrontEnd )
				)
				( objectStatus "@baseboard_fab2_lib.baseboard_fab2(sch_1):a_p5v_stby_scaled" )
			)
			( signal "A_PVNN_STBY_PCH_SENSOR"
				( attribute "VOLTAGE" "+1.2V"
					( Units "uVoltage" "V" 1.000000)
					( Status sAliasFlattened )
					( Origin gFrontEnd )
				)
				( objectStatus "@baseboard_fab2_lib.baseboard_fab2(sch_1):a_pvnn_stby_pch_sensor" )
			)
			( signal "FM_BIOS_SPI_BMC_CTRL"
				( objectStatus "@baseboard_fab2_lib.baseboard_fab2(sch_1):fm_bios_spi_bmc_ctrl" )
			)
			( signal "FM_HEARTBEAT_LED"
				( objectStatus "@baseboard_fab2_lib.baseboard_fab2(sch_1):fm_heartbeat_led" )
			)
			( signal "FM_HEARTBEAT_LED_A"
				( objectStatus "@baseboard_fab2_lib.baseboard_fab2(sch_1):fm_heartbeat_led_a" )
			)
			( signal "FM_HEARTBEAT_LED_K"
				( objectStatus "@baseboard_fab2_lib.baseboard_fab2(sch_1):fm_heartbeat_led_k" )
			)
			( signal "P3V3_STBY_BMC_ADCAV33"
				( attribute "VOLTAGE" "+3.3V"
					( Units "uVoltage" "V" 1.000000)
					( Status sAliasFlattened )
					( Origin gFrontEnd )
				)
				( objectStatus "@baseboard_fab2_lib.baseboard_fab2(sch_1):p3v3_stby_bmc_adcav33" )
			)
			( signal "P3V3_STBY_BMC_ADCVREFN"
				( attribute "VOLTAGE" "+3.3V"
					( Units "uVoltage" "V" 1.000000)
					( Status sAliasFlattened )
					( Origin gFrontEnd )
				)
				( objectStatus "@baseboard_fab2_lib.baseboard_fab2(sch_1):p3v3_stby_bmc_adcvrefn" )
			)
			( signal "P3V3_STBY_BMC_ADCVREFP"
				( attribute "VOLTAGE" "+3.3V"
					( Units "uVoltage" "V" 1.000000)
					( Status sAliasFlattened )
					( Origin gFrontEnd )
				)
				( objectStatus "@baseboard_fab2_lib.baseboard_fab2(sch_1):p3v3_stby_bmc_adcvrefp" )
			)
			( signal "PD_ADCREXT"
				( objectStatus "@baseboard_fab2_lib.baseboard_fab2(sch_1):pd_adcrext" )
			)
			( signal "RMII_BMC_OCP_CRSDV"
				( objectStatus "@baseboard_fab2_lib.baseboard_fab2(sch_1):rmii_bmc_ocp_crsdv" )
			)
			( signal "RMII_BMC_OCP_RXD0"
				( objectStatus "@baseboard_fab2_lib.baseboard_fab2(sch_1):rmii_bmc_ocp_rxd0" )
			)
			( signal "RMII_BMC_OCP_RXD1"
				( objectStatus "@baseboard_fab2_lib.baseboard_fab2(sch_1):rmii_bmc_ocp_rxd1" )
			)
			( signal "RMII_BMC_OCP_RXER"
				( objectStatus "@baseboard_fab2_lib.baseboard_fab2(sch_1):rmii_bmc_ocp_rxer" )
			)
			( signal "RMII_BMC_OCP_TXD0"
				( objectStatus "@baseboard_fab2_lib.baseboard_fab2(sch_1):rmii_bmc_ocp_txd0" )
			)
			( signal "RMII_BMC_OCP_TXD0_R"
				( objectStatus "@baseboard_fab2_lib.baseboard_fab2(sch_1):rmii_bmc_ocp_txd0_r" )
			)
			( signal "RMII_BMC_OCP_TXD1"
				( objectStatus "@baseboard_fab2_lib.baseboard_fab2(sch_1):rmii_bmc_ocp_txd1" )
			)
			( signal "RMII_BMC_OCP_TXD1_R"
				( objectStatus "@baseboard_fab2_lib.baseboard_fab2(sch_1):rmii_bmc_ocp_txd1_r" )
			)
			( signal "RMII_BMC_OCP_TXEN"
				( objectStatus "@baseboard_fab2_lib.baseboard_fab2(sch_1):rmii_bmc_ocp_txen" )
			)
			( signal "RMII_BMC_OCP_TXEN_R"
				( objectStatus "@baseboard_fab2_lib.baseboard_fab2(sch_1):rmii_bmc_ocp_txen_r" )
			)
			( signal "RMII_BMC_PCH_SPRNGVLLE_TXD0_R"
				( objectStatus "@baseboard_fab2_lib.baseboard_fab2(sch_1):rmii_bmc_pch_sprngvlle_txd0_r" )
			)
			( signal "RMII_BMC_PCH_SPRNGVLLE_TXD1_R"
				( objectStatus "@baseboard_fab2_lib.baseboard_fab2(sch_1):rmii_bmc_pch_sprngvlle_txd1_r" )
			)
			( signal "RMII_BMC_SPRNGVLLE_TXEN_R"
				( objectStatus "@baseboard_fab2_lib.baseboard_fab2(sch_1):rmii_bmc_sprngvlle_txen_r" )
			)
			( signal "TP_RGMII1TXCTL_GPIOT1"
				( objectStatus "@baseboard_fab2_lib.baseboard_fab2(sch_1):tp_rgmii1txctl_gpiot1" )
			)
			( signal "TP_RGMII1TXD2_GPIOT4"
				( objectStatus "@baseboard_fab2_lib.baseboard_fab2(sch_1):tp_rgmii1txd2_gpiot4" )
			)
			( signal "TP_RGMII1TXD3_GPIOT5"
				( objectStatus "@baseboard_fab2_lib.baseboard_fab2(sch_1):tp_rgmii1txd3_gpiot5" )
			)
			( signal "TP_RGMII2TXCTL_GPIOT7"
				( objectStatus "@baseboard_fab2_lib.baseboard_fab2(sch_1):tp_rgmii2txctl_gpiot7" )
			)
			( signal "TP_RGMII2TXD2_GPIOT4"
				( objectStatus "@baseboard_fab2_lib.baseboard_fab2(sch_1):tp_rgmii2txd2_gpiot4" )
			)
			( signal "TP_RGMII2TXD3_GPIOT5"
				( objectStatus "@baseboard_fab2_lib.baseboard_fab2(sch_1):tp_rgmii2txd3_gpiot5" )
			)
			( signal "P1V26_BMC_STBY"
				( attribute "VOLTAGE" "1.26V"
					( Units "uVoltage" "V" 1.000000)
					( Status sAliasFlattened )
					( Origin gFrontEnd )
				)
				( objectStatus "@baseboard_fab2_lib.baseboard_fab2(sch_1):p1v26_bmc_stby" )
			)
			( signal "P1V26_BMC_STBY_V1PLLAV12"
				( attribute "VOLTAGE" "+1.26V"
					( Units "uVoltage" "V" 1.000000)
					( Status sAliasFlattened )
					( Origin gFrontEnd )
				)
				( objectStatus "@baseboard_fab2_lib.baseboard_fab2(sch_1):p1v26_bmc_stby_v1pllav12" )
			)
			( signal "P1V538_BMC_STBY"
				( attribute "VOLTAGE" "1.538V"
					( Units "uVoltage" "V" 1.000000)
					( Status sAliasFlattened )
					( Origin gFrontEnd )
				)
				( objectStatus "@baseboard_fab2_lib.baseboard_fab2(sch_1):p1v538_bmc_stby" )
			)
			( signal "P1V8_BMC_STBY_PCIE"
				( attribute "VOLTAGE" "+1.8V"
					( Units "uVoltage" "V" 1.000000)
					( Status sAliasFlattened )
					( Origin gFrontEnd )
				)
				( objectStatus "@baseboard_fab2_lib.baseboard_fab2(sch_1):p1v8_bmc_stby_pcie" )
			)
			( signal "P1V8_BMC_STBY_PCIEA"
				( attribute "VOLTAGE" "+1.8V"
					( Units "uVoltage" "V" 1.000000)
					( Status sAliasFlattened )
					( Origin gFrontEnd )
				)
				( objectStatus "@baseboard_fab2_lib.baseboard_fab2(sch_1):p1v8_bmc_stby_pciea" )
			)
			( signal "P3V3_STBY_BMC_HPLLAV33"
				( attribute "VOLTAGE" "+3.3V"
					( Units "uVoltage" "V" 1.000000)
					( Status sAliasFlattened )
					( Origin gFrontEnd )
				)
				( objectStatus "@baseboard_fab2_lib.baseboard_fab2(sch_1):p3v3_stby_bmc_hpllav33" )
			)
			( signal "A_M_BMC_ZQ"
				( objectStatus "@baseboard_fab2_lib.baseboard_fab2(sch_1):a_m_bmc_zq" )
			)
			( signal "RST_BMC_DDR3_BUF_IN_N"
				( objectStatus "@baseboard_fab2_lib.baseboard_fab2(sch_1):rst_bmc_ddr3_buf_in_n" )
			)
			( signal "RST_BMC_DDR3_N"
				( objectStatus "@baseboard_fab2_lib.baseboard_fab2(sch_1):rst_bmc_ddr3_n" )
			)
			( signal "RST_BMC_DDR3_R_N"
				( objectStatus "@baseboard_fab2_lib.baseboard_fab2(sch_1):rst_bmc_ddr3_r_n" )
			)
			( signal "TP_K4B1G16_BMC_NC0"
				( objectStatus "@baseboard_fab2_lib.baseboard_fab2(sch_1):tp_k4b1g16_bmc_nc0" )
			)
			( signal "TP_K4B1G16_BMC_NC1"
				( objectStatus "@baseboard_fab2_lib.baseboard_fab2(sch_1):tp_k4b1g16_bmc_nc1" )
			)
			( signal "TP_K4B1G16_BMC_NC2"
				( objectStatus "@baseboard_fab2_lib.baseboard_fab2(sch_1):tp_k4b1g16_bmc_nc2" )
			)
			( signal "TP_K4B1G16_BMC_NC3"
				( objectStatus "@baseboard_fab2_lib.baseboard_fab2(sch_1):tp_k4b1g16_bmc_nc3" )
			)
			( signal "TP_K4B1G16_BMC_NC4"
				( objectStatus "@baseboard_fab2_lib.baseboard_fab2(sch_1):tp_k4b1g16_bmc_nc4" )
			)
			( signal "H_CPU0_ABC_MEMHOT_LVT3_R_N"
				( objectStatus "@baseboard_fab2_lib.baseboard_fab2(sch_1):h_cpu0_abc_memhot_lvt3_r_n" )
			)
			( signal "H_CPU0_DEF_MEMHOT_LVT3_R_N"
				( objectStatus "@baseboard_fab2_lib.baseboard_fab2(sch_1):h_cpu0_def_memhot_lvt3_r_n" )
			)
			( signal "H_CPU0_MEMABC_MEMHOT_G_PCH_N"
				( objectStatus "@baseboard_fab2_lib.baseboard_fab2(sch_1):h_cpu0_memabc_memhot_g_pch_n" )
			)
			( signal "H_CPU0_MEMABC_MEMHOT_G_R_N"
				( objectStatus "@baseboard_fab2_lib.baseboard_fab2(sch_1):h_cpu0_memabc_memhot_g_r_n" )
			)
			( signal "H_CPU0_MEMABC_MEMHOT_LVT3_K_N"
				( objectStatus "@baseboard_fab2_lib.baseboard_fab2(sch_1):h_cpu0_memabc_memhot_lvt3_k_n" )
			)
			( signal "H_CPU0_MEMABC_MEMHOT_LVT3_N"
				( objectStatus "@baseboard_fab2_lib.baseboard_fab2(sch_1):h_cpu0_memabc_memhot_lvt3_n" )
			)
			( signal "H_CPU0_MEMDEF_MEMHOT_G_PCH_N"
				( objectStatus "@baseboard_fab2_lib.baseboard_fab2(sch_1):h_cpu0_memdef_memhot_g_pch_n" )
			)
			( signal "H_CPU0_MEMDEF_MEMHOT_G_R_N"
				( objectStatus "@baseboard_fab2_lib.baseboard_fab2(sch_1):h_cpu0_memdef_memhot_g_r_n" )
			)
			( signal "H_CPU0_MEMDEF_MEMHOT_LVT3_K_N"
				( objectStatus "@baseboard_fab2_lib.baseboard_fab2(sch_1):h_cpu0_memdef_memhot_lvt3_k_n" )
			)
			( signal "H_CPU0_MEMDEF_MEMHOT_LVT3_N"
				( objectStatus "@baseboard_fab2_lib.baseboard_fab2(sch_1):h_cpu0_memdef_memhot_lvt3_n" )
			)
			( signal "H_CPU1_GHJ_MEMHOT_LVT3_R_N"
				( objectStatus "@baseboard_fab2_lib.baseboard_fab2(sch_1):h_cpu1_ghj_memhot_lvt3_r_n" )
			)
			( signal "H_CPU1_KLM_MEMHOT_LVT3_R_N"
				( objectStatus "@baseboard_fab2_lib.baseboard_fab2(sch_1):h_cpu1_klm_memhot_lvt3_r_n" )
			)
			( signal "H_CPU1_MEMGHJ_MEMHOT_G_PCH_N"
				( objectStatus "@baseboard_fab2_lib.baseboard_fab2(sch_1):h_cpu1_memghj_memhot_g_pch_n" )
			)
			( signal "H_CPU1_MEMGHJ_MEMHOT_G_R_N"
				( objectStatus "@baseboard_fab2_lib.baseboard_fab2(sch_1):h_cpu1_memghj_memhot_g_r_n" )
			)
			( signal "H_CPU1_MEMGHJ_MEMHOT_LVT3_K_N"
				( objectStatus "@baseboard_fab2_lib.baseboard_fab2(sch_1):h_cpu1_memghj_memhot_lvt3_k_n" )
			)
			( signal "H_CPU1_MEMGHJ_MEMHOT_LVT3_N"
				( objectStatus "@baseboard_fab2_lib.baseboard_fab2(sch_1):h_cpu1_memghj_memhot_lvt3_n" )
			)
			( signal "H_CPU1_MEMKLM_MEMHOT_G_PCH_N"
				( objectStatus "@baseboard_fab2_lib.baseboard_fab2(sch_1):h_cpu1_memklm_memhot_g_pch_n" )
			)
			( signal "H_CPU1_MEMKLM_MEMHOT_G_R_N"
				( objectStatus "@baseboard_fab2_lib.baseboard_fab2(sch_1):h_cpu1_memklm_memhot_g_r_n" )
			)
			( signal "H_CPU1_MEMKLM_MEMHOT_LVT3_K_N"
				( objectStatus "@baseboard_fab2_lib.baseboard_fab2(sch_1):h_cpu1_memklm_memhot_lvt3_k_n" )
			)
			( signal "H_CPU1_MEMKLM_MEMHOT_LVT3_N"
				( objectStatus "@baseboard_fab2_lib.baseboard_fab2(sch_1):h_cpu1_memklm_memhot_lvt3_n" )
			)
			( signal "P0V7_GTL2014_2"
				( attribute "VOLTAGE" "+0.7"
					( Units "uVoltage" "V" 1.000000)
					( Status sAliasFlattened )
					( Origin gFrontEnd )
				)
				( objectStatus "@baseboard_fab2_lib.baseboard_fab2(sch_1):p0v7_gtl2014_2" )
			)
			( signal "PD_DIR_2"
				( objectStatus "@baseboard_fab2_lib.baseboard_fab2(sch_1):pd_dir_2" )
			)
			( signal "PU_BIOS_SPI_HOLD0_N"
				( objectStatus "@baseboard_fab2_lib.baseboard_fab2(sch_1):pu_bios_spi_hold0_n" )
			)
			( signal "PU_BIOS_SPI_HOLD1_N"
				( objectStatus "@baseboard_fab2_lib.baseboard_fab2(sch_1):pu_bios_spi_hold1_n" )
			)
			( signal "PU_BIOS_SPI_WP0_N"
				( objectStatus "@baseboard_fab2_lib.baseboard_fab2(sch_1):pu_bios_spi_wp0_n" )
			)
			( signal "PU_BIOS_SPI_WP1_N"
				( objectStatus "@baseboard_fab2_lib.baseboard_fab2(sch_1):pu_bios_spi_wp1_n" )
			)
			( signal "PU_SPI0_RST"
				( objectStatus "@baseboard_fab2_lib.baseboard_fab2(sch_1):pu_spi0_rst" )
			)
			( signal "PU_SPI1_RST"
				( objectStatus "@baseboard_fab2_lib.baseboard_fab2(sch_1):pu_spi1_rst" )
			)
			( signal "SPI_BIOS_SOCKET_IO2"
				( objectStatus "@baseboard_fab2_lib.baseboard_fab2(sch_1):spi_bios_socket_io2" )
			)
			( signal "SPI_BIOS_SOCKET_IO3"
				( objectStatus "@baseboard_fab2_lib.baseboard_fab2(sch_1):spi_bios_socket_io3" )
			)
			( signal "SPI_CLK_R0"
				( objectStatus "@baseboard_fab2_lib.baseboard_fab2(sch_1):spi_clk_r0" )
			)
			( signal "SPI_CLK_R1"
				( objectStatus "@baseboard_fab2_lib.baseboard_fab2(sch_1):spi_clk_r1" )
			)
			( signal "SPI_CS0_PRIMARY_R_N"
				( objectStatus "@baseboard_fab2_lib.baseboard_fab2(sch_1):spi_cs0_primary_r_n" )
			)
			( signal "SPI_CS0_SECONDARY_R_N"
				( objectStatus "@baseboard_fab2_lib.baseboard_fab2(sch_1):spi_cs0_secondary_r_n" )
			)
			( signal "SPI_MISO_R0"
				( objectStatus "@baseboard_fab2_lib.baseboard_fab2(sch_1):spi_miso_r0" )
			)
			( signal "SPI_MISO_R1"
				( objectStatus "@baseboard_fab2_lib.baseboard_fab2(sch_1):spi_miso_r1" )
			)
			( signal "SPI_SWITCH_CLK"
				( objectStatus "@baseboard_fab2_lib.baseboard_fab2(sch_1):spi_switch_clk" )
			)
			( signal "SPI_SWITCH_MISO"
				( objectStatus "@baseboard_fab2_lib.baseboard_fab2(sch_1):spi_switch_miso" )
			)
			( signal "SPI_SWITCH_MOSI"
				( objectStatus "@baseboard_fab2_lib.baseboard_fab2(sch_1):spi_switch_mosi" )
			)
			( signal "SPI_SWITCH_MOSI_R0"
				( objectStatus "@baseboard_fab2_lib.baseboard_fab2(sch_1):spi_switch_mosi_r0" )
			)
			( signal "SPI_SWITCH_MOSI_R1"
				( objectStatus "@baseboard_fab2_lib.baseboard_fab2(sch_1):spi_switch_mosi_r1" )
			)
			( signal "TP_SPI_0_0"
				( objectStatus "@baseboard_fab2_lib.baseboard_fab2(sch_1):tp_spi_0_0" )
			)
			( signal "TP_SPI_0_1"
				( objectStatus "@baseboard_fab2_lib.baseboard_fab2(sch_1):tp_spi_0_1" )
			)
			( signal "TP_SPI_0_2"
				( objectStatus "@baseboard_fab2_lib.baseboard_fab2(sch_1):tp_spi_0_2" )
			)
			( signal "TP_SPI_0_3"
				( objectStatus "@baseboard_fab2_lib.baseboard_fab2(sch_1):tp_spi_0_3" )
			)
			( signal "TP_SPI_0_4"
				( objectStatus "@baseboard_fab2_lib.baseboard_fab2(sch_1):tp_spi_0_4" )
			)
			( signal "TP_SPI_0_5"
				( objectStatus "@baseboard_fab2_lib.baseboard_fab2(sch_1):tp_spi_0_5" )
			)
			( signal "TP_SPI_0_6"
				( objectStatus "@baseboard_fab2_lib.baseboard_fab2(sch_1):tp_spi_0_6" )
			)
			( signal "TP_SPI_1_0"
				( objectStatus "@baseboard_fab2_lib.baseboard_fab2(sch_1):tp_spi_1_0" )
			)
			( signal "TP_SPI_1_1"
				( objectStatus "@baseboard_fab2_lib.baseboard_fab2(sch_1):tp_spi_1_1" )
			)
			( signal "TP_SPI_1_2"
				( objectStatus "@baseboard_fab2_lib.baseboard_fab2(sch_1):tp_spi_1_2" )
			)
			( signal "TP_SPI_1_3"
				( objectStatus "@baseboard_fab2_lib.baseboard_fab2(sch_1):tp_spi_1_3" )
			)
			( signal "TP_SPI_1_4"
				( objectStatus "@baseboard_fab2_lib.baseboard_fab2(sch_1):tp_spi_1_4" )
			)
			( signal "TP_SPI_1_5"
				( objectStatus "@baseboard_fab2_lib.baseboard_fab2(sch_1):tp_spi_1_5" )
			)
			( signal "TP_SPI_1_6"
				( objectStatus "@baseboard_fab2_lib.baseboard_fab2(sch_1):tp_spi_1_6" )
			)
			( signal "FM_DUAL_BIOS_SEL_N"
				( objectStatus "@baseboard_fab2_lib.baseboard_fab2(sch_1):fm_dual_bios_sel_n" )
			)
			( signal "SPI_CS0_PRIMARY_N"
				( objectStatus "@baseboard_fab2_lib.baseboard_fab2(sch_1):spi_cs0_primary_n" )
			)
			( signal "SPI_CS0_SECONDARY_N"
				( objectStatus "@baseboard_fab2_lib.baseboard_fab2(sch_1):spi_cs0_secondary_n" )
			)
			( signal "SPI_PCH_IO2_R1"
				( objectStatus "@baseboard_fab2_lib.baseboard_fab2(sch_1):spi_pch_io2_r1" )
			)
			( signal "SPI_PCH_IO3_R1"
				( objectStatus "@baseboard_fab2_lib.baseboard_fab2(sch_1):spi_pch_io3_r1" )
			)
			( signal "SPI_PCH_MISO_R"
				( objectStatus "@baseboard_fab2_lib.baseboard_fab2(sch_1):spi_pch_miso_r" )
			)
			( signal "SPI_SWITCH_CS0_N"
				( objectStatus "@baseboard_fab2_lib.baseboard_fab2(sch_1):spi_switch_cs0_n" )
			)
			( signal "TP_SPI_SWITCH1_10"
				( objectStatus "@baseboard_fab2_lib.baseboard_fab2(sch_1):tp_spi_switch1_10" )
			)
			( signal "TP_SPI_SWITCH1_11"
				( objectStatus "@baseboard_fab2_lib.baseboard_fab2(sch_1):tp_spi_switch1_11" )
			)
			( signal "TP_SPI_SWITCH1_12"
				( objectStatus "@baseboard_fab2_lib.baseboard_fab2(sch_1):tp_spi_switch1_12" )
			)
			( signal "TP_SPI_SWITCH1_13"
				( objectStatus "@baseboard_fab2_lib.baseboard_fab2(sch_1):tp_spi_switch1_13" )
			)
			( signal "TP_SPI_SWITCH1_14"
				( objectStatus "@baseboard_fab2_lib.baseboard_fab2(sch_1):tp_spi_switch1_14" )
			)
			( signal "TP_SPI_SWITCH1_3"
				( objectStatus "@baseboard_fab2_lib.baseboard_fab2(sch_1):tp_spi_switch1_3" )
			)
			( signal "TP_SPI_SWITCH1_6"
				( objectStatus "@baseboard_fab2_lib.baseboard_fab2(sch_1):tp_spi_switch1_6" )
			)
			( signal "TP_SPI_SWITCH1_9"
				( objectStatus "@baseboard_fab2_lib.baseboard_fab2(sch_1):tp_spi_switch1_9" )
			)
			( signal "FM_CPLD_DBG_PWR_EN"
				( objectStatus "@baseboard_fab2_lib.baseboard_fab2(sch_1):fm_cpld_dbg_pwr_en" )
			)
			( signal "FM_CPLD_DBG_PWR_EN_N"
				( objectStatus "@baseboard_fab2_lib.baseboard_fab2(sch_1):fm_cpld_dbg_pwr_en_n" )
			)
			( signal "FM_CPLD_DBG_PWR_EN_R_N"
				( objectStatus "@baseboard_fab2_lib.baseboard_fab2(sch_1):fm_cpld_dbg_pwr_en_r_n" )
			)
			( signal "FM_UART_SWITCH_N"
				( objectStatus "@baseboard_fab2_lib.baseboard_fab2(sch_1):fm_uart_switch_n" )
			)
			( signal "LED_POSTCODE_0_R"
				( objectStatus "@baseboard_fab2_lib.baseboard_fab2(sch_1):led_postcode_0_r" )
			)
			( signal "LED_POSTCODE_1_R"
				( objectStatus "@baseboard_fab2_lib.baseboard_fab2(sch_1):led_postcode_1_r" )
			)
			( signal "LED_POSTCODE_2_R"
				( objectStatus "@baseboard_fab2_lib.baseboard_fab2(sch_1):led_postcode_2_r" )
			)
			( signal "LED_POSTCODE_3_R"
				( objectStatus "@baseboard_fab2_lib.baseboard_fab2(sch_1):led_postcode_3_r" )
			)
			( signal "LED_POSTCODE_4_R"
				( objectStatus "@baseboard_fab2_lib.baseboard_fab2(sch_1):led_postcode_4_r" )
			)
			( signal "LED_POSTCODE_5_R"
				( objectStatus "@baseboard_fab2_lib.baseboard_fab2(sch_1):led_postcode_5_r" )
			)
			( signal "LED_POSTCODE_6_R"
				( objectStatus "@baseboard_fab2_lib.baseboard_fab2(sch_1):led_postcode_6_r" )
			)
			( signal "LED_POSTCODE_7_R"
				( objectStatus "@baseboard_fab2_lib.baseboard_fab2(sch_1):led_postcode_7_r" )
			)
			( signal "P12V_STBY"
				( attribute "VOLTAGE" "12.0V"
					( Units "uVoltage" "V" 1.000000)
					( Status sAliasFlattened )
					( Origin gFrontEnd )
				)
				( objectStatus "@baseboard_fab2_lib.baseboard_fab2(sch_1):p12v_stby" )
			)
			( signal "P5V_STBY"
				( attribute "VOLTAGE" "5.0V"
					( Units "uVoltage" "V" 1.000000)
					( Status sAliasFlattened )
					( Status sAliasConflict )
					( Origin gFrontEnd )
				)
				( objectStatus "@baseboard_fab2_lib.baseboard_fab2(sch_1):p5v_stby" )
			)
			( signal "P5V_STBY_DBG"
				( attribute "VOLTAGE" "5"
					( Units "uVoltage" "V" 1.000000)
					( Status sAliasFlattened )
					( Origin gFrontEnd )
				)
				( objectStatus "@baseboard_fab2_lib.baseboard_fab2(sch_1):p5v_stby_dbg" )
			)
			( signal "P5V_STBY_DGB_FS"
				( attribute "VOLTAGE" "5"
					( Units "uVoltage" "V" 1.000000)
					( Status sAliasFlattened )
					( Origin gFrontEnd )
				)
				( objectStatus "@baseboard_fab2_lib.baseboard_fab2(sch_1):p5v_stby_dgb_fs" )
			)
			( signal "SPA_5V_SIN_SW"
				( objectStatus "@baseboard_fab2_lib.baseboard_fab2(sch_1):spa_5v_sin_sw" )
			)
			( signal "SPA_MID_DBG_RX"
				( objectStatus "@baseboard_fab2_lib.baseboard_fab2(sch_1):spa_mid_dbg_rx" )
			)
			( signal "SPA_MID_DBG_TX"
				( objectStatus "@baseboard_fab2_lib.baseboard_fab2(sch_1):spa_mid_dbg_tx" )
			)
			( signal "SPA_SIN_SW_R"
				( objectStatus "@baseboard_fab2_lib.baseboard_fab2(sch_1):spa_sin_sw_r" )
			)
			( signal "FM_BMC_CPU_INIT_N"
				( objectStatus "@baseboard_fab2_lib.baseboard_fab2(sch_1):fm_bmc_cpu_init_n" )
			)
			( signal "FM_PCH_PWRBTN_R_N"
				( objectStatus "@baseboard_fab2_lib.baseboard_fab2(sch_1):fm_pch_pwrbtn_r_n" )
			)
			( signal "H_CPU_BMCINIT_R"
				( objectStatus "@baseboard_fab2_lib.baseboard_fab2(sch_1):h_cpu_bmcinit_r" )
			)
			( signal "RST_BMC_SYSRST_BTN_OUT_B_R_N"
				( objectStatus "@baseboard_fab2_lib.baseboard_fab2(sch_1):rst_bmc_sysrst_btn_out_b_r_n" )
			)
			( signal "FP_NMI_BTN"
				( objectStatus "@baseboard_fab2_lib.baseboard_fab2(sch_1):fp_nmi_btn" )
			)
			( signal "FP_NMI_BTN_OUT_N"
				( objectStatus "@baseboard_fab2_lib.baseboard_fab2(sch_1):fp_nmi_btn_out_n" )
			)
			( signal "FP_NMI_BTN_OUT_R_N"
				( objectStatus "@baseboard_fab2_lib.baseboard_fab2(sch_1):fp_nmi_btn_out_r_n" )
			)
			( signal "FP_NMI_BTN_R_N"
				( objectStatus "@baseboard_fab2_lib.baseboard_fab2(sch_1):fp_nmi_btn_r_n" )
			)
			( signal "H_CPU0_FAST_WAKE"
				( objectStatus "@baseboard_fab2_lib.baseboard_fab2(sch_1):h_cpu0_fast_wake" )
			)
			( signal "H_CPU0_FAST_WAKE_B_N"
				( objectStatus "@baseboard_fab2_lib.baseboard_fab2(sch_1):h_cpu0_fast_wake_b_n" )
			)
			( signal "RST_BMC_SRST_R2_N"
				( objectStatus "@baseboard_fab2_lib.baseboard_fab2(sch_1):rst_bmc_srst_r2_n" )
			)
			( signal "FM_UARTSW_LSB_R_N"
				( objectStatus "@baseboard_fab2_lib.baseboard_fab2(sch_1):fm_uartsw_lsb_r_n" )
			)
			( signal "FM_UARTSW_MSB_R_N"
				( objectStatus "@baseboard_fab2_lib.baseboard_fab2(sch_1):fm_uartsw_msb_r_n" )
			)
			( signal "UART_MUX_IN_R"
				( objectStatus "@baseboard_fab2_lib.baseboard_fab2(sch_1):uart_mux_in_r" )
			)
			( signal "UART_MUX_OUT_R"
				( objectStatus "@baseboard_fab2_lib.baseboard_fab2(sch_1):uart_mux_out_r" )
			)
			( signal "SMB_OCP_LAN_STBY_LVC3_SCL"
				( objectStatus "@baseboard_fab2_lib.baseboard_fab2(sch_1):smb_ocp_lan_stby_lvc3_scl" )
			)
			( signal "SMB_OCP_LAN_STBY_LVC3_SDA"
				( objectStatus "@baseboard_fab2_lib.baseboard_fab2(sch_1):smb_ocp_lan_stby_lvc3_sda" )
			)
			( signal "FAN_PWM_OUT_SYS0_BUF"
				( objectStatus "@baseboard_fab2_lib.baseboard_fab2(sch_1):fan_pwm_out_sys0_buf" )
			)
			( signal "FAN_PWM_OUT_SYS0_R"
				( objectStatus "@baseboard_fab2_lib.baseboard_fab2(sch_1):fan_pwm_out_sys0_r" )
			)
			( signal "FAN_PWM_OUT_SYS1_BUF"
				( objectStatus "@baseboard_fab2_lib.baseboard_fab2(sch_1):fan_pwm_out_sys1_buf" )
			)
			( signal "FAN_PWM_OUT_SYS1_R"
				( objectStatus "@baseboard_fab2_lib.baseboard_fab2(sch_1):fan_pwm_out_sys1_r" )
			)
			( signal "FAN_TACH0_CPU0_D1"
				( objectStatus "@baseboard_fab2_lib.baseboard_fab2(sch_1):fan_tach0_cpu0_d1" )
			)
			( signal "FAN_TACH0_CPU0_D2"
				( objectStatus "@baseboard_fab2_lib.baseboard_fab2(sch_1):fan_tach0_cpu0_d2" )
			)
			( signal "FAN_TACH1_CPU1_D1"
				( objectStatus "@baseboard_fab2_lib.baseboard_fab2(sch_1):fan_tach1_cpu1_d1" )
			)
			( signal "FAN_TACH1_CPU1_D2"
				( objectStatus "@baseboard_fab2_lib.baseboard_fab2(sch_1):fan_tach1_cpu1_d2" )
			)
			( signal "FAN_TACH2_CPU1_D1"
				( objectStatus "@baseboard_fab2_lib.baseboard_fab2(sch_1):fan_tach2_cpu1_d1" )
			)
			( signal "FAN_TACH2_CPU1_D2"
				( objectStatus "@baseboard_fab2_lib.baseboard_fab2(sch_1):fan_tach2_cpu1_d2" )
			)
			( signal "FAN_TACH3_CPU1_D1"
				( objectStatus "@baseboard_fab2_lib.baseboard_fab2(sch_1):fan_tach3_cpu1_d1" )
			)
			( signal "FAN_TACH3_CPU1_D2"
				( objectStatus "@baseboard_fab2_lib.baseboard_fab2(sch_1):fan_tach3_cpu1_d2" )
			)
			( signal "FM_CTNR_PS_ON"
				( objectStatus "@baseboard_fab2_lib.baseboard_fab2(sch_1):fm_ctnr_ps_on" )
			)
			( signal "FM_DISABLE_FAN_N"
				( objectStatus "@baseboard_fab2_lib.baseboard_fab2(sch_1):fm_disable_fan_n" )
			)
			( signal "FM_ENABLE_FAN_POWER"
				( objectStatus "@baseboard_fab2_lib.baseboard_fab2(sch_1):fm_enable_fan_power" )
			)
			( signal "P12V_FAN"
				( attribute "VOLTAGE" "12.0V"
					( Units "uVoltage" "V" 1.000000)
					( Status sAliasFlattened )
					( Origin gFrontEnd )
				)
				( objectStatus "@baseboard_fab2_lib.baseboard_fab2(sch_1):p12v_fan" )
			)
			( signal "TP_FAN_0"
				( objectStatus "@baseboard_fab2_lib.baseboard_fab2(sch_1):tp_fan_0" )
			)
			( signal "TP_FAN_1"
				( objectStatus "@baseboard_fab2_lib.baseboard_fab2(sch_1):tp_fan_1" )
			)
			( signal "PU_SPI_BMC_BT_HOLD_N"
				( objectStatus "@baseboard_fab2_lib.baseboard_fab2(sch_1):pu_spi_bmc_bt_hold_n" )
			)
			( signal "PU_SPI_BMC_BT_WP_N"
				( objectStatus "@baseboard_fab2_lib.baseboard_fab2(sch_1):pu_spi_bmc_bt_wp_n" )
			)
			( signal "PU_SPI_FLASH_RESET_2_N"
				( objectStatus "@baseboard_fab2_lib.baseboard_fab2(sch_1):pu_spi_flash_reset_2_n" )
			)
			( signal "SPI_BMC_BT_DI_R"
				( objectStatus "@baseboard_fab2_lib.baseboard_fab2(sch_1):spi_bmc_bt_di_r" )
			)
			( signal "TP_SPI_2_0"
				( objectStatus "@baseboard_fab2_lib.baseboard_fab2(sch_1):tp_spi_2_0" )
			)
			( signal "TP_SPI_2_1"
				( objectStatus "@baseboard_fab2_lib.baseboard_fab2(sch_1):tp_spi_2_1" )
			)
			( signal "TP_SPI_2_2"
				( objectStatus "@baseboard_fab2_lib.baseboard_fab2(sch_1):tp_spi_2_2" )
			)
			( signal "TP_SPI_2_3"
				( objectStatus "@baseboard_fab2_lib.baseboard_fab2(sch_1):tp_spi_2_3" )
			)
			( signal "TP_SPI_2_4"
				( objectStatus "@baseboard_fab2_lib.baseboard_fab2(sch_1):tp_spi_2_4" )
			)
			( signal "TP_SPI_2_5"
				( objectStatus "@baseboard_fab2_lib.baseboard_fab2(sch_1):tp_spi_2_5" )
			)
			( signal "TP_SPI_2_6"
				( objectStatus "@baseboard_fab2_lib.baseboard_fab2(sch_1):tp_spi_2_6" )
			)
			( signal "SMB_CPU1_PE_HP_GTL_R_SCL"
				( objectStatus "@baseboard_fab2_lib.baseboard_fab2(sch_1):smb_cpu1_pe_hp_gtl_r_scl" )
			)
			( signal "SMB_CPU1_PE_HP_GTL_R_SDA"
				( objectStatus "@baseboard_fab2_lib.baseboard_fab2(sch_1):smb_cpu1_pe_hp_gtl_r_sda" )
			)
			( signal "SMB_PEHPCPU1_STBY_LVC3_R_SCL"
				( objectStatus "@baseboard_fab2_lib.baseboard_fab2(sch_1):smb_pehpcpu1_stby_lvc3_r_scl" )
			)
			( signal "SMB_PEHPCPU1_STBY_LVC3_R_SDA"
				( objectStatus "@baseboard_fab2_lib.baseboard_fab2(sch_1):smb_pehpcpu1_stby_lvc3_r_sda" )
			)
			( signal "SMB_PEHPCPU1_STBY_LVC3_SCL"
				( objectStatus "@baseboard_fab2_lib.baseboard_fab2(sch_1):smb_pehpcpu1_stby_lvc3_scl" )
			)
			( signal "SMB_PEHPCPU1_STBY_LVC3_SDA"
				( objectStatus "@baseboard_fab2_lib.baseboard_fab2(sch_1):smb_pehpcpu1_stby_lvc3_sda" )
			)
			( signal "TP_SMB_PEHPCPU1_EN"
				( objectStatus "@baseboard_fab2_lib.baseboard_fab2(sch_1):tp_smb_pehpcpu1_en" )
			)
			( signal "FM_ADC128_A0"
				( objectStatus "@baseboard_fab2_lib.baseboard_fab2(sch_1):fm_adc128_a0" )
			)
			( signal "FM_ADC128_A1"
				( objectStatus "@baseboard_fab2_lib.baseboard_fab2(sch_1):fm_adc128_a1" )
			)
			( signal "IRQ_VM_INT_R_N"
				( objectStatus "@baseboard_fab2_lib.baseboard_fab2(sch_1):irq_vm_int_r_n" )
			)
			( signal "P3V3_FB_ADC128_VCC"
				( attribute "VOLTAGE" "+3.3V"
					( Units "uVoltage" "V" 1.000000)
					( Status sAliasFlattened )
					( Origin gFrontEnd )
				)
				( objectStatus "@baseboard_fab2_lib.baseboard_fab2(sch_1):p3v3_fb_adc128_vcc" )
			)
			( signal "TP_ADC128_VREF"
				( objectStatus "@baseboard_fab2_lib.baseboard_fab2(sch_1):tp_adc128_vref" )
			)
			( signal "ISENSE_TMP421_1_BC"
				( objectStatus "@baseboard_fab2_lib.baseboard_fab2(sch_1):isense_tmp421_1_bc" )
			)
			( signal "ISENSE_TMP421_1_DXN"
				( objectStatus "@baseboard_fab2_lib.baseboard_fab2(sch_1):isense_tmp421_1_dxn" )
			)
			( signal "ISENSE_TMP421_1_DXP"
				( objectStatus "@baseboard_fab2_lib.baseboard_fab2(sch_1):isense_tmp421_1_dxp" )
			)
			( signal "ISENSE_TMP421_1_E"
				( objectStatus "@baseboard_fab2_lib.baseboard_fab2(sch_1):isense_tmp421_1_e" )
			)
			( signal "ISENSE_TMP421_2_BC"
				( objectStatus "@baseboard_fab2_lib.baseboard_fab2(sch_1):isense_tmp421_2_bc" )
			)
			( signal "ISENSE_TMP421_2_DXN"
				( objectStatus "@baseboard_fab2_lib.baseboard_fab2(sch_1):isense_tmp421_2_dxn" )
			)
			( signal "ISENSE_TMP421_2_DXP"
				( objectStatus "@baseboard_fab2_lib.baseboard_fab2(sch_1):isense_tmp421_2_dxp" )
			)
			( signal "ISENSE_TMP421_2_E"
				( objectStatus "@baseboard_fab2_lib.baseboard_fab2(sch_1):isense_tmp421_2_e" )
			)
			( signal "PD_FRU_WP"
				( objectStatus "@baseboard_fab2_lib.baseboard_fab2(sch_1):pd_fru_wp" )
			)
			( signal "PD_TMP421_1_A0"
				( objectStatus "@baseboard_fab2_lib.baseboard_fab2(sch_1):pd_tmp421_1_a0" )
			)
			( signal "PD_TMP421_2_A1"
				( objectStatus "@baseboard_fab2_lib.baseboard_fab2(sch_1):pd_tmp421_2_a1" )
			)
			( signal "PU_AT24C64_A2"
				( objectStatus "@baseboard_fab2_lib.baseboard_fab2(sch_1):pu_at24c64_a2" )
			)
			( signal "PU_TMP421_1_A1"
				( objectStatus "@baseboard_fab2_lib.baseboard_fab2(sch_1):pu_tmp421_1_a1" )
			)
			( signal "PU_TMP421_2_A0"
				( objectStatus "@baseboard_fab2_lib.baseboard_fab2(sch_1):pu_tmp421_2_a0" )
			)
			( signal "SMB_SENSOR_STBY_LVC3_SCL"
				( objectStatus "@baseboard_fab2_lib.baseboard_fab2(sch_1):smb_sensor_stby_lvc3_scl" )
			)
			( signal "SMB_SENSOR_STBY_LVC3_SCL_R2"
				( objectStatus "@baseboard_fab2_lib.baseboard_fab2(sch_1):smb_sensor_stby_lvc3_scl_r2" )
			)
			( signal "SMB_SENSOR_STBY_LVC3_SDA"
				( objectStatus "@baseboard_fab2_lib.baseboard_fab2(sch_1):smb_sensor_stby_lvc3_sda" )
			)
			( signal "SMB_SENSOR_STBY_LVC3_SDA_R2"
				( objectStatus "@baseboard_fab2_lib.baseboard_fab2(sch_1):smb_sensor_stby_lvc3_sda_r2" )
			)
			( signal "SMB_SENSOR_TMP421_1_SCL"
				( objectStatus "@baseboard_fab2_lib.baseboard_fab2(sch_1):smb_sensor_tmp421_1_scl" )
			)
			( signal "SMB_SENSOR_TMP421_1_SDA"
				( objectStatus "@baseboard_fab2_lib.baseboard_fab2(sch_1):smb_sensor_tmp421_1_sda" )
			)
			( signal "SMB_SENSOR_TMP421_2_SCL"
				( objectStatus "@baseboard_fab2_lib.baseboard_fab2(sch_1):smb_sensor_tmp421_2_scl" )
			)
			( signal "SMB_SENSOR_TMP421_2_SDA"
				( objectStatus "@baseboard_fab2_lib.baseboard_fab2(sch_1):smb_sensor_tmp421_2_sda" )
			)
			( signal "FM_DB_PRESENT"
				( objectStatus "@baseboard_fab2_lib.baseboard_fab2(sch_1):fm_db_present" )
			)
			( signal "FM_DB_UART_SEL0_N"
				( objectStatus "@baseboard_fab2_lib.baseboard_fab2(sch_1):fm_db_uart_sel0_n" )
			)
			( signal "FM_DB_UART_SEL1_N"
				( objectStatus "@baseboard_fab2_lib.baseboard_fab2(sch_1):fm_db_uart_sel1_n" )
			)
			( signal "FM_DB_UART_SEL2_N"
				( objectStatus "@baseboard_fab2_lib.baseboard_fab2(sch_1):fm_db_uart_sel2_n" )
			)
			( signal "FM_DB_UART_SEL3_N"
				( objectStatus "@baseboard_fab2_lib.baseboard_fab2(sch_1):fm_db_uart_sel3_n" )
			)
			( signal "FM_DB_UART_SEL4_N"
				( objectStatus "@baseboard_fab2_lib.baseboard_fab2(sch_1):fm_db_uart_sel4_n" )
			)
			( signal "FM_UART_SEL_N"
				( objectStatus "@baseboard_fab2_lib.baseboard_fab2(sch_1):fm_uart_sel_n" )
			)
			( signal "TP_FET_Q56_3"
				( objectStatus "@baseboard_fab2_lib.baseboard_fab2(sch_1):tp_fet_q56_3" )
			)
			( signal "TP_FET_Q56_4"
				( objectStatus "@baseboard_fab2_lib.baseboard_fab2(sch_1):tp_fet_q56_4" )
			)
			( signal "A_P3V_BAT_R"
				( attribute "VOLTAGE" "+3 V"
					( Units "uVoltage" "V" 1.000000)
					( Status sAliasFlattened )
					( Origin gFrontEnd )
				)
				( objectStatus "@baseboard_fab2_lib.baseboard_fab2(sch_1):a_p3v_bat_r" )
			)
			( signal "P3V_BAT_SOURCE_R"
				( attribute "VOLTAGE" "+3V"
					( Units "uVoltage" "V" 1.000000)
					( Status sAliasFlattened )
					( Origin gFrontEnd )
				)
				( objectStatus "@baseboard_fab2_lib.baseboard_fab2(sch_1):p3v_bat_source_r" )
			)
			( signal "P5V"
				( attribute "VOLTAGE" "5.0V"
					( Units "uVoltage" "V" 1.000000)
					( Status sAliasFlattened )
					( Status sAliasConflict )
					( Origin gFrontEnd )
				)
				( objectStatus "@baseboard_fab2_lib.baseboard_fab2(sch_1):p5v" )
			)
			( signal "H_CPU1_MEMGHJ_MEMHOT_PCH_N"
				( objectStatus "@baseboard_fab2_lib.baseboard_fab2(sch_1):h_cpu1_memghj_memhot_pch_n" )
			)
			( signal "H_CPU0_MEMDEF_MEMHOT_PCH_N"
				( objectStatus "@baseboard_fab2_lib.baseboard_fab2(sch_1):h_cpu0_memdef_memhot_pch_n" )
			)
			( signal "H_CPU0_MEMABC_MEMHOT_PCH_N"
				( objectStatus "@baseboard_fab2_lib.baseboard_fab2(sch_1):h_cpu0_memabc_memhot_pch_n" )
			)
			( signal "FM_FAST_PROCHOT_AND_OUT_0_N"
				( objectStatus "@baseboard_fab2_lib.baseboard_fab2(sch_1):fm_fast_prochot_and_out_0_n" )
			)
			( signal "FM_FAST_PROCHOT_AND_OUT_1_N"
				( objectStatus "@baseboard_fab2_lib.baseboard_fab2(sch_1):fm_fast_prochot_and_out_1_n" )
			)
			( signal "FM_FAST_PROCHOT_EN"
				( objectStatus "@baseboard_fab2_lib.baseboard_fab2(sch_1):fm_fast_prochot_en" )
			)
			( signal "FM_FAST_PROCHOT_THROTTLE_DLY_BU"
				( objectStatus "@baseboard_fab2_lib.baseboard_fab2(sch_1):fm_fast_prochot_throttle_dly_buf_n" )
			)
			( signal "FM_FAST_PROCHOT_THROTTLE_DLY_N"
				( objectStatus "@baseboard_fab2_lib.baseboard_fab2(sch_1):fm_fast_prochot_throttle_dly_n" )
			)
			( signal "FM_FAST_PROCHOT_THROTTLE_IN_N"
				( objectStatus "@baseboard_fab2_lib.baseboard_fab2(sch_1):fm_fast_prochot_throttle_in_n" )
			)
			( signal "FM_OC_DETECT_N"
				( objectStatus "@baseboard_fab2_lib.baseboard_fab2(sch_1):fm_oc_detect_n" )
			)
			( signal "FM_PMBUS_ALERT_BUF_EN"
				( objectStatus "@baseboard_fab2_lib.baseboard_fab2(sch_1):fm_pmbus_alert_buf_en" )
			)
			( signal "FM_THROTTLE_R1_N"
				( objectStatus "@baseboard_fab2_lib.baseboard_fab2(sch_1):fm_throttle_r1_n" )
			)
			( signal "IRQ_FORCE_NM_THROTTLE_R_N"
				( objectStatus "@baseboard_fab2_lib.baseboard_fab2(sch_1):irq_force_nm_throttle_r_n" )
			)
			( signal "IRQ_SML1_PMBUS_ALERT_BUF_N"
				( objectStatus "@baseboard_fab2_lib.baseboard_fab2(sch_1):irq_sml1_pmbus_alert_buf_n" )
			)
			( signal "P12V_HDD_SATA"
				( attribute "VOLTAGE" "12"
					( Units "uVoltage" "V" 1.000000)
					( Status sAliasFlattened )
					( Origin gFrontEnd )
				)
				( objectStatus "@baseboard_fab2_lib.baseboard_fab2(sch_1):p12v_hdd_sata" )
			)
			( signal "P5V_HDD_SATA"
				( attribute "VOLTAGE" "5"
					( Units "uVoltage" "V" 1.000000)
					( Status sAliasFlattened )
					( Origin gFrontEnd )
				)
				( objectStatus "@baseboard_fab2_lib.baseboard_fab2(sch_1):p5v_hdd_sata" )
			)
			( signal "SATA6G_S1_RX_C_DN"
				( objectStatus "@baseboard_fab2_lib.baseboard_fab2(sch_1):sata6g_s1_rx_c_dn" )
			)
			( signal "SATA6G_S1_RX_C_DP"
				( objectStatus "@baseboard_fab2_lib.baseboard_fab2(sch_1):sata6g_s1_rx_c_dp" )
			)
			( signal "SATA6G_S1_TX_C_DN"
				( objectStatus "@baseboard_fab2_lib.baseboard_fab2(sch_1):sata6g_s1_tx_c_dn" )
			)
			( signal "SATA6G_S1_TX_C_DP"
				( objectStatus "@baseboard_fab2_lib.baseboard_fab2(sch_1):sata6g_s1_tx_c_dp" )
			)
			( signal "PD_SATA0_CONTROLLER_TYPE_R"
				( objectStatus "@baseboard_fab2_lib.baseboard_fab2(sch_1):pd_sata0_controller_type_r" )
			)
			( signal "PD_SATA1_CONTROLLER_TYPE_R"
				( objectStatus "@baseboard_fab2_lib.baseboard_fab2(sch_1):pd_sata1_controller_type_r" )
			)
			( signal "PU_DATAIN1_SATA_0_R"
				( objectStatus "@baseboard_fab2_lib.baseboard_fab2(sch_1):pu_datain1_sata_0_r" )
			)
			( signal "PU_DATAIN1_SATA_1_R"
				( objectStatus "@baseboard_fab2_lib.baseboard_fab2(sch_1):pu_datain1_sata_1_r" )
			)
			( signal "SATA6G_P0_RX_C_DN"
				( objectStatus "@baseboard_fab2_lib.baseboard_fab2(sch_1):sata6g_p0_rx_c_dn" )
			)
			( signal "SATA6G_P0_RX_C_DP"
				( objectStatus "@baseboard_fab2_lib.baseboard_fab2(sch_1):sata6g_p0_rx_c_dp" )
			)
			( signal "SATA6G_P0_TX_C_DN"
				( objectStatus "@baseboard_fab2_lib.baseboard_fab2(sch_1):sata6g_p0_tx_c_dn" )
			)
			( signal "SATA6G_P0_TX_C_DP"
				( objectStatus "@baseboard_fab2_lib.baseboard_fab2(sch_1):sata6g_p0_tx_c_dp" )
			)
			( signal "SATA6G_P1_RX_C_DN"
				( objectStatus "@baseboard_fab2_lib.baseboard_fab2(sch_1):sata6g_p1_rx_c_dn" )
			)
			( signal "SATA6G_P1_RX_C_DP"
				( objectStatus "@baseboard_fab2_lib.baseboard_fab2(sch_1):sata6g_p1_rx_c_dp" )
			)
			( signal "SATA6G_P1_TX_C_DN"
				( objectStatus "@baseboard_fab2_lib.baseboard_fab2(sch_1):sata6g_p1_tx_c_dn" )
			)
			( signal "SATA6G_P1_TX_C_DP"
				( objectStatus "@baseboard_fab2_lib.baseboard_fab2(sch_1):sata6g_p1_tx_c_dp" )
			)
			( signal "SATA6G_P2_RX_C_DN"
				( objectStatus "@baseboard_fab2_lib.baseboard_fab2(sch_1):sata6g_p2_rx_c_dn" )
			)
			( signal "SATA6G_P2_RX_C_DP"
				( objectStatus "@baseboard_fab2_lib.baseboard_fab2(sch_1):sata6g_p2_rx_c_dp" )
			)
			( signal "SATA6G_P2_TX_C_DN"
				( objectStatus "@baseboard_fab2_lib.baseboard_fab2(sch_1):sata6g_p2_tx_c_dn" )
			)
			( signal "SATA6G_P2_TX_C_DP"
				( objectStatus "@baseboard_fab2_lib.baseboard_fab2(sch_1):sata6g_p2_tx_c_dp" )
			)
			( signal "SATA6G_P3_RX_C_DN"
				( objectStatus "@baseboard_fab2_lib.baseboard_fab2(sch_1):sata6g_p3_rx_c_dn" )
			)
			( signal "SATA6G_P3_RX_C_DP"
				( objectStatus "@baseboard_fab2_lib.baseboard_fab2(sch_1):sata6g_p3_rx_c_dp" )
			)
			( signal "SATA6G_P3_TX_C_DN"
				( objectStatus "@baseboard_fab2_lib.baseboard_fab2(sch_1):sata6g_p3_tx_c_dn" )
			)
			( signal "SATA6G_P3_TX_C_DP"
				( objectStatus "@baseboard_fab2_lib.baseboard_fab2(sch_1):sata6g_p3_tx_c_dp" )
			)
			( signal "SATA6G_P4_RX_C_DN"
				( objectStatus "@baseboard_fab2_lib.baseboard_fab2(sch_1):sata6g_p4_rx_c_dn" )
			)
			( signal "SATA6G_P4_RX_C_DP"
				( objectStatus "@baseboard_fab2_lib.baseboard_fab2(sch_1):sata6g_p4_rx_c_dp" )
			)
			( signal "SATA6G_P4_TX_C_DN"
				( objectStatus "@baseboard_fab2_lib.baseboard_fab2(sch_1):sata6g_p4_tx_c_dn" )
			)
			( signal "SATA6G_P4_TX_C_DP"
				( objectStatus "@baseboard_fab2_lib.baseboard_fab2(sch_1):sata6g_p4_tx_c_dp" )
			)
			( signal "SATA6G_P5_RX_C_DN"
				( objectStatus "@baseboard_fab2_lib.baseboard_fab2(sch_1):sata6g_p5_rx_c_dn" )
			)
			( signal "SATA6G_P5_RX_C_DP"
				( objectStatus "@baseboard_fab2_lib.baseboard_fab2(sch_1):sata6g_p5_rx_c_dp" )
			)
			( signal "SATA6G_P5_TX_C_DN"
				( objectStatus "@baseboard_fab2_lib.baseboard_fab2(sch_1):sata6g_p5_tx_c_dn" )
			)
			( signal "SATA6G_P5_TX_C_DP"
				( objectStatus "@baseboard_fab2_lib.baseboard_fab2(sch_1):sata6g_p5_tx_c_dp" )
			)
			( signal "SATA6G_P6_RX_C_DN"
				( objectStatus "@baseboard_fab2_lib.baseboard_fab2(sch_1):sata6g_p6_rx_c_dn" )
			)
			( signal "SATA6G_P6_RX_C_DP"
				( objectStatus "@baseboard_fab2_lib.baseboard_fab2(sch_1):sata6g_p6_rx_c_dp" )
			)
			( signal "SATA6G_P6_TX_C_DN"
				( objectStatus "@baseboard_fab2_lib.baseboard_fab2(sch_1):sata6g_p6_tx_c_dn" )
			)
			( signal "SATA6G_P6_TX_C_DP"
				( objectStatus "@baseboard_fab2_lib.baseboard_fab2(sch_1):sata6g_p6_tx_c_dp" )
			)
			( signal "SATA6G_P7_RX_C_DN"
				( objectStatus "@baseboard_fab2_lib.baseboard_fab2(sch_1):sata6g_p7_rx_c_dn" )
			)
			( signal "SATA6G_P7_RX_C_DP"
				( objectStatus "@baseboard_fab2_lib.baseboard_fab2(sch_1):sata6g_p7_rx_c_dp" )
			)
			( signal "SATA6G_P7_TX_C_DN"
				( objectStatus "@baseboard_fab2_lib.baseboard_fab2(sch_1):sata6g_p7_tx_c_dn" )
			)
			( signal "SATA6G_P7_TX_C_DP"
				( objectStatus "@baseboard_fab2_lib.baseboard_fab2(sch_1):sata6g_p7_tx_c_dp" )
			)
			( signal "SGPIO_PCH_SATA_CLOCK_R"
				( objectStatus "@baseboard_fab2_lib.baseboard_fab2(sch_1):sgpio_pch_sata_clock_r" )
			)
			( signal "SGPIO_PCH_SATA_DOUT0_R"
				( objectStatus "@baseboard_fab2_lib.baseboard_fab2(sch_1):sgpio_pch_sata_dout0_r" )
			)
			( signal "SGPIO_PCH_SATA_LOAD_R"
				( objectStatus "@baseboard_fab2_lib.baseboard_fab2(sch_1):sgpio_pch_sata_load_r" )
			)
			( signal "TP_FM_QAT_CBL_PRSNT0_R_N"
				( objectStatus "@baseboard_fab2_lib.baseboard_fab2(sch_1):tp_fm_qat_cbl_prsnt0_r_n" )
			)
			( signal "TP_FM_QAT_CBL_PRSNT1_N_R"
				( objectStatus "@baseboard_fab2_lib.baseboard_fab2(sch_1):tp_fm_qat_cbl_prsnt1_n_r" )
			)
			( signal "TP_SGPIO_SATA_CLOCK1_R"
				( objectStatus "@baseboard_fab2_lib.baseboard_fab2(sch_1):tp_sgpio_sata_clock1_r" )
			)
			( signal "TP_SGPIO_SATA_DATA1_R"
				( objectStatus "@baseboard_fab2_lib.baseboard_fab2(sch_1):tp_sgpio_sata_data1_r" )
			)
			( signal "TP_SGPIO_SATA_LOAD1_R"
				( objectStatus "@baseboard_fab2_lib.baseboard_fab2(sch_1):tp_sgpio_sata_load1_r" )
			)
			( signal "PD_SATA2_CONTROLLER_TYPE"
				( objectStatus "@baseboard_fab2_lib.baseboard_fab2(sch_1):pd_sata2_controller_type" )
			)
			( signal "PU_DATAIN1_SATA_2"
				( objectStatus "@baseboard_fab2_lib.baseboard_fab2(sch_1):pu_datain1_sata_2" )
			)
			( signal "SATA6G_P10_RX_C_DN"
				( objectStatus "@baseboard_fab2_lib.baseboard_fab2(sch_1):sata6g_p10_rx_c_dn" )
			)
			( signal "SATA6G_P10_RX_C_DP"
				( objectStatus "@baseboard_fab2_lib.baseboard_fab2(sch_1):sata6g_p10_rx_c_dp" )
			)
			( signal "SATA6G_P10_TX_C_DN"
				( objectStatus "@baseboard_fab2_lib.baseboard_fab2(sch_1):sata6g_p10_tx_c_dn" )
			)
			( signal "SATA6G_P10_TX_C_DP"
				( objectStatus "@baseboard_fab2_lib.baseboard_fab2(sch_1):sata6g_p10_tx_c_dp" )
			)
			( signal "SATA6G_P11_RX_C_DN"
				( objectStatus "@baseboard_fab2_lib.baseboard_fab2(sch_1):sata6g_p11_rx_c_dn" )
			)
			( signal "SATA6G_P11_RX_C_DP"
				( objectStatus "@baseboard_fab2_lib.baseboard_fab2(sch_1):sata6g_p11_rx_c_dp" )
			)
			( signal "SATA6G_P11_TX_C_DN"
				( objectStatus "@baseboard_fab2_lib.baseboard_fab2(sch_1):sata6g_p11_tx_c_dn" )
			)
			( signal "SATA6G_P11_TX_C_DP"
				( objectStatus "@baseboard_fab2_lib.baseboard_fab2(sch_1):sata6g_p11_tx_c_dp" )
			)
			( signal "SATA6G_P8_RX_C_DN"
				( objectStatus "@baseboard_fab2_lib.baseboard_fab2(sch_1):sata6g_p8_rx_c_dn" )
			)
			( signal "SATA6G_P8_RX_C_DP"
				( objectStatus "@baseboard_fab2_lib.baseboard_fab2(sch_1):sata6g_p8_rx_c_dp" )
			)
			( signal "SATA6G_P8_TX_C_DN"
				( objectStatus "@baseboard_fab2_lib.baseboard_fab2(sch_1):sata6g_p8_tx_c_dn" )
			)
			( signal "SATA6G_P8_TX_C_DP"
				( objectStatus "@baseboard_fab2_lib.baseboard_fab2(sch_1):sata6g_p8_tx_c_dp" )
			)
			( signal "SATA6G_P9_RX_C_DN"
				( objectStatus "@baseboard_fab2_lib.baseboard_fab2(sch_1):sata6g_p9_rx_c_dn" )
			)
			( signal "SATA6G_P9_RX_C_DP"
				( objectStatus "@baseboard_fab2_lib.baseboard_fab2(sch_1):sata6g_p9_rx_c_dp" )
			)
			( signal "SATA6G_P9_TX_C_DN"
				( objectStatus "@baseboard_fab2_lib.baseboard_fab2(sch_1):sata6g_p9_tx_c_dn" )
			)
			( signal "SATA6G_P9_TX_C_DP"
				( objectStatus "@baseboard_fab2_lib.baseboard_fab2(sch_1):sata6g_p9_tx_c_dp" )
			)
			( signal "SGPIO_PCH_SSATA_CLOCK_R"
				( objectStatus "@baseboard_fab2_lib.baseboard_fab2(sch_1):sgpio_pch_ssata_clock_r" )
			)
			( signal "SGPIO_PCH_SSATA_DOUT0_R"
				( objectStatus "@baseboard_fab2_lib.baseboard_fab2(sch_1):sgpio_pch_ssata_dout0_r" )
			)
			( signal "SGPIO_PCH_SSATA_LOAD_R"
				( objectStatus "@baseboard_fab2_lib.baseboard_fab2(sch_1):sgpio_pch_ssata_load_r" )
			)
			( signal "TP_FM_QAT_CBL_PRSNT2_N"
				( objectStatus "@baseboard_fab2_lib.baseboard_fab2(sch_1):tp_fm_qat_cbl_prsnt2_n" )
			)
			( signal "FM_BEEP_LED_P"
				( objectStatus "@baseboard_fab2_lib.baseboard_fab2(sch_1):fm_beep_led_p" )
			)
			( signal "FM_PWR_BTN_R_N"
				( objectStatus "@baseboard_fab2_lib.baseboard_fab2(sch_1):fm_pwr_btn_r_n" )
			)
			( signal "FM_SPEAKER_PCH_N"
				( objectStatus "@baseboard_fab2_lib.baseboard_fab2(sch_1):fm_speaker_pch_n" )
			)
			( signal "FP_ID_LED_P5V_STBY_N"
				( objectStatus "@baseboard_fab2_lib.baseboard_fab2(sch_1):fp_id_led_p5v_stby_n" )
			)
			( signal "FP_ID_LED_XOR_R"
				( objectStatus "@baseboard_fab2_lib.baseboard_fab2(sch_1):fp_id_led_xor_r" )
			)
			( signal "FP_PWR_BTN_BUF1_N"
				( objectStatus "@baseboard_fab2_lib.baseboard_fab2(sch_1):fp_pwr_btn_buf1_n" )
			)
			( signal "FP_PWR_BTN_R1_N"
				( objectStatus "@baseboard_fab2_lib.baseboard_fab2(sch_1):fp_pwr_btn_r1_n" )
			)
			( signal "FP_PWR_BTN_R_N"
				( objectStatus "@baseboard_fab2_lib.baseboard_fab2(sch_1):fp_pwr_btn_r_n" )
			)
			( signal "FP_RST_BTN_BUF1_N"
				( objectStatus "@baseboard_fab2_lib.baseboard_fab2(sch_1):fp_rst_btn_buf1_n" )
			)
			( signal "FP_RST_BTN_R_N"
				( objectStatus "@baseboard_fab2_lib.baseboard_fab2(sch_1):fp_rst_btn_r_n" )
			)
			( signal "PWRGD_P3V3"
				( objectStatus "@baseboard_fab2_lib.baseboard_fab2(sch_1):pwrgd_p3v3" )
			)
			( signal "PWRGD_P3V3_R"
				( objectStatus "@baseboard_fab2_lib.baseboard_fab2(sch_1):pwrgd_p3v3_r" )
			)
			( signal "RST_SYSTEM_BTN_BUF_N"
				( objectStatus "@baseboard_fab2_lib.baseboard_fab2(sch_1):rst_system_btn_buf_n" )
			)
			( signal "P5V_USB"
				( attribute "VOLTAGE" "5V"
					( Units "uVoltage" "V" 1.000000)
					( Status sAliasFlattened )
					( Origin gFrontEnd )
				)
				( objectStatus "@baseboard_fab2_lib.baseboard_fab2(sch_1):p5v_usb" )
			)
			( signal "TP_USB_ESD_AC2"
				( objectStatus "@baseboard_fab2_lib.baseboard_fab2(sch_1):tp_usb_esd_ac2" )
			)
			( signal "TP_USB_ESD_AC3"
				( objectStatus "@baseboard_fab2_lib.baseboard_fab2(sch_1):tp_usb_esd_ac3" )
			)
			( signal "TP_USB_ESD_OUT2"
				( objectStatus "@baseboard_fab2_lib.baseboard_fab2(sch_1):tp_usb_esd_out2" )
			)
			( signal "TP_USB_ESD_OUT3"
				( objectStatus "@baseboard_fab2_lib.baseboard_fab2(sch_1):tp_usb_esd_out3" )
			)
			( signal "USB2_P01_ESD_DN"
				( objectStatus "@baseboard_fab2_lib.baseboard_fab2(sch_1):usb2_p01_esd_dn" )
			)
			( signal "USB2_P01_ESD_DP"
				( objectStatus "@baseboard_fab2_lib.baseboard_fab2(sch_1):usb2_p01_esd_dp" )
			)
			( signal "USB3_P01_C_TXN"
				( objectStatus "@baseboard_fab2_lib.baseboard_fab2(sch_1):usb3_p01_c_txn" )
			)
			( signal "USB3_P01_C_TXP"
				( objectStatus "@baseboard_fab2_lib.baseboard_fab2(sch_1):usb3_p01_c_txp" )
			)
			( signal "USB3_P01_FB_RXN"
				( objectStatus "@baseboard_fab2_lib.baseboard_fab2(sch_1):usb3_p01_fb_rxn" )
			)
			( signal "USB3_P01_FB_RXP"
				( objectStatus "@baseboard_fab2_lib.baseboard_fab2(sch_1):usb3_p01_fb_rxp" )
			)
			( signal "USB3_P01_FB_TXN"
				( objectStatus "@baseboard_fab2_lib.baseboard_fab2(sch_1):usb3_p01_fb_txn" )
			)
			( signal "USB3_P01_FB_TXP"
				( objectStatus "@baseboard_fab2_lib.baseboard_fab2(sch_1):usb3_p01_fb_txp" )
			)
			( signal "FM_BMC_FAULT_LED"
				( objectStatus "@baseboard_fab2_lib.baseboard_fab2(sch_1):fm_bmc_fault_led" )
			)
			( signal "FM_RED_LED_ANODE"
				( objectStatus "@baseboard_fab2_lib.baseboard_fab2(sch_1):fm_red_led_anode" )
			)
			( signal "FM_RED_LED_CATHODE"
				( objectStatus "@baseboard_fab2_lib.baseboard_fab2(sch_1):fm_red_led_cathode" )
			)
			( signal "FP_LED_HDD_ACTIVITY_AND_N"
				( objectStatus "@baseboard_fab2_lib.baseboard_fab2(sch_1):fp_led_hdd_activity_and_n" )
			)
			( signal "FP_LED_HDD_ACTIVITY_AND_R_N"
				( objectStatus "@baseboard_fab2_lib.baseboard_fab2(sch_1):fp_led_hdd_activity_and_r_n" )
			)
			( signal "LED_P5V_STBY"
				( objectStatus "@baseboard_fab2_lib.baseboard_fab2(sch_1):led_p5v_stby" )
			)
			( signal "LED_SAS_ACT_R_N"
				( objectStatus "@baseboard_fab2_lib.baseboard_fab2(sch_1):led_sas_act_r_n" )
			)
			( signal "LED_SATA_ACT_R_N"
				( objectStatus "@baseboard_fab2_lib.baseboard_fab2(sch_1):led_sata_act_r_n" )
			)
			( signal "FAN_PWM_OUT_SYS0_R1"
				( objectStatus "@baseboard_fab2_lib.baseboard_fab2(sch_1):fan_pwm_out_sys0_r1" )
			)
			( signal "FAN_TACH0_R"
				( objectStatus "@baseboard_fab2_lib.baseboard_fab2(sch_1):fan_tach0_r" )
			)
			( signal "FAN_TACH1_R"
				( objectStatus "@baseboard_fab2_lib.baseboard_fab2(sch_1):fan_tach1_r" )
			)
			( signal "FAN_TACH2_R"
				( objectStatus "@baseboard_fab2_lib.baseboard_fab2(sch_1):fan_tach2_r" )
			)
			( signal "FAN_TACH3_R"
				( objectStatus "@baseboard_fab2_lib.baseboard_fab2(sch_1):fan_tach3_r" )
			)
			( signal "FM_CTNR_PS_ON_R"
				( objectStatus "@baseboard_fab2_lib.baseboard_fab2(sch_1):fm_ctnr_ps_on_r" )
			)
			( signal "FM_MATED_IN_D1_N"
				( objectStatus "@baseboard_fab2_lib.baseboard_fab2(sch_1):fm_mated_in_d1_n" )
			)
			( signal "FM_MATED_IN_D2_N"
				( objectStatus "@baseboard_fab2_lib.baseboard_fab2(sch_1):fm_mated_in_d2_n" )
			)
			( signal "FM_MATED_IN_N"
				( objectStatus "@baseboard_fab2_lib.baseboard_fab2(sch_1):fm_mated_in_n" )
			)
			( signal "FM_P12V_HOTSWAP0_EN"
				( objectStatus "@baseboard_fab2_lib.baseboard_fab2(sch_1):fm_p12v_hotswap0_en" )
			)
			( signal "FM_PS_EN"
				( objectStatus "@baseboard_fab2_lib.baseboard_fab2(sch_1):fm_ps_en" )
			)
			( signal "P12V_PSU"
				( attribute "VOLTAGE" "12.0"
					( Units "uVoltage" "V" 1.000000)
					( Status sAliasFlattened )
					( Origin gFrontEnd )
				)
				( objectStatus "@baseboard_fab2_lib.baseboard_fab2(sch_1):p12v_psu" )
			)
			( signal "P3E_CPU1_PE3_MP_C_TXN<0>"
				( objectStatus "@baseboard_fab2_lib.baseboard_fab2(sch_1):p3e_cpu1_pe3_mp_c_txn(0)" )
			)
			( signal "P3E_CPU1_PE3_MP_C_TXN<1>"
				( objectStatus "@baseboard_fab2_lib.baseboard_fab2(sch_1):p3e_cpu1_pe3_mp_c_txn(1)" )
			)
			( signal "P3E_CPU1_PE3_MP_C_TXN<2>"
				( objectStatus "@baseboard_fab2_lib.baseboard_fab2(sch_1):p3e_cpu1_pe3_mp_c_txn(2)" )
			)
			( signal "P3E_CPU1_PE3_MP_C_TXN<3>"
				( objectStatus "@baseboard_fab2_lib.baseboard_fab2(sch_1):p3e_cpu1_pe3_mp_c_txn(3)" )
			)
			( signal "P3E_CPU1_PE3_MP_C_TXN<4>"
				( objectStatus "@baseboard_fab2_lib.baseboard_fab2(sch_1):p3e_cpu1_pe3_mp_c_txn(4)" )
			)
			( signal "P3E_CPU1_PE3_MP_C_TXN<5>"
				( objectStatus "@baseboard_fab2_lib.baseboard_fab2(sch_1):p3e_cpu1_pe3_mp_c_txn(5)" )
			)
			( signal "P3E_CPU1_PE3_MP_C_TXN<6>"
				( objectStatus "@baseboard_fab2_lib.baseboard_fab2(sch_1):p3e_cpu1_pe3_mp_c_txn(6)" )
			)
			( signal "P3E_CPU1_PE3_MP_C_TXN<7>"
				( objectStatus "@baseboard_fab2_lib.baseboard_fab2(sch_1):p3e_cpu1_pe3_mp_c_txn(7)" )
			)
			( signal "P3E_CPU1_PE3_MP_C_TXP<0>"
				( objectStatus "@baseboard_fab2_lib.baseboard_fab2(sch_1):p3e_cpu1_pe3_mp_c_txp(0)" )
			)
			( signal "P3E_CPU1_PE3_MP_C_TXP<1>"
				( objectStatus "@baseboard_fab2_lib.baseboard_fab2(sch_1):p3e_cpu1_pe3_mp_c_txp(1)" )
			)
			( signal "P3E_CPU1_PE3_MP_C_TXP<2>"
				( objectStatus "@baseboard_fab2_lib.baseboard_fab2(sch_1):p3e_cpu1_pe3_mp_c_txp(2)" )
			)
			( signal "P3E_CPU1_PE3_MP_C_TXP<3>"
				( objectStatus "@baseboard_fab2_lib.baseboard_fab2(sch_1):p3e_cpu1_pe3_mp_c_txp(3)" )
			)
			( signal "P3E_CPU1_PE3_MP_C_TXP<4>"
				( objectStatus "@baseboard_fab2_lib.baseboard_fab2(sch_1):p3e_cpu1_pe3_mp_c_txp(4)" )
			)
			( signal "P3E_CPU1_PE3_MP_C_TXP<5>"
				( objectStatus "@baseboard_fab2_lib.baseboard_fab2(sch_1):p3e_cpu1_pe3_mp_c_txp(5)" )
			)
			( signal "P3E_CPU1_PE3_MP_C_TXP<6>"
				( objectStatus "@baseboard_fab2_lib.baseboard_fab2(sch_1):p3e_cpu1_pe3_mp_c_txp(6)" )
			)
			( signal "P3E_CPU1_PE3_MP_C_TXP<7>"
				( objectStatus "@baseboard_fab2_lib.baseboard_fab2(sch_1):p3e_cpu1_pe3_mp_c_txp(7)" )
			)
			( signal "PWRGD_P12V_HSC_DLY"
				( objectStatus "@baseboard_fab2_lib.baseboard_fab2(sch_1):pwrgd_p12v_hsc_dly" )
			)
			( signal "RST_PCIE_MIDPLANE_N"
				( objectStatus "@baseboard_fab2_lib.baseboard_fab2(sch_1):rst_pcie_midplane_n" )
			)
			( signal "P3E_CPU1_PE3_MP_C_TXN<8>"
				( objectStatus "@baseboard_fab2_lib.baseboard_fab2(sch_1):p3e_cpu1_pe3_mp_c_txn(8)" )
			)
			( signal "P3E_CPU1_PE3_MP_C_TXN<9>"
				( objectStatus "@baseboard_fab2_lib.baseboard_fab2(sch_1):p3e_cpu1_pe3_mp_c_txn(9)" )
			)
			( signal "P3E_CPU1_PE3_MP_C_TXN<10>"
				( objectStatus "@baseboard_fab2_lib.baseboard_fab2(sch_1):p3e_cpu1_pe3_mp_c_txn(10)" )
			)
			( signal "P3E_CPU1_PE3_MP_C_TXN<11>"
				( objectStatus "@baseboard_fab2_lib.baseboard_fab2(sch_1):p3e_cpu1_pe3_mp_c_txn(11)" )
			)
			( signal "P3E_CPU1_PE3_MP_C_TXN<12>"
				( objectStatus "@baseboard_fab2_lib.baseboard_fab2(sch_1):p3e_cpu1_pe3_mp_c_txn(12)" )
			)
			( signal "P3E_CPU1_PE3_MP_C_TXN<13>"
				( objectStatus "@baseboard_fab2_lib.baseboard_fab2(sch_1):p3e_cpu1_pe3_mp_c_txn(13)" )
			)
			( signal "P3E_CPU1_PE3_MP_C_TXN<14>"
				( objectStatus "@baseboard_fab2_lib.baseboard_fab2(sch_1):p3e_cpu1_pe3_mp_c_txn(14)" )
			)
			( signal "P3E_CPU1_PE3_MP_C_TXN<15>"
				( objectStatus "@baseboard_fab2_lib.baseboard_fab2(sch_1):p3e_cpu1_pe3_mp_c_txn(15)" )
			)
			( signal "P3E_CPU1_PE3_MP_C_TXP<8>"
				( objectStatus "@baseboard_fab2_lib.baseboard_fab2(sch_1):p3e_cpu1_pe3_mp_c_txp(8)" )
			)
			( signal "P3E_CPU1_PE3_MP_C_TXP<9>"
				( objectStatus "@baseboard_fab2_lib.baseboard_fab2(sch_1):p3e_cpu1_pe3_mp_c_txp(9)" )
			)
			( signal "P3E_CPU1_PE3_MP_C_TXP<10>"
				( objectStatus "@baseboard_fab2_lib.baseboard_fab2(sch_1):p3e_cpu1_pe3_mp_c_txp(10)" )
			)
			( signal "P3E_CPU1_PE3_MP_C_TXP<11>"
				( objectStatus "@baseboard_fab2_lib.baseboard_fab2(sch_1):p3e_cpu1_pe3_mp_c_txp(11)" )
			)
			( signal "P3E_CPU1_PE3_MP_C_TXP<12>"
				( objectStatus "@baseboard_fab2_lib.baseboard_fab2(sch_1):p3e_cpu1_pe3_mp_c_txp(12)" )
			)
			( signal "P3E_CPU1_PE3_MP_C_TXP<13>"
				( objectStatus "@baseboard_fab2_lib.baseboard_fab2(sch_1):p3e_cpu1_pe3_mp_c_txp(13)" )
			)
			( signal "P3E_CPU1_PE3_MP_C_TXP<14>"
				( objectStatus "@baseboard_fab2_lib.baseboard_fab2(sch_1):p3e_cpu1_pe3_mp_c_txp(14)" )
			)
			( signal "P3E_CPU1_PE3_MP_C_TXP<15>"
				( objectStatus "@baseboard_fab2_lib.baseboard_fab2(sch_1):p3e_cpu1_pe3_mp_c_txp(15)" )
			)
			( signal "TP_FM_WAKE_N"
				( objectStatus "@baseboard_fab2_lib.baseboard_fab2(sch_1):tp_fm_wake_n" )
			)
			( signal "TP_IOA5"
				( objectStatus "@baseboard_fab2_lib.baseboard_fab2(sch_1):tp_ioa5" )
			)
			( signal "TP_IOE4"
				( objectStatus "@baseboard_fab2_lib.baseboard_fab2(sch_1):tp_ioe4" )
			)
			( signal "TP_IOF4"
				( objectStatus "@baseboard_fab2_lib.baseboard_fab2(sch_1):tp_iof4" )
			)
			( signal "TP_IOG3"
				( objectStatus "@baseboard_fab2_lib.baseboard_fab2(sch_1):tp_iog3" )
			)
			( signal "TP_IOH3"
				( objectStatus "@baseboard_fab2_lib.baseboard_fab2(sch_1):tp_ioh3" )
			)
			( signal "TP_IOH4"
				( objectStatus "@baseboard_fab2_lib.baseboard_fab2(sch_1):tp_ioh4" )
			)
			( signal "TP_IOI4"
				( objectStatus "@baseboard_fab2_lib.baseboard_fab2(sch_1):tp_ioi4" )
			)
			( signal "FM_PI7C9X1172_A0"
				( objectStatus "@baseboard_fab2_lib.baseboard_fab2(sch_1):fm_pi7c9x1172_a0" )
			)
			( signal "FM_PI7C9X1172_A1"
				( objectStatus "@baseboard_fab2_lib.baseboard_fab2(sch_1):fm_pi7c9x1172_a1" )
			)
			( signal "NC_PI7C9X1172_1"
				( objectStatus "@baseboard_fab2_lib.baseboard_fab2(sch_1):nc_pi7c9x1172_1" )
			)
			( signal "NC_PI7C9X1172_8"
				( objectStatus "@baseboard_fab2_lib.baseboard_fab2(sch_1):nc_pi7c9x1172_8" )
			)
			( signal "PU_PI7C9X1172_I2C_SPI_N"
				( objectStatus "@baseboard_fab2_lib.baseboard_fab2(sch_1):pu_pi7c9x1172_i2c_spi_n" )
			)
			( signal "SP1_HOST_BRIDGE_UART_RX"
				( objectStatus "@baseboard_fab2_lib.baseboard_fab2(sch_1):sp1_host_bridge_uart_rx" )
			)
			( signal "SP1_HOST_BRIDGE_UART_TX"
				( objectStatus "@baseboard_fab2_lib.baseboard_fab2(sch_1):sp1_host_bridge_uart_tx" )
			)
			( signal "TP_GPIO0_DSRB_N"
				( objectStatus "@baseboard_fab2_lib.baseboard_fab2(sch_1):tp_gpio0_dsrb_n" )
			)
			( signal "TP_GPIO1_DTRB_N"
				( objectStatus "@baseboard_fab2_lib.baseboard_fab2(sch_1):tp_gpio1_dtrb_n" )
			)
			( signal "TP_GPIO2_CDB_N"
				( objectStatus "@baseboard_fab2_lib.baseboard_fab2(sch_1):tp_gpio2_cdb_n" )
			)
			( signal "TP_GPIO3_RIB_N"
				( objectStatus "@baseboard_fab2_lib.baseboard_fab2(sch_1):tp_gpio3_rib_n" )
			)
			( signal "TP_GPIO4_DSRA_N"
				( objectStatus "@baseboard_fab2_lib.baseboard_fab2(sch_1):tp_gpio4_dsra_n" )
			)
			( signal "TP_GPIO5_DTRA_N"
				( objectStatus "@baseboard_fab2_lib.baseboard_fab2(sch_1):tp_gpio5_dtra_n" )
			)
			( signal "TP_GPIO6_CDA_N"
				( objectStatus "@baseboard_fab2_lib.baseboard_fab2(sch_1):tp_gpio6_cda_n" )
			)
			( signal "TP_GPIO7_RIA_N"
				( objectStatus "@baseboard_fab2_lib.baseboard_fab2(sch_1):tp_gpio7_ria_n" )
			)
			( signal "TP_PI7C9X1172_EN485_N"
				( objectStatus "@baseboard_fab2_lib.baseboard_fab2(sch_1):tp_pi7c9x1172_en485_n" )
			)
			( signal "TP_PI7C9X1172_ENIR_N"
				( objectStatus "@baseboard_fab2_lib.baseboard_fab2(sch_1):tp_pi7c9x1172_enir_n" )
			)
			( signal "TP_PI7C9X1172_RTSA_N"
				( objectStatus "@baseboard_fab2_lib.baseboard_fab2(sch_1):tp_pi7c9x1172_rtsa_n" )
			)
			( signal "TP_PI7C9X1172_RTSB_N"
				( objectStatus "@baseboard_fab2_lib.baseboard_fab2(sch_1):tp_pi7c9x1172_rtsb_n" )
			)
			( signal "TP_PI7C9X1172_SO"
				( objectStatus "@baseboard_fab2_lib.baseboard_fab2(sch_1):tp_pi7c9x1172_so" )
			)
			( signal "UART_BRIDGE_RXD5"
				( objectStatus "@baseboard_fab2_lib.baseboard_fab2(sch_1):uart_bridge_rxd5" )
			)
			( signal "UART_BRIDGE_TXD5"
				( objectStatus "@baseboard_fab2_lib.baseboard_fab2(sch_1):uart_bridge_txd5" )
			)
			( signal "XTAL_24MHZ_IN_R"
				( objectStatus "@baseboard_fab2_lib.baseboard_fab2(sch_1):xtal_24mhz_in_r" )
			)
			( signal "XTAL_24MHZ_OUT_R"
				( objectStatus "@baseboard_fab2_lib.baseboard_fab2(sch_1):xtal_24mhz_out_r" )
			)
			( signal "XTAL_24MHZ_PI7C9X1172_IN"
				( objectStatus "@baseboard_fab2_lib.baseboard_fab2(sch_1):xtal_24mhz_pi7c9x1172_in" )
			)
			( signal "XTAL_24MHZ_PI7C9X1172_OUT"
				( objectStatus "@baseboard_fab2_lib.baseboard_fab2(sch_1):xtal_24mhz_pi7c9x1172_out" )
			)
			( signal "IRQ_SPI_TPM_N_R"
				( objectStatus "@baseboard_fab2_lib.baseboard_fab2(sch_1):irq_spi_tpm_n_r" )
			)
			( signal "SPI_PCH_TPM_CLK_R"
				( objectStatus "@baseboard_fab2_lib.baseboard_fab2(sch_1):spi_pch_tpm_clk_r" )
			)
			( signal "SPI_PCH_TPM_CS_R_N"
				( objectStatus "@baseboard_fab2_lib.baseboard_fab2(sch_1):spi_pch_tpm_cs_r_n" )
			)
			( signal "SPI_PCH_TPM_MISO_R"
				( objectStatus "@baseboard_fab2_lib.baseboard_fab2(sch_1):spi_pch_tpm_miso_r" )
			)
			( signal "SPI_PCH_TPM_MOSI_R"
				( objectStatus "@baseboard_fab2_lib.baseboard_fab2(sch_1):spi_pch_tpm_mosi_r" )
			)
			( signal "FM_M2_DET_LVC3"
				( objectStatus "@baseboard_fab2_lib.baseboard_fab2(sch_1):fm_m2_det_lvc3" )
			)
			( signal "FM_M2_SSD_PEDET"
				( objectStatus "@baseboard_fab2_lib.baseboard_fab2(sch_1):fm_m2_ssd_pedet" )
			)
			( signal "NC_M2<0>"
				( objectStatus "@baseboard_fab2_lib.baseboard_fab2(sch_1):nc_m2(0)" )
			)
			( signal "NC_M2<1>"
				( objectStatus "@baseboard_fab2_lib.baseboard_fab2(sch_1):nc_m2(1)" )
			)
			( signal "NC_M2<2>"
				( objectStatus "@baseboard_fab2_lib.baseboard_fab2(sch_1):nc_m2(2)" )
			)
			( signal "NC_M2<3>"
				( objectStatus "@baseboard_fab2_lib.baseboard_fab2(sch_1):nc_m2(3)" )
			)
			( signal "NC_M2<4>"
				( objectStatus "@baseboard_fab2_lib.baseboard_fab2(sch_1):nc_m2(4)" )
			)
			( signal "NC_M2<5>"
				( objectStatus "@baseboard_fab2_lib.baseboard_fab2(sch_1):nc_m2(5)" )
			)
			( signal "NC_M2<6>"
				( objectStatus "@baseboard_fab2_lib.baseboard_fab2(sch_1):nc_m2(6)" )
			)
			( signal "NC_M2<7>"
				( objectStatus "@baseboard_fab2_lib.baseboard_fab2(sch_1):nc_m2(7)" )
			)
			( signal "NC_M2<8>"
				( objectStatus "@baseboard_fab2_lib.baseboard_fab2(sch_1):nc_m2(8)" )
			)
			( signal "NC_M2<9>"
				( objectStatus "@baseboard_fab2_lib.baseboard_fab2(sch_1):nc_m2(9)" )
			)
			( signal "NC_M2<10>"
				( objectStatus "@baseboard_fab2_lib.baseboard_fab2(sch_1):nc_m2(10)" )
			)
			( signal "NC_M2<11>"
				( objectStatus "@baseboard_fab2_lib.baseboard_fab2(sch_1):nc_m2(11)" )
			)
			( signal "NC_M2<12>"
				( objectStatus "@baseboard_fab2_lib.baseboard_fab2(sch_1):nc_m2(12)" )
			)
			( signal "NC_M2<13>"
				( objectStatus "@baseboard_fab2_lib.baseboard_fab2(sch_1):nc_m2(13)" )
			)
			( signal "NC_M2<14>"
				( objectStatus "@baseboard_fab2_lib.baseboard_fab2(sch_1):nc_m2(14)" )
			)
			( signal "NC_M2<15>"
				( objectStatus "@baseboard_fab2_lib.baseboard_fab2(sch_1):nc_m2(15)" )
			)
			( signal "NC_M2<16>"
				( objectStatus "@baseboard_fab2_lib.baseboard_fab2(sch_1):nc_m2(16)" )
			)
			( signal "NC_M2<17>"
				( objectStatus "@baseboard_fab2_lib.baseboard_fab2(sch_1):nc_m2(17)" )
			)
			( signal "NC_M2<18>"
				( objectStatus "@baseboard_fab2_lib.baseboard_fab2(sch_1):nc_m2(18)" )
			)
			( signal "P3E_PCH_M2_SATA6G_RX_R_DN"
				( objectStatus "@baseboard_fab2_lib.baseboard_fab2(sch_1):p3e_pch_m2_sata6g_rx_r_dn" )
			)
			( signal "P3E_PCH_M2_SATA6G_RX_R_DP"
				( objectStatus "@baseboard_fab2_lib.baseboard_fab2(sch_1):p3e_pch_m2_sata6g_rx_r_dp" )
			)
			( signal "P3E_PCH_M2_SATA6G_TX_R_DN"
				( objectStatus "@baseboard_fab2_lib.baseboard_fab2(sch_1):p3e_pch_m2_sata6g_tx_r_dn" )
			)
			( signal "P3E_PCH_M2_SATA6G_TX_R_DP"
				( objectStatus "@baseboard_fab2_lib.baseboard_fab2(sch_1):p3e_pch_m2_sata6g_tx_r_dp" )
			)
			( signal "P3E_PCH_M2_TX_C_DN<1>"
				( objectStatus "@baseboard_fab2_lib.baseboard_fab2(sch_1):p3e_pch_m2_tx_c_dn(1)" )
			)
			( signal "P3E_PCH_M2_TX_C_DN<2>"
				( objectStatus "@baseboard_fab2_lib.baseboard_fab2(sch_1):p3e_pch_m2_tx_c_dn(2)" )
			)
			( signal "P3E_PCH_M2_TX_C_DN<3>"
				( objectStatus "@baseboard_fab2_lib.baseboard_fab2(sch_1):p3e_pch_m2_tx_c_dn(3)" )
			)
			( signal "P3E_PCH_M2_TX_C_DP<1>"
				( objectStatus "@baseboard_fab2_lib.baseboard_fab2(sch_1):p3e_pch_m2_tx_c_dp(1)" )
			)
			( signal "P3E_PCH_M2_TX_C_DP<2>"
				( objectStatus "@baseboard_fab2_lib.baseboard_fab2(sch_1):p3e_pch_m2_tx_c_dp(2)" )
			)
			( signal "P3E_PCH_M2_TX_C_DP<3>"
				( objectStatus "@baseboard_fab2_lib.baseboard_fab2(sch_1):p3e_pch_m2_tx_c_dp(3)" )
			)
			( signal "PU_M2_CLK_REQ_N"
				( objectStatus "@baseboard_fab2_lib.baseboard_fab2(sch_1):pu_m2_clk_req_n" )
			)
			( signal "RST_PCIE_M2_DEV_N"
				( objectStatus "@baseboard_fab2_lib.baseboard_fab2(sch_1):rst_pcie_m2_dev_n" )
			)
			( signal "TP_LED_M2_ACT_N"
				( objectStatus "@baseboard_fab2_lib.baseboard_fab2(sch_1):tp_led_m2_act_n" )
			)
			( signal "TP_M2_32M_SUSCLK"
				( objectStatus "@baseboard_fab2_lib.baseboard_fab2(sch_1):tp_m2_32m_susclk" )
			)
			( signal "TP_M2_DEVSLP"
				( objectStatus "@baseboard_fab2_lib.baseboard_fab2(sch_1):tp_m2_devslp" )
			)
			( signal "FM_MEZZA_PRSNT1_N"
				( objectStatus "@baseboard_fab2_lib.baseboard_fab2(sch_1):fm_mezza_prsnt1_n" )
			)
			( signal "RMII_BMC_OCP_CRSDV_R"
				( objectStatus "@baseboard_fab2_lib.baseboard_fab2(sch_1):rmii_bmc_ocp_crsdv_r" )
			)
			( signal "RMII_BMC_OCP_RXD0_R"
				( objectStatus "@baseboard_fab2_lib.baseboard_fab2(sch_1):rmii_bmc_ocp_rxd0_r" )
			)
			( signal "RMII_BMC_OCP_RXD1_R"
				( objectStatus "@baseboard_fab2_lib.baseboard_fab2(sch_1):rmii_bmc_ocp_rxd1_r" )
			)
			( signal "RMII_BMC_OCP_RXER_R"
				( objectStatus "@baseboard_fab2_lib.baseboard_fab2(sch_1):rmii_bmc_ocp_rxer_r" )
			)
			( signal "RST_PCIE_CPU_DEV0_N"
				( objectStatus "@baseboard_fab2_lib.baseboard_fab2(sch_1):rst_pcie_cpu_dev0_n" )
			)
			( signal "RST_PCIE_CPU_DEV0_R_N"
				( objectStatus "@baseboard_fab2_lib.baseboard_fab2(sch_1):rst_pcie_cpu_dev0_r_n" )
			)
			( signal "FM_MEZZ_PRSNTB1_N"
				( objectStatus "@baseboard_fab2_lib.baseboard_fab2(sch_1):fm_mezz_prsntb1_n" )
			)
			( signal "RST_PCIE_CPU_DEV1_N"
				( objectStatus "@baseboard_fab2_lib.baseboard_fab2(sch_1):rst_pcie_cpu_dev1_n" )
			)
			( signal "RST_PCIE_CPU_DEV1_R_N"
				( objectStatus "@baseboard_fab2_lib.baseboard_fab2(sch_1):rst_pcie_cpu_dev1_r_n" )
			)
			( signal "RST_PCIE_CPU_DEV2_N"
				( objectStatus "@baseboard_fab2_lib.baseboard_fab2(sch_1):rst_pcie_cpu_dev2_n" )
			)
			( signal "RST_PCIE_CPU_DEV2_R_N"
				( objectStatus "@baseboard_fab2_lib.baseboard_fab2(sch_1):rst_pcie_cpu_dev2_r_n" )
			)
			( signal "RST_PCIE_CPU_DEV3_N"
				( objectStatus "@baseboard_fab2_lib.baseboard_fab2(sch_1):rst_pcie_cpu_dev3_n" )
			)
			( signal "RST_PCIE_CPU_DEV3_R_N"
				( objectStatus "@baseboard_fab2_lib.baseboard_fab2(sch_1):rst_pcie_cpu_dev3_r_n" )
			)
			( signal "TP_RSVD_B1"
				( objectStatus "@baseboard_fab2_lib.baseboard_fab2(sch_1):tp_rsvd_b1" )
			)
			( signal "KR_P0_OCP_RX_DN"
				( objectStatus "@baseboard_fab2_lib.baseboard_fab2(sch_1):kr_p0_ocp_rx_dn" )
			)
			( signal "KR_P0_OCP_RX_DP"
				( objectStatus "@baseboard_fab2_lib.baseboard_fab2(sch_1):kr_p0_ocp_rx_dp" )
			)
			( signal "KR_P1_OCP_RX_DN"
				( objectStatus "@baseboard_fab2_lib.baseboard_fab2(sch_1):kr_p1_ocp_rx_dn" )
			)
			( signal "KR_P1_OCP_RX_DP"
				( objectStatus "@baseboard_fab2_lib.baseboard_fab2(sch_1):kr_p1_ocp_rx_dp" )
			)
			( signal "KR_P2_OCP_RX_DN"
				( objectStatus "@baseboard_fab2_lib.baseboard_fab2(sch_1):kr_p2_ocp_rx_dn" )
			)
			( signal "KR_P2_OCP_RX_DP"
				( objectStatus "@baseboard_fab2_lib.baseboard_fab2(sch_1):kr_p2_ocp_rx_dp" )
			)
			( signal "KR_P3_OCP_RX_DN"
				( objectStatus "@baseboard_fab2_lib.baseboard_fab2(sch_1):kr_p3_ocp_rx_dn" )
			)
			( signal "KR_P3_OCP_RX_DP"
				( objectStatus "@baseboard_fab2_lib.baseboard_fab2(sch_1):kr_p3_ocp_rx_dp" )
			)
			( signal "TP_EXT_MDIO_I2C_SEL"
				( objectStatus "@baseboard_fab2_lib.baseboard_fab2(sch_1):tp_ext_mdio_i2c_sel" )
			)
			( signal "TP_RSVD<0>"
				( objectStatus "@baseboard_fab2_lib.baseboard_fab2(sch_1):tp_rsvd(0)" )
			)
			( signal "TP_SHARED_KR_MDC_0"
				( objectStatus "@baseboard_fab2_lib.baseboard_fab2(sch_1):tp_shared_kr_mdc_0" )
			)
			( signal "TP_SHARED_KR_MDIO_0"
				( objectStatus "@baseboard_fab2_lib.baseboard_fab2(sch_1):tp_shared_kr_mdio_0" )
			)
			( signal "FM_JTAG_PLD_EN_DEBUG"
				( objectStatus "@baseboard_fab2_lib.baseboard_fab2(sch_1):fm_jtag_pld_en_debug" )
			)
			( signal "JTAG_PLD_TCK"
				( objectStatus "@baseboard_fab2_lib.baseboard_fab2(sch_1):jtag_pld_tck" )
			)
			( signal "JTAG_PLD_TDI"
				( objectStatus "@baseboard_fab2_lib.baseboard_fab2(sch_1):jtag_pld_tdi" )
			)
			( signal "JTAG_PLD_TDO"
				( objectStatus "@baseboard_fab2_lib.baseboard_fab2(sch_1):jtag_pld_tdo" )
			)
			( signal "JTAG_PLD_TMS"
				( objectStatus "@baseboard_fab2_lib.baseboard_fab2(sch_1):jtag_pld_tms" )
			)
			( signal "JTAG_TCK"
				( objectStatus "@baseboard_fab2_lib.baseboard_fab2(sch_1):jtag_tck" )
			)
			( signal "JTAG_TCK_R"
				( objectStatus "@baseboard_fab2_lib.baseboard_fab2(sch_1):jtag_tck_r" )
			)
			( signal "JTAG_TDI"
				( objectStatus "@baseboard_fab2_lib.baseboard_fab2(sch_1):jtag_tdi" )
			)
			( signal "JTAG_TDI_R"
				( objectStatus "@baseboard_fab2_lib.baseboard_fab2(sch_1):jtag_tdi_r" )
			)
			( signal "JTAG_TDO"
				( objectStatus "@baseboard_fab2_lib.baseboard_fab2(sch_1):jtag_tdo" )
			)
			( signal "JTAG_TDO_R"
				( objectStatus "@baseboard_fab2_lib.baseboard_fab2(sch_1):jtag_tdo_r" )
			)
			( signal "JTAG_TMS"
				( objectStatus "@baseboard_fab2_lib.baseboard_fab2(sch_1):jtag_tms" )
			)
			( signal "JTAG_TMS_R"
				( objectStatus "@baseboard_fab2_lib.baseboard_fab2(sch_1):jtag_tms_r" )
			)
			( signal "JTAG_TRST_N"
				( objectStatus "@baseboard_fab2_lib.baseboard_fab2(sch_1):jtag_trst_n" )
			)
			( signal "P3V3_STBY_PLD_D"
				( attribute "VOLTAGE" "3.3"
					( Units "uVoltage" "V" 1.000000)
					( Status sAliasFlattened )
					( Origin gFrontEnd )
				)
				( objectStatus "@baseboard_fab2_lib.baseboard_fab2(sch_1):p3v3_stby_pld_d" )
			)
			( signal "FM_MEM_EVENT_FUNC"
				( objectStatus "@baseboard_fab2_lib.baseboard_fab2(sch_1):fm_mem_event_func" )
			)
			( signal "FM_PVCCIO_CPU0_EN"
				( objectStatus "@baseboard_fab2_lib.baseboard_fab2(sch_1):fm_pvccio_cpu0_en" )
			)
			( signal "FM_PVCCIO_CPU1_EN"
				( objectStatus "@baseboard_fab2_lib.baseboard_fab2(sch_1):fm_pvccio_cpu1_en" )
			)
			( signal "FM_PVCCIOMCP_CPU0_EN"
				( objectStatus "@baseboard_fab2_lib.baseboard_fab2(sch_1):fm_pvcciomcp_cpu0_en" )
			)
			( signal "FM_PVCCIOMCP_CPU1_EN"
				( objectStatus "@baseboard_fab2_lib.baseboard_fab2(sch_1):fm_pvcciomcp_cpu1_en" )
			)
			( signal "FM_PVCCMCP_CPU0_EN"
				( objectStatus "@baseboard_fab2_lib.baseboard_fab2(sch_1):fm_pvccmcp_cpu0_en" )
			)
			( signal "FM_PVCCMCP_CPU1_EN"
				( objectStatus "@baseboard_fab2_lib.baseboard_fab2(sch_1):fm_pvccmcp_cpu1_en" )
			)
			( signal "PU_RST_PERST_BIT0"
				( objectStatus "@baseboard_fab2_lib.baseboard_fab2(sch_1):pu_rst_perst_bit0" )
			)
			( signal "PWRGD_P5V"
				( objectStatus "@baseboard_fab2_lib.baseboard_fab2(sch_1):pwrgd_p5v" )
			)
			( signal "PWRGD_PVCCIN_CPU1"
				( objectStatus "@baseboard_fab2_lib.baseboard_fab2(sch_1):pwrgd_pvccin_cpu1" )
			)
			( signal "PWRGD_PVCCIO_CPU0"
				( objectStatus "@baseboard_fab2_lib.baseboard_fab2(sch_1):pwrgd_pvccio_cpu0" )
			)
			( signal "PWRGD_PVCCIOMCP_CPU0"
				( objectStatus "@baseboard_fab2_lib.baseboard_fab2(sch_1):pwrgd_pvcciomcp_cpu0" )
			)
			( signal "PWRGD_PVCCIOMCP_CPU1"
				( objectStatus "@baseboard_fab2_lib.baseboard_fab2(sch_1):pwrgd_pvcciomcp_cpu1" )
			)
			( signal "PWRGD_PVCCMCP_CPU0"
				( objectStatus "@baseboard_fab2_lib.baseboard_fab2(sch_1):pwrgd_pvccmcp_cpu0" )
			)
			( signal "PWRGD_PVCCMCP_CPU1"
				( objectStatus "@baseboard_fab2_lib.baseboard_fab2(sch_1):pwrgd_pvccmcp_cpu1" )
			)
			( signal "PWRGD_PVNN_P1V05_PCH"
				( objectStatus "@baseboard_fab2_lib.baseboard_fab2(sch_1):pwrgd_pvnn_p1v05_pch" )
			)
			( signal "PWRGD_PVPP_DEF"
				( objectStatus "@baseboard_fab2_lib.baseboard_fab2(sch_1):pwrgd_pvpp_def" )
			)
			( signal "PWRGD_PVPP_GHJ"
				( objectStatus "@baseboard_fab2_lib.baseboard_fab2(sch_1):pwrgd_pvpp_ghj" )
			)
			( signal "PWRGD_PVPP_KLM"
				( objectStatus "@baseboard_fab2_lib.baseboard_fab2(sch_1):pwrgd_pvpp_klm" )
			)
			( signal "PWRGD_PVSA_CPU0"
				( objectStatus "@baseboard_fab2_lib.baseboard_fab2(sch_1):pwrgd_pvsa_cpu0" )
			)
			( signal "PWRGD_PVSA_CPU1"
				( objectStatus "@baseboard_fab2_lib.baseboard_fab2(sch_1):pwrgd_pvsa_cpu1" )
			)
			( signal "PWRGD_PVTT_CPU1"
				( objectStatus "@baseboard_fab2_lib.baseboard_fab2(sch_1):pwrgd_pvtt_cpu1" )
			)
			( signal "RST_CPU0_LVC3_R1_N"
				( objectStatus "@baseboard_fab2_lib.baseboard_fab2(sch_1):rst_cpu0_lvc3_r1_n" )
			)
			( signal "RST_CPU1_LVC3_R1_N"
				( objectStatus "@baseboard_fab2_lib.baseboard_fab2(sch_1):rst_cpu1_lvc3_r1_n" )
			)
			( signal "RST_RSMRST_R_N"
				( objectStatus "@baseboard_fab2_lib.baseboard_fab2(sch_1):rst_rsmrst_r_n" )
			)
			( signal "TP_CPLD1_PB11B_PCLKC2_0"
				( objectStatus "@baseboard_fab2_lib.baseboard_fab2(sch_1):tp_cpld1_pb11b_pclkc2_0" )
			)
			( signal "TP_CPLD1_PB16A_PCLKT2_1"
				( objectStatus "@baseboard_fab2_lib.baseboard_fab2(sch_1):tp_cpld1_pb16a_pclkt2_1" )
			)
			( signal "TP_CPLD1_PB16B_PCLKC2_1"
				( objectStatus "@baseboard_fab2_lib.baseboard_fab2(sch_1):tp_cpld1_pb16b_pclkc2_1" )
			)
			( signal "TP_CPLD1_PB25B_SI_SISPI"
				( objectStatus "@baseboard_fab2_lib.baseboard_fab2(sch_1):tp_cpld1_pb25b_si_sispi" )
			)
			( signal "TP_CPLD1_PB5A_CSSPIN"
				( objectStatus "@baseboard_fab2_lib.baseboard_fab2(sch_1):tp_cpld1_pb5a_csspin" )
			)
			( signal "TP_CPLD1_PB8A_MCLK_CCLK"
				( objectStatus "@baseboard_fab2_lib.baseboard_fab2(sch_1):tp_cpld1_pb8a_mclk_cclk" )
			)
			( signal "TP_CPLD1_PB8B_SO_SPISO"
				( objectStatus "@baseboard_fab2_lib.baseboard_fab2(sch_1):tp_cpld1_pb8b_so_spiso" )
			)
			( signal "TP_CPLD1_PB8D"
				( objectStatus "@baseboard_fab2_lib.baseboard_fab2(sch_1):tp_cpld1_pb8d" )
			)
			( signal "TP_CPLD1_PL12B_PCLKC3_0"
				( objectStatus "@baseboard_fab2_lib.baseboard_fab2(sch_1):tp_cpld1_pl12b_pclkc3_0" )
			)
			( signal "TP_CPLD1_PL1A_L_GPLLT_FB"
				( objectStatus "@baseboard_fab2_lib.baseboard_fab2(sch_1):tp_cpld1_pl1a_l_gpllt_fb" )
			)
			( signal "TP_CPLD1_PL1B_L_GPLLC_FB"
				( objectStatus "@baseboard_fab2_lib.baseboard_fab2(sch_1):tp_cpld1_pl1b_l_gpllc_fb" )
			)
			( signal "TP_CPLD1_PL2B_L_GPLLC_IN"
				( objectStatus "@baseboard_fab2_lib.baseboard_fab2(sch_1):tp_cpld1_pl2b_l_gpllc_in" )
			)
			( signal "TP_CPLD1_PL7D_PCLKT4_0"
				( objectStatus "@baseboard_fab2_lib.baseboard_fab2(sch_1):tp_cpld1_pl7d_pclkt4_0" )
			)
			( signal "FM_ADR_SMI_GPIO_R_N"
				( objectStatus "@baseboard_fab2_lib.baseboard_fab2(sch_1):fm_adr_smi_gpio_r_n" )
			)
			( signal "FM_P12V_MAIN_SW_EN"
				( objectStatus "@baseboard_fab2_lib.baseboard_fab2(sch_1):fm_p12v_main_sw_en" )
			)
			( signal "FM_P1V8MCP_CPU0_EN"
				( objectStatus "@baseboard_fab2_lib.baseboard_fab2(sch_1):fm_p1v8mcp_cpu0_en" )
			)
			( signal "FM_P1V8MCP_CPU1_EN"
				( objectStatus "@baseboard_fab2_lib.baseboard_fab2(sch_1):fm_p1v8mcp_cpu1_en" )
			)
			( signal "FM_P3V3_CPLD_EN"
				( objectStatus "@baseboard_fab2_lib.baseboard_fab2(sch_1):fm_p3v3_cpld_en" )
			)
			( signal "FM_PLD_DEBUG_MODE_N"
				( objectStatus "@baseboard_fab2_lib.baseboard_fab2(sch_1):fm_pld_debug_mode_n" )
			)
			( signal "FM_PVCCIN_PVCCSA_CPU0_EN_LVC1"
				( objectStatus "@baseboard_fab2_lib.baseboard_fab2(sch_1):fm_pvccin_pvccsa_cpu0_en_lvc1" )
			)
			( signal "FM_PVCCIN_PVCCSA_CPU1_EN_LVC1"
				( objectStatus "@baseboard_fab2_lib.baseboard_fab2(sch_1):fm_pvccin_pvccsa_cpu1_en_lvc1" )
			)
			( signal "FM_PVDDQ_ABC_EN"
				( objectStatus "@baseboard_fab2_lib.baseboard_fab2(sch_1):fm_pvddq_abc_en" )
			)
			( signal "FM_PVDDQ_DEF_EN"
				( objectStatus "@baseboard_fab2_lib.baseboard_fab2(sch_1):fm_pvddq_def_en" )
			)
			( signal "FM_PVDDQ_GHJ_EN"
				( objectStatus "@baseboard_fab2_lib.baseboard_fab2(sch_1):fm_pvddq_ghj_en" )
			)
			( signal "FM_PVDDQ_KLM_EN"
				( objectStatus "@baseboard_fab2_lib.baseboard_fab2(sch_1):fm_pvddq_klm_en" )
			)
			( signal "FM_PVPP_CPU0_EN"
				( objectStatus "@baseboard_fab2_lib.baseboard_fab2(sch_1):fm_pvpp_cpu0_en" )
			)
			( signal "FM_PVPP_CPU1_EN"
				( objectStatus "@baseboard_fab2_lib.baseboard_fab2(sch_1):fm_pvpp_cpu1_en" )
			)
			( signal "FM_UV_ADR_TRIGGER_N"
				( objectStatus "@baseboard_fab2_lib.baseboard_fab2(sch_1):fm_uv_adr_trigger_n" )
			)
			( signal "PU_RST_PERST_BIT1"
				( objectStatus "@baseboard_fab2_lib.baseboard_fab2(sch_1):pu_rst_perst_bit1" )
			)
			( signal "PU_THERMTRIP_FORCE_N"
				( objectStatus "@baseboard_fab2_lib.baseboard_fab2(sch_1):pu_thermtrip_force_n" )
			)
			( signal "PWRGD_P12V_MAIN"
				( objectStatus "@baseboard_fab2_lib.baseboard_fab2(sch_1):pwrgd_p12v_main" )
			)
			( signal "PWRGD_P1V26_BMC_STBY"
				( objectStatus "@baseboard_fab2_lib.baseboard_fab2(sch_1):pwrgd_p1v26_bmc_stby" )
			)
			( signal "PWRGD_P1V8MCP_CPU0"
				( objectStatus "@baseboard_fab2_lib.baseboard_fab2(sch_1):pwrgd_p1v8mcp_cpu0" )
			)
			( signal "PWRGD_P1V8MCP_CPU1"
				( objectStatus "@baseboard_fab2_lib.baseboard_fab2(sch_1):pwrgd_p1v8mcp_cpu1" )
			)
			( signal "PWRGD_PVCCIO_CPU1"
				( objectStatus "@baseboard_fab2_lib.baseboard_fab2(sch_1):pwrgd_pvccio_cpu1" )
			)
			( signal "PWRGD_PVTT_CPU0"
				( objectStatus "@baseboard_fab2_lib.baseboard_fab2(sch_1):pwrgd_pvtt_cpu0" )
			)
			( signal "SGPIO_BMC_DIN_R"
				( objectStatus "@baseboard_fab2_lib.baseboard_fab2(sch_1):sgpio_bmc_din_r" )
			)
			( signal "TP_CPLD1_PR10C"
				( objectStatus "@baseboard_fab2_lib.baseboard_fab2(sch_1):tp_cpld1_pr10c" )
			)
			( signal "TP_CPLD1_PR11B"
				( objectStatus "@baseboard_fab2_lib.baseboard_fab2(sch_1):tp_cpld1_pr11b" )
			)
			( signal "TP_CPLD1_PR12D"
				( objectStatus "@baseboard_fab2_lib.baseboard_fab2(sch_1):tp_cpld1_pr12d" )
			)
			( signal "TP_CPLD1_PR7A_PCLKT1_0"
				( objectStatus "@baseboard_fab2_lib.baseboard_fab2(sch_1):tp_cpld1_pr7a_pclkt1_0" )
			)
			( signal "TP_CPLD1_PR7B_PCLKC1_0"
				( objectStatus "@baseboard_fab2_lib.baseboard_fab2(sch_1):tp_cpld1_pr7b_pclkc1_0" )
			)
			( signal "TP_CPLD1_PR7C"
				( objectStatus "@baseboard_fab2_lib.baseboard_fab2(sch_1):tp_cpld1_pr7c" )
			)
			( signal "TP_CPLD1_PR7D"
				( objectStatus "@baseboard_fab2_lib.baseboard_fab2(sch_1):tp_cpld1_pr7d" )
			)
			( signal "TP_CPLD1_PR9A"
				( objectStatus "@baseboard_fab2_lib.baseboard_fab2(sch_1):tp_cpld1_pr9a" )
			)
			( signal "TP_CPLD1_PR9C"
				( objectStatus "@baseboard_fab2_lib.baseboard_fab2(sch_1):tp_cpld1_pr9c" )
			)
			( signal "TP_CPLD1_PR9D"
				( objectStatus "@baseboard_fab2_lib.baseboard_fab2(sch_1):tp_cpld1_pr9d" )
			)
			( signal "TP_CPLD1_PT11A"
				( objectStatus "@baseboard_fab2_lib.baseboard_fab2(sch_1):tp_cpld1_pt11a" )
			)
			( signal "TP_CPLD1_PT11B"
				( objectStatus "@baseboard_fab2_lib.baseboard_fab2(sch_1):tp_cpld1_pt11b" )
			)
			( signal "TP_CPLD1_PT13A"
				( objectStatus "@baseboard_fab2_lib.baseboard_fab2(sch_1):tp_cpld1_pt13a" )
			)
			( signal "TP_CPLD1_PT16B"
				( objectStatus "@baseboard_fab2_lib.baseboard_fab2(sch_1):tp_cpld1_pt16b" )
			)
			( signal "TP_CPLD1_PT17B_PCLKC0_1"
				( objectStatus "@baseboard_fab2_lib.baseboard_fab2(sch_1):tp_cpld1_pt17b_pclkc0_1" )
			)
			( signal "TP_CPLD1_PT17C"
				( objectStatus "@baseboard_fab2_lib.baseboard_fab2(sch_1):tp_cpld1_pt17c" )
			)
			( signal "TP_CPLD1_PT19D"
				( objectStatus "@baseboard_fab2_lib.baseboard_fab2(sch_1):tp_cpld1_pt19d" )
			)
			( signal "TP_CPLD1_PT20A"
				( objectStatus "@baseboard_fab2_lib.baseboard_fab2(sch_1):tp_cpld1_pt20a" )
			)
			( signal "TP_CPLD1_PT20B"
				( objectStatus "@baseboard_fab2_lib.baseboard_fab2(sch_1):tp_cpld1_pt20b" )
			)
			( signal "TP_CPLD1_PT20D_PROGRAMN"
				( objectStatus "@baseboard_fab2_lib.baseboard_fab2(sch_1):tp_cpld1_pt20d_programn" )
			)
			( signal "TP_CPLD1_PT22C"
				( objectStatus "@baseboard_fab2_lib.baseboard_fab2(sch_1):tp_cpld1_pt22c" )
			)
			( signal "TP_CPLD1_PT22D"
				( objectStatus "@baseboard_fab2_lib.baseboard_fab2(sch_1):tp_cpld1_pt22d" )
			)
			( signal "TP_CPLD1_PT24B"
				( objectStatus "@baseboard_fab2_lib.baseboard_fab2(sch_1):tp_cpld1_pt24b" )
			)
			( signal "TP_CPLD1_PT24C_INITN"
				( objectStatus "@baseboard_fab2_lib.baseboard_fab2(sch_1):tp_cpld1_pt24c_initn" )
			)
			( signal "TP_CPLD1_PT24D_DONE"
				( objectStatus "@baseboard_fab2_lib.baseboard_fab2(sch_1):tp_cpld1_pt24d_done" )
			)
			( signal "NC_CPLD1"
				( objectStatus "@baseboard_fab2_lib.baseboard_fab2(sch_1):nc_cpld1" )
			)
			( signal "VR_PVCCIOMCP_CPU1_XADDR1"
				( objectStatus "@baseboard_fab2_lib.baseboard_fab2(sch_1):vr_pvcciomcp_cpu1_xaddr1" )
			)
			( signal "VR_PVCCMCP_CPU1_XADDR2"
				( objectStatus "@baseboard_fab2_lib.baseboard_fab2(sch_1):vr_pvccmcp_cpu1_xaddr2" )
			)
			( signal "VR_PVCCIOMCP_CPU0_XADDR1"
				( objectStatus "@baseboard_fab2_lib.baseboard_fab2(sch_1):vr_pvcciomcp_cpu0_xaddr1" )
			)
			( signal "VR_PVCCMCP_CPU0_XADDR2"
				( objectStatus "@baseboard_fab2_lib.baseboard_fab2(sch_1):vr_pvccmcp_cpu0_xaddr2" )
			)
			( signal "A_ADM1085_CEXT"
				( objectStatus "@baseboard_fab2_lib.baseboard_fab2(sch_1):a_adm1085_cext" )
			)
			( signal "A_PG_P12V_MAIN"
				( objectStatus "@baseboard_fab2_lib.baseboard_fab2(sch_1):a_pg_p12v_main" )
			)
			( signal "A_PG_P5V"
				( objectStatus "@baseboard_fab2_lib.baseboard_fab2(sch_1):a_pg_p5v" )
			)
			( signal "P3V_BAT_SOURCE"
				( attribute "VOLTAGE" "+3 V"
					( Units "uVoltage" "V" 1.000000)
					( Status sAliasFlattened )
					( Origin gFrontEnd )
				)
				( objectStatus "@baseboard_fab2_lib.baseboard_fab2(sch_1):p3v_bat_source" )
			)
			( signal "PWRGD_P12V_HSC"
				( objectStatus "@baseboard_fab2_lib.baseboard_fab2(sch_1):pwrgd_p12v_hsc" )
			)
			( signal "PWRGD_P12V_HSC_DLY_R"
				( objectStatus "@baseboard_fab2_lib.baseboard_fab2(sch_1):pwrgd_p12v_hsc_dly_r" )
			)
			( signal "PWRGD_P12V_MAIN_R"
				( objectStatus "@baseboard_fab2_lib.baseboard_fab2(sch_1):pwrgd_p12v_main_r" )
			)
			( signal "PWRGD_P3V3_R1"
				( objectStatus "@baseboard_fab2_lib.baseboard_fab2(sch_1):pwrgd_p3v3_r1" )
			)
			( signal "PWRGD_P5V_N"
				( objectStatus "@baseboard_fab2_lib.baseboard_fab2(sch_1):pwrgd_p5v_n" )
			)
			( signal "PWRGD_P5V_R"
				( objectStatus "@baseboard_fab2_lib.baseboard_fab2(sch_1):pwrgd_p5v_r" )
			)
			( signal "VSENSE_P12V_ADM1085"
				( objectStatus "@baseboard_fab2_lib.baseboard_fab2(sch_1):vsense_p12v_adm1085" )
			)
			( signal "VR_PVDDQ_ABC_AIINSEN"
				( objectStatus "@baseboard_fab2_lib.baseboard_fab2(sch_1):vr_pvddq_abc_aiinsen" )
			)
			( signal "VR_PVDDQ_ABC_AIINSEN_R"
				( objectStatus "@baseboard_fab2_lib.baseboard_fab2(sch_1):vr_pvddq_abc_aiinsen_r" )
			)
			( signal "VR_PVDDQ_DEF_AIINSEN"
				( objectStatus "@baseboard_fab2_lib.baseboard_fab2(sch_1):vr_pvddq_def_aiinsen" )
			)
			( signal "VR_PVDDQ_DEF_AIINSEN_R"
				( objectStatus "@baseboard_fab2_lib.baseboard_fab2(sch_1):vr_pvddq_def_aiinsen_r" )
			)
			( signal "VR_PVDDQ_GHJ_AIINSEN"
				( objectStatus "@baseboard_fab2_lib.baseboard_fab2(sch_1):vr_pvddq_ghj_aiinsen" )
			)
			( signal "VR_PVDDQ_GHJ_AIINSEN_R"
				( objectStatus "@baseboard_fab2_lib.baseboard_fab2(sch_1):vr_pvddq_ghj_aiinsen_r" )
			)
			( signal "VR_PVDDQ_KLM_AIINSEN"
				( objectStatus "@baseboard_fab2_lib.baseboard_fab2(sch_1):vr_pvddq_klm_aiinsen" )
			)
			( signal "VR_PVDDQ_KLM_AIINSEN_R"
				( objectStatus "@baseboard_fab2_lib.baseboard_fab2(sch_1):vr_pvddq_klm_aiinsen_r" )
			)
			( signal "P12V_FAN_SWITCH_G"
				( attribute "VOLTAGE" "+5V"
					( Units "uVoltage" "V" 1.000000)
					( Status sAliasFlattened )
					( Origin gFrontEnd )
				)
				( objectStatus "@baseboard_fab2_lib.baseboard_fab2(sch_1):p12v_fan_switch_g" )
			)
			( signal "P12V_SWITCH_G"
				( attribute "VOLTAGE" "+3.3V"
					( Units "uVoltage" "V" 1.000000)
					( Status sAliasFlattened )
					( Origin gFrontEnd )
				)
				( objectStatus "@baseboard_fab2_lib.baseboard_fab2(sch_1):p12v_switch_g" )
			)
			( signal "P3V3_SWITCH_G"
				( attribute "VOLTAGE" "3.3"
					( Units "uVoltage" "V" 1.000000)
					( Status sAliasFlattened )
					( Origin gFrontEnd )
				)
				( objectStatus "@baseboard_fab2_lib.baseboard_fab2(sch_1):p3v3_switch_g" )
			)
			( signal "P5V_SWITCH_G"
				( attribute "VOLTAGE" "+5V"
					( Units "uVoltage" "V" 1.000000)
					( Status sAliasFlattened )
					( Origin gFrontEnd )
				)
				( objectStatus "@baseboard_fab2_lib.baseboard_fab2(sch_1):p5v_switch_g" )
			)
			( signal "TP_SLG55021_P12V_FAN_8"
				( objectStatus "@baseboard_fab2_lib.baseboard_fab2(sch_1):tp_slg55021_p12v_fan_8" )
			)
			( signal "TP_SLG55021_P12V_MAIN_8"
				( objectStatus "@baseboard_fab2_lib.baseboard_fab2(sch_1):tp_slg55021_p12v_main_8" )
			)
			( signal "TP_SLG55021_P3V3_8"
				( objectStatus "@baseboard_fab2_lib.baseboard_fab2(sch_1):tp_slg55021_p3v3_8" )
			)
			( signal "TP_SLG55021_P5V_8"
				( objectStatus "@baseboard_fab2_lib.baseboard_fab2(sch_1):tp_slg55021_p5v_8" )
			)
			( signal "A_HSC_CSOUT"
				( objectStatus "@baseboard_fab2_lib.baseboard_fab2(sch_1):a_hsc_csout" )
			)
			( signal "A_HSC_GATE"
				( objectStatus "@baseboard_fab2_lib.baseboard_fab2(sch_1):a_hsc_gate" )
			)
			( signal "A_HSC_HIGH_EN"
				( objectStatus "@baseboard_fab2_lib.baseboard_fab2(sch_1):a_hsc_high_en" )
			)
			( signal "A_HSC_HSN"
				( objectStatus "@baseboard_fab2_lib.baseboard_fab2(sch_1):a_hsc_hsn" )
			)
			( signal "A_HSC_HSP"
				( objectStatus "@baseboard_fab2_lib.baseboard_fab2(sch_1):a_hsc_hsp" )
			)
			( signal "A_HSC_ISET"
				( objectStatus "@baseboard_fab2_lib.baseboard_fab2(sch_1):a_hsc_iset" )
			)
			( signal "A_HSC_ISET_S"
				( objectStatus "@baseboard_fab2_lib.baseboard_fab2(sch_1):a_hsc_iset_s" )
			)
			( signal "A_HSC_ISET_S2"
				( objectStatus "@baseboard_fab2_lib.baseboard_fab2(sch_1):a_hsc_iset_s2" )
			)
			( signal "A_HSC_ISTART"
				( objectStatus "@baseboard_fab2_lib.baseboard_fab2(sch_1):a_hsc_istart" )
			)
			( signal "AGND_HSC"
				( attribute "VOLTAGE" "0"
					( Units "uVoltage" "V" 1.000000)
					( Status sAliasFlattened )
					( Origin gFrontEnd )
				)
				( objectStatus "@baseboard_fab2_lib.baseboard_fab2(sch_1):agnd_hsc" )
			)
			( signal "A_HSC_LOW_EN"
				( objectStatus "@baseboard_fab2_lib.baseboard_fab2(sch_1):a_hsc_low_en" )
			)
			( signal "A_HSC_UV"
				( objectStatus "@baseboard_fab2_lib.baseboard_fab2(sch_1):a_hsc_uv" )
			)
			( signal "FM_P12V_HSC_ADR1"
				( objectStatus "@baseboard_fab2_lib.baseboard_fab2(sch_1):fm_p12v_hsc_adr1" )
			)
			( signal "A_HSC_TIMER"
				( objectStatus "@baseboard_fab2_lib.baseboard_fab2(sch_1):a_hsc_timer" )
			)
			( signal "A_HSC_MON"
				( objectStatus "@baseboard_fab2_lib.baseboard_fab2(sch_1):a_hsc_mon" )
			)
			( signal "A_HSC_MOP"
				( objectStatus "@baseboard_fab2_lib.baseboard_fab2(sch_1):a_hsc_mop" )
			)
			( signal "A_HSC_OCP_SEL"
				( objectStatus "@baseboard_fab2_lib.baseboard_fab2(sch_1):a_hsc_ocp_sel" )
			)
			( signal "A_HSC_OV"
				( objectStatus "@baseboard_fab2_lib.baseboard_fab2(sch_1):a_hsc_ov" )
			)
			( signal "A_HSC_PSET"
				( objectStatus "@baseboard_fab2_lib.baseboard_fab2(sch_1):a_hsc_pset" )
			)
			( signal "A_HSC_PWGIN"
				( objectStatus "@baseboard_fab2_lib.baseboard_fab2(sch_1):a_hsc_pwgin" )
			)
			( signal "A_HSC_TEMP"
				( objectStatus "@baseboard_fab2_lib.baseboard_fab2(sch_1):a_hsc_temp" )
			)
			( signal "A_HSC_VCAP"
				( objectStatus "@baseboard_fab2_lib.baseboard_fab2(sch_1):a_hsc_vcap" )
			)
			( signal "A_HSC_VOUT"
				( objectStatus "@baseboard_fab2_lib.baseboard_fab2(sch_1):a_hsc_vout" )
			)
			( signal "FM_P12V_HSC_ADR2"
				( objectStatus "@baseboard_fab2_lib.baseboard_fab2(sch_1):fm_p12v_hsc_adr2" )
			)
			( signal "IRQ_HSC_FAULT_R_N"
				( objectStatus "@baseboard_fab2_lib.baseboard_fab2(sch_1):irq_hsc_fault_r_n" )
			)
			( signal "IRQ_SML1_PMBUS_ALERT_R_N"
				( objectStatus "@baseboard_fab2_lib.baseboard_fab2(sch_1):irq_sml1_pmbus_alert_r_n" )
			)
			( signal "P12V_HSC_VCC"
				( attribute "VOLTAGE" "+12V"
					( Units "uVoltage" "V" 1.000000)
					( Status sAliasFlattened )
					( Origin gFrontEnd )
				)
				( objectStatus "@baseboard_fab2_lib.baseboard_fab2(sch_1):p12v_hsc_vcc" )
			)
			( signal "PD_HSC_RETRY_N"
				( objectStatus "@baseboard_fab2_lib.baseboard_fab2(sch_1):pd_hsc_retry_n" )
			)
			( signal "PWRGD_P12V_R"
				( objectStatus "@baseboard_fab2_lib.baseboard_fab2(sch_1):pwrgd_p12v_r" )
			)
			( signal "SMB_3V3SB_HSC_SCL_R"
				( objectStatus "@baseboard_fab2_lib.baseboard_fab2(sch_1):smb_3v3sb_hsc_scl_r" )
			)
			( signal "SMB_3V3SB_HSC_SDA_R"
				( objectStatus "@baseboard_fab2_lib.baseboard_fab2(sch_1):smb_3v3sb_hsc_sda_r" )
			)
			( signal "TP_HSC_ALERT2_N"
				( objectStatus "@baseboard_fab2_lib.baseboard_fab2(sch_1):tp_hsc_alert2_n" )
			)
			( signal "TP_HSC_MCLK"
				( objectStatus "@baseboard_fab2_lib.baseboard_fab2(sch_1):tp_hsc_mclk" )
			)
			( signal "TP_HSC_MDAT"
				( objectStatus "@baseboard_fab2_lib.baseboard_fab2(sch_1):tp_hsc_mdat" )
			)
			( signal "TP_HSC_SPISSN"
				( objectStatus "@baseboard_fab2_lib.baseboard_fab2(sch_1):tp_hsc_spissn" )
			)
			( signal "A_HSC_C"
				( objectStatus "@baseboard_fab2_lib.baseboard_fab2(sch_1):a_hsc_c" )
			)
			( signal "A_HSC_GATE1_R"
				( objectStatus "@baseboard_fab2_lib.baseboard_fab2(sch_1):a_hsc_gate1_r" )
			)
			( signal "A_HSC_GATE2_R"
				( objectStatus "@baseboard_fab2_lib.baseboard_fab2(sch_1):a_hsc_gate2_r" )
			)
			( signal "A_HSC_GATE3_R"
				( objectStatus "@baseboard_fab2_lib.baseboard_fab2(sch_1):a_hsc_gate3_r" )
			)
			( signal "A_HSC_HIGH"
				( objectStatus "@baseboard_fab2_lib.baseboard_fab2(sch_1):a_hsc_high" )
			)
			( signal "A_HSC_INAP"
				( objectStatus "@baseboard_fab2_lib.baseboard_fab2(sch_1):a_hsc_inap" )
			)
			( signal "A_HSC_LOW"
				( objectStatus "@baseboard_fab2_lib.baseboard_fab2(sch_1):a_hsc_low" )
			)
			( signal "A_HSC_LOW_DRAIN"
				( objectStatus "@baseboard_fab2_lib.baseboard_fab2(sch_1):a_hsc_low_drain" )
			)
			( signal "A_HSC_LOW_GATE"
				( objectStatus "@baseboard_fab2_lib.baseboard_fab2(sch_1):a_hsc_low_gate" )
			)
			( signal "A_HSC_TIMER_R"
				( objectStatus "@baseboard_fab2_lib.baseboard_fab2(sch_1):a_hsc_timer_r" )
			)
			( signal "A_P12V_STBY_ADR_TRIGGER"
				( objectStatus "@baseboard_fab2_lib.baseboard_fab2(sch_1):a_p12v_stby_adr_trigger" )
			)
			( signal "A_P12V_STBY_FP_TRIGGER"
				( objectStatus "@baseboard_fab2_lib.baseboard_fab2(sch_1):a_p12v_stby_fp_trigger" )
			)
			( signal "A_P12V_STBY_FPH_GATE"
				( objectStatus "@baseboard_fab2_lib.baseboard_fab2(sch_1):a_p12v_stby_fph_gate" )
			)
			( signal "FM_OC_DETECT_EN"
				( objectStatus "@baseboard_fab2_lib.baseboard_fab2(sch_1):fm_oc_detect_en" )
			)
			( signal "P12V_HSC_SENN0"
				( attribute "VOLTAGE" "+12V"
					( Units "uVoltage" "V" 1.000000)
					( Status sAliasFlattened )
					( Origin gFrontEnd )
				)
				( objectStatus "@baseboard_fab2_lib.baseboard_fab2(sch_1):p12v_hsc_senn0" )
			)
			( signal "P12V_HSC_SENN1"
				( attribute "VOLTAGE" "+12V"
					( Units "uVoltage" "V" 1.000000)
					( Status sAliasFlattened )
					( Origin gFrontEnd )
				)
				( objectStatus "@baseboard_fab2_lib.baseboard_fab2(sch_1):p12v_hsc_senn1" )
			)
			( signal "P12V_HSC_SENP0"
				( attribute "VOLTAGE" "+12V"
					( Units "uVoltage" "V" 1.000000)
					( Status sAliasFlattened )
					( Origin gFrontEnd )
				)
				( objectStatus "@baseboard_fab2_lib.baseboard_fab2(sch_1):p12v_hsc_senp0" )
			)
			( signal "P12V_HSC_SENP1"
				( attribute "VOLTAGE" "+12V"
					( Units "uVoltage" "V" 1.000000)
					( Status sAliasFlattened )
					( Origin gFrontEnd )
				)
				( objectStatus "@baseboard_fab2_lib.baseboard_fab2(sch_1):p12v_hsc_senp1" )
			)
			( signal "P12V_MB0_SW"
				( attribute "VOLTAGE" "+12V"
					( Units "uVoltage" "V" 1.000000)
					( Status sAliasFlattened )
					( Origin gFrontEnd )
				)
				( objectStatus "@baseboard_fab2_lib.baseboard_fab2(sch_1):p12v_mb0_sw" )
			)
			( signal "IRQ_PVCCIN_CPU0_VRHOT_LVC3_R_N"
				( objectStatus "@baseboard_fab2_lib.baseboard_fab2(sch_1):irq_pvccin_cpu0_vrhot_lvc3_r_n" )
			)
			( signal "ISENSE_PVCCIN_CPU0_PH1_IMON"
				( objectStatus "@baseboard_fab2_lib.baseboard_fab2(sch_1):isense_pvccin_cpu0_ph1_imon" )
			)
			( signal "ISENSE_PVCCIN_CPU0_PH2_IMON"
				( objectStatus "@baseboard_fab2_lib.baseboard_fab2(sch_1):isense_pvccin_cpu0_ph2_imon" )
			)
			( signal "ISENSE_PVCCIN_CPU0_PH3_IMON"
				( objectStatus "@baseboard_fab2_lib.baseboard_fab2(sch_1):isense_pvccin_cpu0_ph3_imon" )
			)
			( signal "ISENSE_PVCCIN_CPU0_PH4_IMON"
				( objectStatus "@baseboard_fab2_lib.baseboard_fab2(sch_1):isense_pvccin_cpu0_ph4_imon" )
			)
			( signal "ISENSE_PVCCIN_CPU0_PH5_IMON"
				( objectStatus "@baseboard_fab2_lib.baseboard_fab2(sch_1):isense_pvccin_cpu0_ph5_imon" )
			)
			( signal "ISENSE_PVSA_CPU0_IMON"
				( objectStatus "@baseboard_fab2_lib.baseboard_fab2(sch_1):isense_pvsa_cpu0_imon" )
			)
			( signal "PU_VR_PVCCIN_CPU0_FLT1_SMBALT_N"
				( objectStatus "@baseboard_fab2_lib.baseboard_fab2(sch_1):pu_vr_pvccin_cpu0_flt1_smbalt_n_imon" )
			)
			( signal "PU_VR_PVCCIN_CPU0_IMON"
				( objectStatus "@baseboard_fab2_lib.baseboard_fab2(sch_1):pu_vr_pvccin_cpu0_imon" )
			)
			( signal "PVCCIN_PVSA_CPU0_IINSEN"
				( attribute "VOLTAGE" "+3.3V"
					( Units "uVoltage" "V" 1.000000)
					( Status sAliasFlattened )
					( Origin gFrontEnd )
				)
				( objectStatus "@baseboard_fab2_lib.baseboard_fab2(sch_1):pvccin_pvsa_cpu0_iinsen" )
			)
			( signal "PWRGD_PVSA_CPU0_R"
				( objectStatus "@baseboard_fab2_lib.baseboard_fab2(sch_1):pwrgd_pvsa_cpu0_r" )
			)
			( signal "SMB_VR_SCL_R"
				( objectStatus "@baseboard_fab2_lib.baseboard_fab2(sch_1):smb_vr_scl_r" )
			)
			( signal "SMB_VR_SDA_R"
				( objectStatus "@baseboard_fab2_lib.baseboard_fab2(sch_1):smb_vr_sda_r" )
			)
			( signal "SVID_VALERT_VCCIN_CPU0"
				( objectStatus "@baseboard_fab2_lib.baseboard_fab2(sch_1):svid_valert_vccin_cpu0" )
			)
			( signal "SVID_VCLK_PVCCIN_CPU0"
				( objectStatus "@baseboard_fab2_lib.baseboard_fab2(sch_1):svid_vclk_pvccin_cpu0" )
			)
			( signal "SVID_VDIO_PVCCIN_CPU0"
				( objectStatus "@baseboard_fab2_lib.baseboard_fab2(sch_1):svid_vdio_pvccin_cpu0" )
			)
			( signal "TP_PVCCIN_CPU0_AIREF6"
				( objectStatus "@baseboard_fab2_lib.baseboard_fab2(sch_1):tp_pvccin_cpu0_airef6" )
			)
			( signal "TP_PVCCIN_CPU0_AISEN6"
				( objectStatus "@baseboard_fab2_lib.baseboard_fab2(sch_1):tp_pvccin_cpu0_aisen6" )
			)
			( signal "TP_PVCCIN_CPU0_APWM6"
				( objectStatus "@baseboard_fab2_lib.baseboard_fab2(sch_1):tp_pvccin_cpu0_apwm6" )
			)
			( signal "TP_PVCCIN_CPU0_FAULT1_20"
				( objectStatus "@baseboard_fab2_lib.baseboard_fab2(sch_1):tp_pvccin_cpu0_fault1_20" )
			)
			( signal "TP_PVCCIN_CPU0_GP1"
				( objectStatus "@baseboard_fab2_lib.baseboard_fab2(sch_1):tp_pvccin_cpu0_gp1" )
			)
			( signal "TP_PVCCIN_CPU0_RESET"
				( objectStatus "@baseboard_fab2_lib.baseboard_fab2(sch_1):tp_pvccin_cpu0_reset" )
			)
			( signal "VR_FET_SW_P12V_STBY_PVCCIN_CPU0"
				( objectStatus "@baseboard_fab2_lib.baseboard_fab2(sch_1):vr_fet_sw_p12v_stby_pvccin_cpu0" )
			)
			( signal "VR_PVCCIN_CPU0_AIREF1"
				( objectStatus "@baseboard_fab2_lib.baseboard_fab2(sch_1):vr_pvccin_cpu0_airef1" )
			)
			( signal "VR_PVCCIN_CPU0_AIREF2"
				( objectStatus "@baseboard_fab2_lib.baseboard_fab2(sch_1):vr_pvccin_cpu0_airef2" )
			)
			( signal "VR_PVCCIN_CPU0_AIREF3"
				( objectStatus "@baseboard_fab2_lib.baseboard_fab2(sch_1):vr_pvccin_cpu0_airef3" )
			)
			( signal "VR_PVCCIN_CPU0_AIREF4"
				( objectStatus "@baseboard_fab2_lib.baseboard_fab2(sch_1):vr_pvccin_cpu0_airef4" )
			)
			( signal "VR_PVCCIN_CPU0_AIREF5"
				( objectStatus "@baseboard_fab2_lib.baseboard_fab2(sch_1):vr_pvccin_cpu0_airef5" )
			)
			( signal "VR_PVCCIN_CPU0_AVINSEN"
				( attribute "VOLTAGE" "0.8"
					( Units "uVoltage" "V" 1.000000)
					( Status sAliasFlattened )
					( Origin gFrontEnd )
				)
				( objectStatus "@baseboard_fab2_lib.baseboard_fab2(sch_1):vr_pvccin_cpu0_avinsen" )
			)
			( signal "VR_PVCCIN_CPU0_PWM1"
				( attribute "VOLTAGE" "3.6"
					( Units "uVoltage" "V" 1.000000)
					( Status sAliasFlattened )
					( Origin gFrontEnd )
				)
				( objectStatus "@baseboard_fab2_lib.baseboard_fab2(sch_1):vr_pvccin_cpu0_pwm1" )
			)
			( signal "VR_PVCCIN_CPU0_PWM2"
				( attribute "VOLTAGE" "3.6"
					( Units "uVoltage" "V" 1.000000)
					( Status sAliasFlattened )
					( Origin gFrontEnd )
				)
				( objectStatus "@baseboard_fab2_lib.baseboard_fab2(sch_1):vr_pvccin_cpu0_pwm2" )
			)
			( signal "VR_PVCCIN_CPU0_PWM3"
				( attribute "VOLTAGE" "3.6"
					( Units "uVoltage" "V" 1.000000)
					( Status sAliasFlattened )
					( Origin gFrontEnd )
				)
				( objectStatus "@baseboard_fab2_lib.baseboard_fab2(sch_1):vr_pvccin_cpu0_pwm3" )
			)
			( signal "VR_PVCCIN_CPU0_PWM4"
				( attribute "VOLTAGE" "3.6"
					( Units "uVoltage" "V" 1.000000)
					( Status sAliasFlattened )
					( Origin gFrontEnd )
				)
				( objectStatus "@baseboard_fab2_lib.baseboard_fab2(sch_1):vr_pvccin_cpu0_pwm4" )
			)
			( signal "VR_PVCCIN_CPU0_PWM5"
				( attribute "VOLTAGE" "3.6"
					( Units "uVoltage" "V" 1.000000)
					( Status sAliasFlattened )
					( Origin gFrontEnd )
				)
				( objectStatus "@baseboard_fab2_lib.baseboard_fab2(sch_1):vr_pvccin_cpu0_pwm5" )
			)
			( signal "VR_PVCCIN_CPU0_VD12"
				( objectStatus "@baseboard_fab2_lib.baseboard_fab2(sch_1):vr_pvccin_cpu0_vd12" )
			)
			( signal "VR_PVCCIN_CPU0_VDD"
				( attribute "VOLTAGE" "3.3"
					( Units "uVoltage" "V" 1.000000)
					( Status sAliasFlattened )
					( Origin gFrontEnd )
				)
				( objectStatus "@baseboard_fab2_lib.baseboard_fab2(sch_1):vr_pvccin_cpu0_vdd" )
			)
			( signal "VR_PVCCIN_CPU0_VREN"
				( attribute "VOLTAGE" "3.3"
					( Units "uVoltage" "V" 1.000000)
					( Status sAliasFlattened )
					( Origin gFrontEnd )
				)
				( objectStatus "@baseboard_fab2_lib.baseboard_fab2(sch_1):vr_pvccin_cpu0_vren" )
			)
			( signal "VR_PVCCIN_CPU0_XADDR1"
				( attribute "VOLTAGE" "3.3"
					( Units "uVoltage" "V" 1.000000)
					( Status sAliasFlattened )
					( Origin gFrontEnd )
				)
				( objectStatus "@baseboard_fab2_lib.baseboard_fab2(sch_1):vr_pvccin_cpu0_xaddr1" )
			)
			( signal "VR_PVCCIN_CPU0_XADDR2"
				( attribute "VOLTAGE" "3.3"
					( Units "uVoltage" "V" 1.000000)
					( Status sAliasFlattened )
					( Origin gFrontEnd )
				)
				( objectStatus "@baseboard_fab2_lib.baseboard_fab2(sch_1):vr_pvccin_cpu0_xaddr2" )
			)
			( signal "VR_PVSA_CPU0_BIREF1"
				( objectStatus "@baseboard_fab2_lib.baseboard_fab2(sch_1):vr_pvsa_cpu0_biref1" )
			)
			( signal "VR_PVSA_CPU0_PWM"
				( objectStatus "@baseboard_fab2_lib.baseboard_fab2(sch_1):vr_pvsa_cpu0_pwm" )
			)
			( signal "VR_VRRDY_PVCCIN_CPU0"
				( attribute "VOLTAGE" "3.3"
					( Units "uVoltage" "V" 1.000000)
					( Status sAliasFlattened )
					( Origin gFrontEnd )
				)
				( objectStatus "@baseboard_fab2_lib.baseboard_fab2(sch_1):vr_vrrdy_pvccin_cpu0" )
			)
			( signal "VSENSE_PVCCIN_CPU0_AVSP"
				( attribute "VOLTAGE" "2"
					( Units "uVoltage" "V" 1.000000)
					( Status sAliasFlattened )
					( Origin gFrontEnd )
				)
				( objectStatus "@baseboard_fab2_lib.baseboard_fab2(sch_1):vsense_pvccin_cpu0_avsp" )
			)
			( signal "VSENSE_PVCCIN_CPU0_N"
				( attribute "VOLTAGE" "2"
					( Units "uVoltage" "V" 1.000000)
					( Status sAliasFlattened )
					( Origin gFrontEnd )
				)
				( objectStatus "@baseboard_fab2_lib.baseboard_fab2(sch_1):vsense_pvccin_cpu0_n" )
			)
			( signal "VSENSE_PVCCIN_CPU0_P"
				( attribute "VOLTAGE" "2"
					( Units "uVoltage" "V" 1.000000)
					( Status sAliasFlattened )
					( Origin gFrontEnd )
				)
				( objectStatus "@baseboard_fab2_lib.baseboard_fab2(sch_1):vsense_pvccin_cpu0_p" )
			)
			( signal "VSENSE_PVSA_CPU0_BVSP"
				( objectStatus "@baseboard_fab2_lib.baseboard_fab2(sch_1):vsense_pvsa_cpu0_bvsp" )
			)
			( signal "VSENSE_PVSA_CPU0_N"
				( objectStatus "@baseboard_fab2_lib.baseboard_fab2(sch_1):vsense_pvsa_cpu0_n" )
			)
			( signal "VSENSE_PVSA_CPU0_P"
				( objectStatus "@baseboard_fab2_lib.baseboard_fab2(sch_1):vsense_pvsa_cpu0_p" )
			)
			( signal "NC_PVCCIN_CPU0_PH1_P31"
				( objectStatus "@baseboard_fab2_lib.baseboard_fab2(sch_1):nc_pvccin_cpu0_ph1_p31" )
			)
			( signal "NC_PVCCIN_CPU0_PH2_P31"
				( objectStatus "@baseboard_fab2_lib.baseboard_fab2(sch_1):nc_pvccin_cpu0_ph2_p31" )
			)
			( signal "TP_PVCCIN_CPU0_PH1_GL_0"
				( objectStatus "@baseboard_fab2_lib.baseboard_fab2(sch_1):tp_pvccin_cpu0_ph1_gl_0" )
			)
			( signal "TP_PVCCIN_CPU0_PH1_GL_1"
				( objectStatus "@baseboard_fab2_lib.baseboard_fab2(sch_1):tp_pvccin_cpu0_ph1_gl_1" )
			)
			( signal "TP_PVCCIN_CPU0_PH2_GL_0"
				( objectStatus "@baseboard_fab2_lib.baseboard_fab2(sch_1):tp_pvccin_cpu0_ph2_gl_0" )
			)
			( signal "TP_PVCCIN_CPU0_PH2_GL_1"
				( objectStatus "@baseboard_fab2_lib.baseboard_fab2(sch_1):tp_pvccin_cpu0_ph2_gl_1" )
			)
			( signal "VR_PVCCIN_CPU0_PH1_BOOT"
				( attribute "VOLTAGE" "5"
					( Units "uVoltage" "V" 1.000000)
					( Status sAliasFlattened )
					( Origin gFrontEnd )
				)
				( objectStatus "@baseboard_fab2_lib.baseboard_fab2(sch_1):vr_pvccin_cpu0_ph1_boot" )
			)
			( signal "VR_PVCCIN_CPU0_PH1_OCSET"
				( attribute "VOLTAGE" "3.6"
					( Units "uVoltage" "V" 1.000000)
					( Status sAliasFlattened )
					( Origin gFrontEnd )
				)
				( objectStatus "@baseboard_fab2_lib.baseboard_fab2(sch_1):vr_pvccin_cpu0_ph1_ocset" )
			)
			( signal "VR_PVCCIN_CPU0_PH1_PHASE"
				( attribute "VOLTAGE" "5"
					( Units "uVoltage" "V" 1.000000)
					( Status sAliasFlattened )
					( Origin gFrontEnd )
				)
				( objectStatus "@baseboard_fab2_lib.baseboard_fab2(sch_1):vr_pvccin_cpu0_ph1_phase" )
			)
			( signal "VR_PVCCIN_CPU0_PH1_VCIN"
				( attribute "VOLTAGE" "5"
					( Units "uVoltage" "V" 1.000000)
					( Status sAliasFlattened )
					( Origin gFrontEnd )
				)
				( objectStatus "@baseboard_fab2_lib.baseboard_fab2(sch_1):vr_pvccin_cpu0_ph1_vcin" )
			)
			( signal "VR_PVCCIN_CPU0_PH2_BOOT"
				( attribute "VOLTAGE" "5"
					( Units "uVoltage" "V" 1.000000)
					( Status sAliasFlattened )
					( Origin gFrontEnd )
				)
				( objectStatus "@baseboard_fab2_lib.baseboard_fab2(sch_1):vr_pvccin_cpu0_ph2_boot" )
			)
			( signal "VR_PVCCIN_CPU0_PH2_OCSET"
				( attribute "VOLTAGE" "3.6"
					( Units "uVoltage" "V" 1.000000)
					( Status sAliasFlattened )
					( Origin gFrontEnd )
				)
				( objectStatus "@baseboard_fab2_lib.baseboard_fab2(sch_1):vr_pvccin_cpu0_ph2_ocset" )
			)
			( signal "VR_PVCCIN_CPU0_PH2_PHASE"
				( attribute "VOLTAGE" "5"
					( Units "uVoltage" "V" 1.000000)
					( Status sAliasFlattened )
					( Origin gFrontEnd )
				)
				( objectStatus "@baseboard_fab2_lib.baseboard_fab2(sch_1):vr_pvccin_cpu0_ph2_phase" )
			)
			( signal "VR_PVCCIN_CPU0_PH2_VCIN"
				( attribute "VOLTAGE" "5"
					( Units "uVoltage" "V" 1.000000)
					( Status sAliasFlattened )
					( Origin gFrontEnd )
				)
				( objectStatus "@baseboard_fab2_lib.baseboard_fab2(sch_1):vr_pvccin_cpu0_ph2_vcin" )
			)
			( signal "VR_PVCCIN_CPU0_PHASE1"
				( attribute "VOLTAGE" "5"
					( Units "uVoltage" "V" 1.000000)
					( Status sAliasFlattened )
					( Origin gFrontEnd )
				)
				( objectStatus "@baseboard_fab2_lib.baseboard_fab2(sch_1):vr_pvccin_cpu0_phase1" )
			)
			( signal "VR_PVCCIN_CPU0_PHASE2"
				( attribute "VOLTAGE" "5"
					( Units "uVoltage" "V" 1.000000)
					( Status sAliasFlattened )
					( Origin gFrontEnd )
				)
				( objectStatus "@baseboard_fab2_lib.baseboard_fab2(sch_1):vr_pvccin_cpu0_phase2" )
			)
			( signal "NC_PVCCIN_CPU0_PH3_P31"
				( objectStatus "@baseboard_fab2_lib.baseboard_fab2(sch_1):nc_pvccin_cpu0_ph3_p31" )
			)
			( signal "NC_PVCCIN_CPU0_PH4_P31"
				( objectStatus "@baseboard_fab2_lib.baseboard_fab2(sch_1):nc_pvccin_cpu0_ph4_p31" )
			)
			( signal "TP_PVCCIN_CPU0_PH3_GL_0"
				( objectStatus "@baseboard_fab2_lib.baseboard_fab2(sch_1):tp_pvccin_cpu0_ph3_gl_0" )
			)
			( signal "TP_PVCCIN_CPU0_PH3_GL_1"
				( objectStatus "@baseboard_fab2_lib.baseboard_fab2(sch_1):tp_pvccin_cpu0_ph3_gl_1" )
			)
			( signal "TP_PVCCIN_CPU0_PH4_GL_0"
				( objectStatus "@baseboard_fab2_lib.baseboard_fab2(sch_1):tp_pvccin_cpu0_ph4_gl_0" )
			)
			( signal "TP_PVCCIN_CPU0_PH4_GL_1"
				( objectStatus "@baseboard_fab2_lib.baseboard_fab2(sch_1):tp_pvccin_cpu0_ph4_gl_1" )
			)
			( signal "VR_PVCCIN_CPU0_PH3_BOOT"
				( attribute "VOLTAGE" "5"
					( Units "uVoltage" "V" 1.000000)
					( Status sAliasFlattened )
					( Origin gFrontEnd )
				)
				( objectStatus "@baseboard_fab2_lib.baseboard_fab2(sch_1):vr_pvccin_cpu0_ph3_boot" )
			)
			( signal "VR_PVCCIN_CPU0_PH3_OCSET"
				( attribute "VOLTAGE" "3.6"
					( Units "uVoltage" "V" 1.000000)
					( Status sAliasFlattened )
					( Origin gFrontEnd )
				)
				( objectStatus "@baseboard_fab2_lib.baseboard_fab2(sch_1):vr_pvccin_cpu0_ph3_ocset" )
			)
			( signal "VR_PVCCIN_CPU0_PH3_PHASE"
				( attribute "VOLTAGE" "5"
					( Units "uVoltage" "V" 1.000000)
					( Status sAliasFlattened )
					( Origin gFrontEnd )
				)
				( objectStatus "@baseboard_fab2_lib.baseboard_fab2(sch_1):vr_pvccin_cpu0_ph3_phase" )
			)
			( signal "VR_PVCCIN_CPU0_PH3_VCIN"
				( objectStatus "@baseboard_fab2_lib.baseboard_fab2(sch_1):vr_pvccin_cpu0_ph3_vcin" )
			)
			( signal "VR_PVCCIN_CPU0_PH4_BOOT"
				( attribute "VOLTAGE" "5"
					( Units "uVoltage" "V" 1.000000)
					( Status sAliasFlattened )
					( Origin gFrontEnd )
				)
				( objectStatus "@baseboard_fab2_lib.baseboard_fab2(sch_1):vr_pvccin_cpu0_ph4_boot" )
			)
			( signal "VR_PVCCIN_CPU0_PH4_OCSET"
				( attribute "VOLTAGE" "3.6"
					( Units "uVoltage" "V" 1.000000)
					( Status sAliasFlattened )
					( Origin gFrontEnd )
				)
				( objectStatus "@baseboard_fab2_lib.baseboard_fab2(sch_1):vr_pvccin_cpu0_ph4_ocset" )
			)
			( signal "VR_PVCCIN_CPU0_PH4_PHASE"
				( attribute "VOLTAGE" "5"
					( Units "uVoltage" "V" 1.000000)
					( Status sAliasFlattened )
					( Origin gFrontEnd )
				)
				( objectStatus "@baseboard_fab2_lib.baseboard_fab2(sch_1):vr_pvccin_cpu0_ph4_phase" )
			)
			( signal "VR_PVCCIN_CPU0_PH4_VCIN"
				( attribute "VOLTAGE" "5"
					( Units "uVoltage" "V" 1.000000)
					( Status sAliasFlattened )
					( Origin gFrontEnd )
				)
				( objectStatus "@baseboard_fab2_lib.baseboard_fab2(sch_1):vr_pvccin_cpu0_ph4_vcin" )
			)
			( signal "VR_PVCCIN_CPU0_PHASE3"
				( attribute "VOLTAGE" "5"
					( Units "uVoltage" "V" 1.000000)
					( Status sAliasFlattened )
					( Origin gFrontEnd )
				)
				( objectStatus "@baseboard_fab2_lib.baseboard_fab2(sch_1):vr_pvccin_cpu0_phase3" )
			)
			( signal "VR_PVCCIN_CPU0_PHASE4"
				( attribute "VOLTAGE" "5"
					( Units "uVoltage" "V" 1.000000)
					( Status sAliasFlattened )
					( Origin gFrontEnd )
				)
				( objectStatus "@baseboard_fab2_lib.baseboard_fab2(sch_1):vr_pvccin_cpu0_phase4" )
			)
			( signal "NC_PVCCIN_CPU0_PH5_P31"
				( objectStatus "@baseboard_fab2_lib.baseboard_fab2(sch_1):nc_pvccin_cpu0_ph5_p31" )
			)
			( signal "TP_PVCCIN_CPU0_PH5_GL_0"
				( objectStatus "@baseboard_fab2_lib.baseboard_fab2(sch_1):tp_pvccin_cpu0_ph5_gl_0" )
			)
			( signal "TP_PVCCIN_CPU0_PH5_GL_1"
				( objectStatus "@baseboard_fab2_lib.baseboard_fab2(sch_1):tp_pvccin_cpu0_ph5_gl_1" )
			)
			( signal "VR_FET_SW_P12V_PVCCIN_CPU0_R"
				( objectStatus "@baseboard_fab2_lib.baseboard_fab2(sch_1):vr_fet_sw_p12v_pvccin_cpu0_r" )
			)
			( signal "VR_PVCCIN_CPU0_PH5_BOOT"
				( attribute "VOLTAGE" "5"
					( Units "uVoltage" "V" 1.000000)
					( Status sAliasFlattened )
					( Origin gFrontEnd )
				)
				( objectStatus "@baseboard_fab2_lib.baseboard_fab2(sch_1):vr_pvccin_cpu0_ph5_boot" )
			)
			( signal "VR_PVCCIN_CPU0_PH5_OCSET"
				( attribute "VOLTAGE" "3.6"
					( Units "uVoltage" "V" 1.000000)
					( Status sAliasFlattened )
					( Origin gFrontEnd )
				)
				( objectStatus "@baseboard_fab2_lib.baseboard_fab2(sch_1):vr_pvccin_cpu0_ph5_ocset" )
			)
			( signal "VR_PVCCIN_CPU0_PH5_PHASE"
				( attribute "VOLTAGE" "5"
					( Units "uVoltage" "V" 1.000000)
					( Status sAliasFlattened )
					( Origin gFrontEnd )
				)
				( objectStatus "@baseboard_fab2_lib.baseboard_fab2(sch_1):vr_pvccin_cpu0_ph5_phase" )
			)
			( signal "VR_PVCCIN_CPU0_PH5_VCIN"
				( attribute "VOLTAGE" "5"
					( Units "uVoltage" "V" 1.000000)
					( Status sAliasFlattened )
					( Origin gFrontEnd )
				)
				( objectStatus "@baseboard_fab2_lib.baseboard_fab2(sch_1):vr_pvccin_cpu0_ph5_vcin" )
			)
			( signal "VR_PVCCIN_CPU0_PHASE5"
				( attribute "VOLTAGE" "5"
					( Units "uVoltage" "V" 1.000000)
					( Status sAliasFlattened )
					( Origin gFrontEnd )
				)
				( objectStatus "@baseboard_fab2_lib.baseboard_fab2(sch_1):vr_pvccin_cpu0_phase5" )
			)
			( signal "NC_PVSA_CPU0_P31"
				( objectStatus "@baseboard_fab2_lib.baseboard_fab2(sch_1):nc_pvsa_cpu0_p31" )
			)
			( signal "TP_PVSA_CPU0_GL_0"
				( objectStatus "@baseboard_fab2_lib.baseboard_fab2(sch_1):tp_pvsa_cpu0_gl_0" )
			)
			( signal "TP_PVSA_CPU0_GL_1"
				( objectStatus "@baseboard_fab2_lib.baseboard_fab2(sch_1):tp_pvsa_cpu0_gl_1" )
			)
			( signal "VR_PVSA_CPU0_BOOT"
				( attribute "VOLTAGE" "5"
					( Units "uVoltage" "V" 1.000000)
					( Status sAliasFlattened )
					( Origin gFrontEnd )
				)
				( objectStatus "@baseboard_fab2_lib.baseboard_fab2(sch_1):vr_pvsa_cpu0_boot" )
			)
			( signal "VR_PVSA_CPU0_OCSET"
				( objectStatus "@baseboard_fab2_lib.baseboard_fab2(sch_1):vr_pvsa_cpu0_ocset" )
			)
			( signal "VR_PVSA_CPU0_PHASE"
				( attribute "VOLTAGE" "5"
					( Units "uVoltage" "V" 1.000000)
					( Status sAliasFlattened )
					( Origin gFrontEnd )
				)
				( objectStatus "@baseboard_fab2_lib.baseboard_fab2(sch_1):vr_pvsa_cpu0_phase" )
			)
			( signal "VR_PVSA_CPU0_PHASE_SW"
				( attribute "VOLTAGE" "5"
					( Units "uVoltage" "V" 1.000000)
					( Status sAliasFlattened )
					( Origin gFrontEnd )
				)
				( objectStatus "@baseboard_fab2_lib.baseboard_fab2(sch_1):vr_pvsa_cpu0_phase_sw" )
			)
			( signal "VR_PVSA_CPU0_VCIN"
				( attribute "VOLTAGE" "5"
					( Units "uVoltage" "V" 1.000000)
					( Status sAliasFlattened )
					( Origin gFrontEnd )
				)
				( objectStatus "@baseboard_fab2_lib.baseboard_fab2(sch_1):vr_pvsa_cpu0_vcin" )
			)
			( signal "IRQ_PVCCIN_CPU1_VRHOT_LVC3_R_N"
				( objectStatus "@baseboard_fab2_lib.baseboard_fab2(sch_1):irq_pvccin_cpu1_vrhot_lvc3_r_n" )
			)
			( signal "ISENSE_PVCCIN_CPU1_PH1_IMON"
				( objectStatus "@baseboard_fab2_lib.baseboard_fab2(sch_1):isense_pvccin_cpu1_ph1_imon" )
			)
			( signal "ISENSE_PVCCIN_CPU1_PH2_IMON"
				( objectStatus "@baseboard_fab2_lib.baseboard_fab2(sch_1):isense_pvccin_cpu1_ph2_imon" )
			)
			( signal "ISENSE_PVCCIN_CPU1_PH3_IMON"
				( objectStatus "@baseboard_fab2_lib.baseboard_fab2(sch_1):isense_pvccin_cpu1_ph3_imon" )
			)
			( signal "ISENSE_PVCCIN_CPU1_PH4_IMON"
				( objectStatus "@baseboard_fab2_lib.baseboard_fab2(sch_1):isense_pvccin_cpu1_ph4_imon" )
			)
			( signal "ISENSE_PVCCIN_CPU1_PH5_IMON"
				( objectStatus "@baseboard_fab2_lib.baseboard_fab2(sch_1):isense_pvccin_cpu1_ph5_imon" )
			)
			( signal "ISENSE_PVSA_CPU1_IMON"
				( objectStatus "@baseboard_fab2_lib.baseboard_fab2(sch_1):isense_pvsa_cpu1_imon" )
			)
			( signal "PU_VR_PVCCIN_CPU1_FLT1_SMBALT_N"
				( objectStatus "@baseboard_fab2_lib.baseboard_fab2(sch_1):pu_vr_pvccin_cpu1_flt1_smbalt_n_imon" )
			)
			( signal "PU_VR_PVCCIN_CPU1_IMON"
				( objectStatus "@baseboard_fab2_lib.baseboard_fab2(sch_1):pu_vr_pvccin_cpu1_imon" )
			)
			( signal "PVCCIN_PVSA_CPU1_IINSEN"
				( attribute "VOLTAGE" "+1.5V"
					( Units "uVoltage" "V" 1.000000)
					( Status sAliasFlattened )
					( Origin gFrontEnd )
				)
				( objectStatus "@baseboard_fab2_lib.baseboard_fab2(sch_1):pvccin_pvsa_cpu1_iinsen" )
			)
			( signal "PWRGD_PVSA_CPU1_R"
				( objectStatus "@baseboard_fab2_lib.baseboard_fab2(sch_1):pwrgd_pvsa_cpu1_r" )
			)
			( signal "SMB_VR_SCL_R1"
				( objectStatus "@baseboard_fab2_lib.baseboard_fab2(sch_1):smb_vr_scl_r1" )
			)
			( signal "SMB_VR_SDA_R1"
				( objectStatus "@baseboard_fab2_lib.baseboard_fab2(sch_1):smb_vr_sda_r1" )
			)
			( signal "SVID_VALERT_VCCIN_CPU1"
				( objectStatus "@baseboard_fab2_lib.baseboard_fab2(sch_1):svid_valert_vccin_cpu1" )
			)
			( signal "SVID_VCLK_PVCCIN_CPU1"
				( objectStatus "@baseboard_fab2_lib.baseboard_fab2(sch_1):svid_vclk_pvccin_cpu1" )
			)
			( signal "SVID_VDIO_PVCCIN_CPU1"
				( objectStatus "@baseboard_fab2_lib.baseboard_fab2(sch_1):svid_vdio_pvccin_cpu1" )
			)
			( signal "TP_PVCCIN_CPU1_AIREF6"
				( objectStatus "@baseboard_fab2_lib.baseboard_fab2(sch_1):tp_pvccin_cpu1_airef6" )
			)
			( signal "TP_PVCCIN_CPU1_AISEN6"
				( objectStatus "@baseboard_fab2_lib.baseboard_fab2(sch_1):tp_pvccin_cpu1_aisen6" )
			)
			( signal "TP_PVCCIN_CPU1_APWM6"
				( objectStatus "@baseboard_fab2_lib.baseboard_fab2(sch_1):tp_pvccin_cpu1_apwm6" )
			)
			( signal "TP_PVCCIN_CPU1_FAULT1_20"
				( objectStatus "@baseboard_fab2_lib.baseboard_fab2(sch_1):tp_pvccin_cpu1_fault1_20" )
			)
			( signal "TP_PVCCIN_CPU1_GP1"
				( objectStatus "@baseboard_fab2_lib.baseboard_fab2(sch_1):tp_pvccin_cpu1_gp1" )
			)
			( signal "TP_PVCCIN_CPU1_RESET_N"
				( objectStatus "@baseboard_fab2_lib.baseboard_fab2(sch_1):tp_pvccin_cpu1_reset_n" )
			)
			( signal "A_TSENSE_PVDDQ_KLM"
				( objectStatus "@baseboard_fab2_lib.baseboard_fab2(sch_1):a_tsense_pvddq_klm" )
			)
			( signal "A_TSENSE_PVNN_PCH_TMON"
				( objectStatus "@baseboard_fab2_lib.baseboard_fab2(sch_1):a_tsense_pvnn_pch_tmon" )
			)
			( signal "VR_FET_SW_P12V_STBY_PVCCIN_CPU1"
				( attribute "VOLTAGE" "12"
					( Units "uVoltage" "V" 1.000000)
					( Status sAliasFlattened )
					( Origin gFrontEnd )
				)
				( objectStatus "@baseboard_fab2_lib.baseboard_fab2(sch_1):vr_fet_sw_p12v_stby_pvccin_cpu1" )
			)
			( signal "VR_PVCCIN_CPU1_AIREF1"
				( objectStatus "@baseboard_fab2_lib.baseboard_fab2(sch_1):vr_pvccin_cpu1_airef1" )
			)
			( signal "VR_PVCCIN_CPU1_AIREF2"
				( objectStatus "@baseboard_fab2_lib.baseboard_fab2(sch_1):vr_pvccin_cpu1_airef2" )
			)
			( signal "VR_PVCCIN_CPU1_AIREF3"
				( objectStatus "@baseboard_fab2_lib.baseboard_fab2(sch_1):vr_pvccin_cpu1_airef3" )
			)
			( signal "VR_PVCCIN_CPU1_AIREF4"
				( objectStatus "@baseboard_fab2_lib.baseboard_fab2(sch_1):vr_pvccin_cpu1_airef4" )
			)
			( signal "VR_PVCCIN_CPU1_AIREF5"
				( objectStatus "@baseboard_fab2_lib.baseboard_fab2(sch_1):vr_pvccin_cpu1_airef5" )
			)
			( signal "VR_PVCCIN_CPU1_AVINSEN"
				( attribute "VOLTAGE" "0.8"
					( Units "uVoltage" "V" 1.000000)
					( Status sAliasFlattened )
					( Origin gFrontEnd )
				)
				( objectStatus "@baseboard_fab2_lib.baseboard_fab2(sch_1):vr_pvccin_cpu1_avinsen" )
			)
			( signal "VR_PVCCIN_CPU1_PWM1"
				( attribute "VOLTAGE" "3.6"
					( Units "uVoltage" "V" 1.000000)
					( Status sAliasFlattened )
					( Origin gFrontEnd )
				)
				( objectStatus "@baseboard_fab2_lib.baseboard_fab2(sch_1):vr_pvccin_cpu1_pwm1" )
			)
			( signal "VR_PVCCIN_CPU1_PWM2"
				( attribute "VOLTAGE" "3.6"
					( Units "uVoltage" "V" 1.000000)
					( Status sAliasFlattened )
					( Origin gFrontEnd )
				)
				( objectStatus "@baseboard_fab2_lib.baseboard_fab2(sch_1):vr_pvccin_cpu1_pwm2" )
			)
			( signal "VR_PVCCIN_CPU1_PWM3"
				( attribute "VOLTAGE" "3.6"
					( Units "uVoltage" "V" 1.000000)
					( Status sAliasFlattened )
					( Origin gFrontEnd )
				)
				( objectStatus "@baseboard_fab2_lib.baseboard_fab2(sch_1):vr_pvccin_cpu1_pwm3" )
			)
			( signal "VR_PVCCIN_CPU1_PWM4"
				( attribute "VOLTAGE" "3.6"
					( Units "uVoltage" "V" 1.000000)
					( Status sAliasFlattened )
					( Origin gFrontEnd )
				)
				( objectStatus "@baseboard_fab2_lib.baseboard_fab2(sch_1):vr_pvccin_cpu1_pwm4" )
			)
			( signal "VR_PVCCIN_CPU1_PWM5"
				( attribute "VOLTAGE" "3.6"
					( Units "uVoltage" "V" 1.000000)
					( Status sAliasFlattened )
					( Origin gFrontEnd )
				)
				( objectStatus "@baseboard_fab2_lib.baseboard_fab2(sch_1):vr_pvccin_cpu1_pwm5" )
			)
			( signal "VR_PVCCIN_CPU1_VD12"
				( objectStatus "@baseboard_fab2_lib.baseboard_fab2(sch_1):vr_pvccin_cpu1_vd12" )
			)
			( signal "VR_PVCCIN_CPU1_VDD"
				( attribute "VOLTAGE" "3.3"
					( Units "uVoltage" "V" 1.000000)
					( Status sAliasFlattened )
					( Origin gFrontEnd )
				)
				( objectStatus "@baseboard_fab2_lib.baseboard_fab2(sch_1):vr_pvccin_cpu1_vdd" )
			)
			( signal "VR_PVCCIN_CPU1_VREN"
				( attribute "VOLTAGE" "3.3"
					( Units "uVoltage" "V" 1.000000)
					( Status sAliasFlattened )
					( Origin gFrontEnd )
				)
				( objectStatus "@baseboard_fab2_lib.baseboard_fab2(sch_1):vr_pvccin_cpu1_vren" )
			)
			( signal "VR_PVCCIN_CPU1_XADDR1"
				( attribute "VOLTAGE" "3.3"
					( Units "uVoltage" "V" 1.000000)
					( Status sAliasFlattened )
					( Origin gFrontEnd )
				)
				( objectStatus "@baseboard_fab2_lib.baseboard_fab2(sch_1):vr_pvccin_cpu1_xaddr1" )
			)
			( signal "VR_PVCCIN_CPU1_XADDR2"
				( attribute "VOLTAGE" "3.3"
					( Units "uVoltage" "V" 1.000000)
					( Status sAliasFlattened )
					( Origin gFrontEnd )
				)
				( objectStatus "@baseboard_fab2_lib.baseboard_fab2(sch_1):vr_pvccin_cpu1_xaddr2" )
			)
			( signal "VR_PVSA_CPU1_BIREF1"
				( objectStatus "@baseboard_fab2_lib.baseboard_fab2(sch_1):vr_pvsa_cpu1_biref1" )
			)
			( signal "VR_PVSA_CPU1_PWM"
				( attribute "VOLTAGE" "3.6"
					( Units "uVoltage" "V" 1.000000)
					( Status sAliasFlattened )
					( Origin gFrontEnd )
				)
				( objectStatus "@baseboard_fab2_lib.baseboard_fab2(sch_1):vr_pvsa_cpu1_pwm" )
			)
			( signal "VR_VRRDY_PVCCIN_CPU1"
				( objectStatus "@baseboard_fab2_lib.baseboard_fab2(sch_1):vr_vrrdy_pvccin_cpu1" )
			)
			( signal "VSENSE_PVCCIN_CPU1_AVSP"
				( objectStatus "@baseboard_fab2_lib.baseboard_fab2(sch_1):vsense_pvccin_cpu1_avsp" )
			)
			( signal "VSENSE_PVCCIN_CPU1_N"
				( attribute "VOLTAGE" "0.3"
					( Units "uVoltage" "V" 1.000000)
					( Status sAliasFlattened )
					( Origin gFrontEnd )
				)
				( objectStatus "@baseboard_fab2_lib.baseboard_fab2(sch_1):vsense_pvccin_cpu1_n" )
			)
			( signal "VSENSE_PVCCIN_CPU1_P"
				( attribute "VOLTAGE" "2.0"
					( Units "uVoltage" "V" 1.000000)
					( Status sAliasFlattened )
					( Origin gFrontEnd )
				)
				( objectStatus "@baseboard_fab2_lib.baseboard_fab2(sch_1):vsense_pvccin_cpu1_p" )
			)
			( signal "VSENSE_PVSA_CPU1_BVSP"
				( objectStatus "@baseboard_fab2_lib.baseboard_fab2(sch_1):vsense_pvsa_cpu1_bvsp" )
			)
			( signal "VSENSE_PVSA_CPU1_N"
				( attribute "VOLTAGE" "0.3"
					( Units "uVoltage" "V" 1.000000)
					( Status sAliasFlattened )
					( Origin gFrontEnd )
				)
				( objectStatus "@baseboard_fab2_lib.baseboard_fab2(sch_1):vsense_pvsa_cpu1_n" )
			)
			( signal "VSENSE_PVSA_CPU1_P"
				( attribute "VOLTAGE" "1.0"
					( Units "uVoltage" "V" 1.000000)
					( Status sAliasFlattened )
					( Origin gFrontEnd )
				)
				( objectStatus "@baseboard_fab2_lib.baseboard_fab2(sch_1):vsense_pvsa_cpu1_p" )
			)
			( signal "NC_PVCCIN_CPU1_PH1_P31"
				( objectStatus "@baseboard_fab2_lib.baseboard_fab2(sch_1):nc_pvccin_cpu1_ph1_p31" )
			)
			( signal "NC_PVCCIN_CPU1_PH2_P31"
				( objectStatus "@baseboard_fab2_lib.baseboard_fab2(sch_1):nc_pvccin_cpu1_ph2_p31" )
			)
			( signal "TP_PVCCINC_CPU1_PH1_GL_0"
				( objectStatus "@baseboard_fab2_lib.baseboard_fab2(sch_1):tp_pvccinc_cpu1_ph1_gl_0" )
			)
			( signal "TP_PVCCINC_CPU1_PH1_GL_1"
				( objectStatus "@baseboard_fab2_lib.baseboard_fab2(sch_1):tp_pvccinc_cpu1_ph1_gl_1" )
			)
			( signal "TP_PVCCINC_CPU1_PH2_GL_0"
				( objectStatus "@baseboard_fab2_lib.baseboard_fab2(sch_1):tp_pvccinc_cpu1_ph2_gl_0" )
			)
			( signal "TP_PVCCINC_CPU1_PH2_GL_1"
				( objectStatus "@baseboard_fab2_lib.baseboard_fab2(sch_1):tp_pvccinc_cpu1_ph2_gl_1" )
			)
			( signal "VR_PVCCIN_CPU1_PH1_BOOT"
				( attribute "VOLTAGE" "5"
					( Units "uVoltage" "V" 1.000000)
					( Status sAliasFlattened )
					( Origin gFrontEnd )
				)
				( objectStatus "@baseboard_fab2_lib.baseboard_fab2(sch_1):vr_pvccin_cpu1_ph1_boot" )
			)
			( signal "VR_PVCCIN_CPU1_PH1_OCSET"
				( objectStatus "@baseboard_fab2_lib.baseboard_fab2(sch_1):vr_pvccin_cpu1_ph1_ocset" )
			)
			( signal "VR_PVCCIN_CPU1_PH1_PHASE"
				( attribute "VOLTAGE" "5"
					( Units "uVoltage" "V" 1.000000)
					( Status sAliasFlattened )
					( Origin gFrontEnd )
				)
				( objectStatus "@baseboard_fab2_lib.baseboard_fab2(sch_1):vr_pvccin_cpu1_ph1_phase" )
			)
			( signal "VR_PVCCIN_CPU1_PH1_VCIN"
				( attribute "VOLTAGE" "5"
					( Units "uVoltage" "V" 1.000000)
					( Status sAliasFlattened )
					( Origin gFrontEnd )
				)
				( objectStatus "@baseboard_fab2_lib.baseboard_fab2(sch_1):vr_pvccin_cpu1_ph1_vcin" )
			)
			( signal "VR_PVCCIN_CPU1_PH2_BOOT"
				( attribute "VOLTAGE" "5"
					( Units "uVoltage" "V" 1.000000)
					( Status sAliasFlattened )
					( Origin gFrontEnd )
				)
				( objectStatus "@baseboard_fab2_lib.baseboard_fab2(sch_1):vr_pvccin_cpu1_ph2_boot" )
			)
			( signal "VR_PVCCIN_CPU1_PH2_OCSET"
				( objectStatus "@baseboard_fab2_lib.baseboard_fab2(sch_1):vr_pvccin_cpu1_ph2_ocset" )
			)
			( signal "VR_PVCCIN_CPU1_PH2_PHASE"
				( attribute "VOLTAGE" "5"
					( Units "uVoltage" "V" 1.000000)
					( Status sAliasFlattened )
					( Origin gFrontEnd )
				)
				( objectStatus "@baseboard_fab2_lib.baseboard_fab2(sch_1):vr_pvccin_cpu1_ph2_phase" )
			)
			( signal "VR_PVCCIN_CPU1_PH2_VCIN"
				( attribute "VOLTAGE" "5"
					( Units "uVoltage" "V" 1.000000)
					( Status sAliasFlattened )
					( Origin gFrontEnd )
				)
				( objectStatus "@baseboard_fab2_lib.baseboard_fab2(sch_1):vr_pvccin_cpu1_ph2_vcin" )
			)
			( signal "VR_PVCCIN_CPU1_PHASE1"
				( attribute "VOLTAGE" "5"
					( Units "uVoltage" "V" 1.000000)
					( Status sAliasFlattened )
					( Origin gFrontEnd )
				)
				( objectStatus "@baseboard_fab2_lib.baseboard_fab2(sch_1):vr_pvccin_cpu1_phase1" )
			)
			( signal "VR_PVCCIN_CPU1_PHASE2"
				( attribute "VOLTAGE" "5"
					( Units "uVoltage" "V" 1.000000)
					( Status sAliasFlattened )
					( Origin gFrontEnd )
				)
				( objectStatus "@baseboard_fab2_lib.baseboard_fab2(sch_1):vr_pvccin_cpu1_phase2" )
			)
			( signal "NC_PVCCIN_CPU1_PH3_P31"
				( objectStatus "@baseboard_fab2_lib.baseboard_fab2(sch_1):nc_pvccin_cpu1_ph3_p31" )
			)
			( signal "NC_PVCCIN_CPU1_PH4_P31"
				( objectStatus "@baseboard_fab2_lib.baseboard_fab2(sch_1):nc_pvccin_cpu1_ph4_p31" )
			)
			( signal "TP_PVCCIN_CPU1_PH3_GL_0"
				( objectStatus "@baseboard_fab2_lib.baseboard_fab2(sch_1):tp_pvccin_cpu1_ph3_gl_0" )
			)
			( signal "TP_PVCCIN_CPU1_PH3_GL_1"
				( objectStatus "@baseboard_fab2_lib.baseboard_fab2(sch_1):tp_pvccin_cpu1_ph3_gl_1" )
			)
			( signal "TP_PVCCIN_CPU1_PH4_GL_0"
				( objectStatus "@baseboard_fab2_lib.baseboard_fab2(sch_1):tp_pvccin_cpu1_ph4_gl_0" )
			)
			( signal "TP_PVCCIN_CPU1_PH4_GL_1"
				( objectStatus "@baseboard_fab2_lib.baseboard_fab2(sch_1):tp_pvccin_cpu1_ph4_gl_1" )
			)
			( signal "VR_PVCCIN_CPU1_PH3_BOOT"
				( objectStatus "@baseboard_fab2_lib.baseboard_fab2(sch_1):vr_pvccin_cpu1_ph3_boot" )
			)
			( signal "VR_PVCCIN_CPU1_PH3_OCSET"
				( objectStatus "@baseboard_fab2_lib.baseboard_fab2(sch_1):vr_pvccin_cpu1_ph3_ocset" )
			)
			( signal "VR_PVCCIN_CPU1_PH3_PHASE"
				( objectStatus "@baseboard_fab2_lib.baseboard_fab2(sch_1):vr_pvccin_cpu1_ph3_phase" )
			)
			( signal "VR_PVCCIN_CPU1_PH3_VCIN"
				( attribute "VOLTAGE" "5"
					( Units "uVoltage" "V" 1.000000)
					( Status sAliasFlattened )
					( Origin gFrontEnd )
				)
				( objectStatus "@baseboard_fab2_lib.baseboard_fab2(sch_1):vr_pvccin_cpu1_ph3_vcin" )
			)
			( signal "VR_PVCCIN_CPU1_PH4_BOOT"
				( objectStatus "@baseboard_fab2_lib.baseboard_fab2(sch_1):vr_pvccin_cpu1_ph4_boot" )
			)
			( signal "VR_PVCCIN_CPU1_PH4_OCSET"
				( objectStatus "@baseboard_fab2_lib.baseboard_fab2(sch_1):vr_pvccin_cpu1_ph4_ocset" )
			)
			( signal "VR_PVCCIN_CPU1_PH4_PHASE"
				( attribute "VOLTAGE" "5"
					( Units "uVoltage" "V" 1.000000)
					( Status sAliasFlattened )
					( Origin gFrontEnd )
				)
				( objectStatus "@baseboard_fab2_lib.baseboard_fab2(sch_1):vr_pvccin_cpu1_ph4_phase" )
			)
			( signal "VR_PVCCIN_CPU1_PH4_VCIN"
				( attribute "VOLTAGE" "5"
					( Units "uVoltage" "V" 1.000000)
					( Status sAliasFlattened )
					( Origin gFrontEnd )
				)
				( objectStatus "@baseboard_fab2_lib.baseboard_fab2(sch_1):vr_pvccin_cpu1_ph4_vcin" )
			)
			( signal "VR_PVCCIN_CPU1_PHASE3"
				( attribute "VOLTAGE" "5"
					( Units "uVoltage" "V" 1.000000)
					( Status sAliasFlattened )
					( Origin gFrontEnd )
				)
				( objectStatus "@baseboard_fab2_lib.baseboard_fab2(sch_1):vr_pvccin_cpu1_phase3" )
			)
			( signal "VR_PVCCIN_CPU1_PHASE4"
				( attribute "VOLTAGE" "5"
					( Units "uVoltage" "V" 1.000000)
					( Status sAliasFlattened )
					( Origin gFrontEnd )
				)
				( objectStatus "@baseboard_fab2_lib.baseboard_fab2(sch_1):vr_pvccin_cpu1_phase4" )
			)
			( signal "NC_PVCCIN_CPU1_PH5_P31"
				( objectStatus "@baseboard_fab2_lib.baseboard_fab2(sch_1):nc_pvccin_cpu1_ph5_p31" )
			)
			( signal "TP_PVCCIN_CPU1_PH5_GL_0"
				( objectStatus "@baseboard_fab2_lib.baseboard_fab2(sch_1):tp_pvccin_cpu1_ph5_gl_0" )
			)
			( signal "TP_PVCCIN_CPU1_PH5_GL_1"
				( objectStatus "@baseboard_fab2_lib.baseboard_fab2(sch_1):tp_pvccin_cpu1_ph5_gl_1" )
			)
			( signal "VR_FET_SW_P12V_PVCCIN_CPU1_R"
				( objectStatus "@baseboard_fab2_lib.baseboard_fab2(sch_1):vr_fet_sw_p12v_pvccin_cpu1_r" )
			)
			( signal "VR_PVCCIN_CPU1_PH5_BOOT"
				( attribute "VOLTAGE" "5"
					( Units "uVoltage" "V" 1.000000)
					( Status sAliasFlattened )
					( Origin gFrontEnd )
				)
				( objectStatus "@baseboard_fab2_lib.baseboard_fab2(sch_1):vr_pvccin_cpu1_ph5_boot" )
			)
			( signal "VR_PVCCIN_CPU1_PH5_OCSET"
				( objectStatus "@baseboard_fab2_lib.baseboard_fab2(sch_1):vr_pvccin_cpu1_ph5_ocset" )
			)
			( signal "VR_PVCCIN_CPU1_PH5_PHASE"
				( attribute "VOLTAGE" "5"
					( Units "uVoltage" "V" 1.000000)
					( Status sAliasFlattened )
					( Origin gFrontEnd )
				)
				( objectStatus "@baseboard_fab2_lib.baseboard_fab2(sch_1):vr_pvccin_cpu1_ph5_phase" )
			)
			( signal "VR_PVCCIN_CPU1_PH5_VCIN"
				( attribute "VOLTAGE" "5"
					( Units "uVoltage" "V" 1.000000)
					( Status sAliasFlattened )
					( Origin gFrontEnd )
				)
				( objectStatus "@baseboard_fab2_lib.baseboard_fab2(sch_1):vr_pvccin_cpu1_ph5_vcin" )
			)
			( signal "VR_PVCCIN_CPU1_PHASE5"
				( attribute "VOLTAGE" "5"
					( Units "uVoltage" "V" 1.000000)
					( Status sAliasFlattened )
					( Origin gFrontEnd )
				)
				( objectStatus "@baseboard_fab2_lib.baseboard_fab2(sch_1):vr_pvccin_cpu1_phase5" )
			)
			( signal "NC_PVSA_CPU1_P31"
				( objectStatus "@baseboard_fab2_lib.baseboard_fab2(sch_1):nc_pvsa_cpu1_p31" )
			)
			( signal "TP_PVSA_CPU1_GL_0"
				( objectStatus "@baseboard_fab2_lib.baseboard_fab2(sch_1):tp_pvsa_cpu1_gl_0" )
			)
			( signal "TP_PVSA_CPU1_GL_1"
				( objectStatus "@baseboard_fab2_lib.baseboard_fab2(sch_1):tp_pvsa_cpu1_gl_1" )
			)
			( signal "VR_PVSA_CPU1_BOOT"
				( attribute "VOLTAGE" "5"
					( Units "uVoltage" "V" 1.000000)
					( Status sAliasFlattened )
					( Origin gFrontEnd )
				)
				( objectStatus "@baseboard_fab2_lib.baseboard_fab2(sch_1):vr_pvsa_cpu1_boot" )
			)
			( signal "VR_PVSA_CPU1_OCSET"
				( objectStatus "@baseboard_fab2_lib.baseboard_fab2(sch_1):vr_pvsa_cpu1_ocset" )
			)
			( signal "VR_PVSA_CPU1_PHASE"
				( attribute "VOLTAGE" "5"
					( Units "uVoltage" "V" 1.000000)
					( Status sAliasFlattened )
					( Origin gFrontEnd )
				)
				( objectStatus "@baseboard_fab2_lib.baseboard_fab2(sch_1):vr_pvsa_cpu1_phase" )
			)
			( signal "VR_PVSA_CPU1_PHASE_SW"
				( attribute "VOLTAGE" "5"
					( Units "uVoltage" "V" 1.000000)
					( Status sAliasFlattened )
					( Origin gFrontEnd )
				)
				( objectStatus "@baseboard_fab2_lib.baseboard_fab2(sch_1):vr_pvsa_cpu1_phase_sw" )
			)
			( signal "VR_PVSA_CPU1_VCIN"
				( attribute "VOLTAGE" "5"
					( Units "uVoltage" "V" 1.000000)
					( Status sAliasFlattened )
					( Origin gFrontEnd )
				)
				( objectStatus "@baseboard_fab2_lib.baseboard_fab2(sch_1):vr_pvsa_cpu1_vcin" )
			)
			( signal "IRQ_PVCCIO_CPU0_VRHOT_N"
				( objectStatus "@baseboard_fab2_lib.baseboard_fab2(sch_1):irq_pvccio_cpu0_vrhot_n" )
			)
			( signal "ISENSE_PVCCIO_CPU0_PH1_IMON"
				( attribute "VOLTAGE" "3.6"
					( Units "uVoltage" "V" 1.000000)
					( Status sAliasFlattened )
					( Origin gFrontEnd )
				)
				( objectStatus "@baseboard_fab2_lib.baseboard_fab2(sch_1):isense_pvccio_cpu0_ph1_imon" )
			)
			( signal "NC_PVCCIO_CPU0_DNC0"
				( objectStatus "@baseboard_fab2_lib.baseboard_fab2(sch_1):nc_pvccio_cpu0_dnc0" )
			)
			( signal "NC_PVCCIO_CPU0_DNC1"
				( objectStatus "@baseboard_fab2_lib.baseboard_fab2(sch_1):nc_pvccio_cpu0_dnc1" )
			)
			( signal "NC_PVCCIO_CPU0_DNC2"
				( objectStatus "@baseboard_fab2_lib.baseboard_fab2(sch_1):nc_pvccio_cpu0_dnc2" )
			)
			( signal "NC_PVCCIO_CPU0_DNC3"
				( objectStatus "@baseboard_fab2_lib.baseboard_fab2(sch_1):nc_pvccio_cpu0_dnc3" )
			)
			( signal "NC_PVCCIO_CPU0_DNC4"
				( objectStatus "@baseboard_fab2_lib.baseboard_fab2(sch_1):nc_pvccio_cpu0_dnc4" )
			)
			( signal "PU_VR_PVCCIO_CPU0_FAULT1"
				( objectStatus "@baseboard_fab2_lib.baseboard_fab2(sch_1):pu_vr_pvccio_cpu0_fault1" )
			)
			( signal "PWRGD_PVCCIO_CPU0_R"
				( objectStatus "@baseboard_fab2_lib.baseboard_fab2(sch_1):pwrgd_pvccio_cpu0_r" )
			)
			( signal "SMB_VR_SCL_PVCCIO_CPU0"
				( objectStatus "@baseboard_fab2_lib.baseboard_fab2(sch_1):smb_vr_scl_pvccio_cpu0" )
			)
			( signal "SMB_VR_SDA_PVCCIO_CPU0"
				( objectStatus "@baseboard_fab2_lib.baseboard_fab2(sch_1):smb_vr_sda_pvccio_cpu0" )
			)
			( signal "SVID_ALERT_PVCCIO_CPU0"
				( objectStatus "@baseboard_fab2_lib.baseboard_fab2(sch_1):svid_alert_pvccio_cpu0" )
			)
			( signal "SVID_CLK_PVCCIO_CPU0"
				( objectStatus "@baseboard_fab2_lib.baseboard_fab2(sch_1):svid_clk_pvccio_cpu0" )
			)
			( signal "SVID_VDIO_PVCCIO_CPU0"
				( objectStatus "@baseboard_fab2_lib.baseboard_fab2(sch_1):svid_vdio_pvccio_cpu0" )
			)
			( signal "TP_PVCCIO_CPU0_BIREF1"
				( objectStatus "@baseboard_fab2_lib.baseboard_fab2(sch_1):tp_pvccio_cpu0_biref1" )
			)
			( signal "TP_PVCCIO_CPU0_BPWM1"
				( objectStatus "@baseboard_fab2_lib.baseboard_fab2(sch_1):tp_pvccio_cpu0_bpwm1" )
			)
			( signal "TP_PVCCIO_CPU0_BTSEN"
				( objectStatus "@baseboard_fab2_lib.baseboard_fab2(sch_1):tp_pvccio_cpu0_btsen" )
			)
			( signal "TP_PVCCIO_CPU0_BVREF"
				( objectStatus "@baseboard_fab2_lib.baseboard_fab2(sch_1):tp_pvccio_cpu0_bvref" )
			)
			( signal "TP_PVCCIO_CPU0_BVSEN"
				( objectStatus "@baseboard_fab2_lib.baseboard_fab2(sch_1):tp_pvccio_cpu0_bvsen" )
			)
			( signal "TP_PVCCIO_CPU0_PINALRT_N"
				( objectStatus "@baseboard_fab2_lib.baseboard_fab2(sch_1):tp_pvccio_cpu0_pinalrt_n" )
			)
			( signal "TP_PVCCIO_CPU0_RESET_N"
				( objectStatus "@baseboard_fab2_lib.baseboard_fab2(sch_1):tp_pvccio_cpu0_reset_n" )
			)
			( signal "TP_VR_PVCCIO_CPU0_AIINSEN"
				( objectStatus "@baseboard_fab2_lib.baseboard_fab2(sch_1):tp_vr_pvccio_cpu0_aiinsen" )
			)
			( signal "TP_VR_PVCCIO_CPU0_MP0"
				( objectStatus "@baseboard_fab2_lib.baseboard_fab2(sch_1):tp_vr_pvccio_cpu0_mp0" )
			)
			( signal "TP_VR_PVCCIO_CPU0_MP1"
				( objectStatus "@baseboard_fab2_lib.baseboard_fab2(sch_1):tp_vr_pvccio_cpu0_mp1" )
			)
			( signal "TP_VR_PVCCIO_CPU0_MP2"
				( objectStatus "@baseboard_fab2_lib.baseboard_fab2(sch_1):tp_vr_pvccio_cpu0_mp2" )
			)
			( signal "TP_VR_PVCCIO_CPU0_MP3"
				( objectStatus "@baseboard_fab2_lib.baseboard_fab2(sch_1):tp_vr_pvccio_cpu0_mp3" )
			)
			( signal "A_TSENSE_PVDDQ_ABC"
				( objectStatus "@baseboard_fab2_lib.baseboard_fab2(sch_1):a_tsense_pvddq_abc" )
			)
			( signal "VR_FET_SW_P12V_STBY_PVCCIO_CPU0"
				( attribute "VOLTAGE" "12"
					( Units "uVoltage" "V" 1.000000)
					( Status sAliasFlattened )
					( Origin gFrontEnd )
				)
				( objectStatus "@baseboard_fab2_lib.baseboard_fab2(sch_1):vr_fet_sw_p12v_stby_pvccio_cpu0" )
			)
			( signal "VR_PVCCIO_CPU0_AIREF1"
				( objectStatus "@baseboard_fab2_lib.baseboard_fab2(sch_1):vr_pvccio_cpu0_airef1" )
			)
			( signal "VR_PVCCIO_CPU0_AVSP"
				( attribute "VOLTAGE" "2"
					( Units "uVoltage" "V" 1.000000)
					( Status sAliasFlattened )
					( Origin gFrontEnd )
				)
				( objectStatus "@baseboard_fab2_lib.baseboard_fab2(sch_1):vr_pvccio_cpu0_avsp" )
			)
			( signal "VR_PVCCIO_CPU0_EN"
				( attribute "VOLTAGE" "3.3"
					( Units "uVoltage" "V" 1.000000)
					( Status sAliasFlattened )
					( Origin gFrontEnd )
				)
				( objectStatus "@baseboard_fab2_lib.baseboard_fab2(sch_1):vr_pvccio_cpu0_en" )
			)
			( signal "VR_PVCCIO_CPU0_PWM1"
				( attribute "VOLTAGE" "3.3"
					( Units "uVoltage" "V" 1.000000)
					( Status sAliasFlattened )
					( Origin gFrontEnd )
				)
				( objectStatus "@baseboard_fab2_lib.baseboard_fab2(sch_1):vr_pvccio_cpu0_pwm1" )
			)
			( signal "VR_PVCCIO_CPU0_VD12"
				( objectStatus "@baseboard_fab2_lib.baseboard_fab2(sch_1):vr_pvccio_cpu0_vd12" )
			)
			( signal "VR_PVCCIO_CPU0_VDD"
				( objectStatus "@baseboard_fab2_lib.baseboard_fab2(sch_1):vr_pvccio_cpu0_vdd" )
			)
			( signal "VR_PVCCIO_CPU0_VINSEN"
				( attribute "VOLTAGE" "0.8"
					( Units "uVoltage" "V" 1.000000)
					( Status sAliasFlattened )
					( Origin gFrontEnd )
				)
				( objectStatus "@baseboard_fab2_lib.baseboard_fab2(sch_1):vr_pvccio_cpu0_vinsen" )
			)
			( signal "VR_PVCCIO_CPU0_XADDR1"
				( attribute "VOLTAGE" "3.3"
					( Units "uVoltage" "V" 1.000000)
					( Status sAliasFlattened )
					( Origin gFrontEnd )
				)
				( objectStatus "@baseboard_fab2_lib.baseboard_fab2(sch_1):vr_pvccio_cpu0_xaddr1" )
			)
			( signal "VR_PVCCIO_CPU0_XADDR2"
				( attribute "VOLTAGE" "3.3V"
					( Units "uVoltage" "V" 1.000000)
					( Status sAliasFlattened )
					( Origin gFrontEnd )
				)
				( objectStatus "@baseboard_fab2_lib.baseboard_fab2(sch_1):vr_pvccio_cpu0_xaddr2" )
			)
			( signal "VSENSE_PVCCIO_CPU0_AVSN"
				( attribute "VOLTAGE" "0.3"
					( Units "uVoltage" "V" 1.000000)
					( Status sAliasFlattened )
					( Origin gFrontEnd )
				)
				( objectStatus "@baseboard_fab2_lib.baseboard_fab2(sch_1):vsense_pvccio_cpu0_avsn" )
			)
			( signal "VSENSE_PVCCIO_CPU0_AVSP"
				( attribute "VOLTAGE" "2"
					( Units "uVoltage" "V" 1.000000)
					( Status sAliasFlattened )
					( Origin gFrontEnd )
				)
				( objectStatus "@baseboard_fab2_lib.baseboard_fab2(sch_1):vsense_pvccio_cpu0_avsp" )
			)
			( signal "NC_PVCCIO_CPU0_PH1_P31"
				( objectStatus "@baseboard_fab2_lib.baseboard_fab2(sch_1):nc_pvccio_cpu0_ph1_p31" )
			)
			( signal "TP_PVCCIO_CPU0_GL_0"
				( objectStatus "@baseboard_fab2_lib.baseboard_fab2(sch_1):tp_pvccio_cpu0_gl_0" )
			)
			( signal "TP_PVCCIO_CPU0_GL_1"
				( objectStatus "@baseboard_fab2_lib.baseboard_fab2(sch_1):tp_pvccio_cpu0_gl_1" )
			)
			( signal "VR_PVCCIO_CPU0_OCSET"
				( objectStatus "@baseboard_fab2_lib.baseboard_fab2(sch_1):vr_pvccio_cpu0_ocset" )
			)
			( signal "VR_PVCCIO_CPU0_PH1_BOOT"
				( attribute "VOLTAGE" "5"
					( Units "uVoltage" "V" 1.000000)
					( Status sAliasFlattened )
					( Origin gFrontEnd )
				)
				( objectStatus "@baseboard_fab2_lib.baseboard_fab2(sch_1):vr_pvccio_cpu0_ph1_boot" )
			)
			( signal "VR_PVCCIO_CPU0_PH1_PHASE"
				( attribute "VOLTAGE" "5"
					( Units "uVoltage" "V" 1.000000)
					( Status sAliasFlattened )
					( Origin gFrontEnd )
				)
				( objectStatus "@baseboard_fab2_lib.baseboard_fab2(sch_1):vr_pvccio_cpu0_ph1_phase" )
			)
			( signal "VR_PVCCIO_CPU0_PH1_SW"
				( attribute "VOLTAGE" "5"
					( Units "uVoltage" "V" 1.000000)
					( Status sAliasFlattened )
					( Origin gFrontEnd )
				)
				( objectStatus "@baseboard_fab2_lib.baseboard_fab2(sch_1):vr_pvccio_cpu0_ph1_sw" )
			)
			( signal "VR_PVCCIO_CPU0_PH1_VCIN"
				( attribute "VOLTAGE" "5"
					( Units "uVoltage" "V" 1.000000)
					( Status sAliasFlattened )
					( Origin gFrontEnd )
				)
				( objectStatus "@baseboard_fab2_lib.baseboard_fab2(sch_1):vr_pvccio_cpu0_ph1_vcin" )
			)
			( signal "IRQ_PVCCIO_CPU1_VRHOT_N"
				( objectStatus "@baseboard_fab2_lib.baseboard_fab2(sch_1):irq_pvccio_cpu1_vrhot_n" )
			)
			( signal "ISENSE_PVCCIO_CPU1_PH1_IMON"
				( objectStatus "@baseboard_fab2_lib.baseboard_fab2(sch_1):isense_pvccio_cpu1_ph1_imon" )
			)
			( signal "NC_PVCCIO_CPU1_DNC0"
				( objectStatus "@baseboard_fab2_lib.baseboard_fab2(sch_1):nc_pvccio_cpu1_dnc0" )
			)
			( signal "NC_PVCCIO_CPU1_DNC1"
				( objectStatus "@baseboard_fab2_lib.baseboard_fab2(sch_1):nc_pvccio_cpu1_dnc1" )
			)
			( signal "NC_PVCCIO_CPU1_DNC2"
				( objectStatus "@baseboard_fab2_lib.baseboard_fab2(sch_1):nc_pvccio_cpu1_dnc2" )
			)
			( signal "NC_PVCCIO_CPU1_DNC3"
				( objectStatus "@baseboard_fab2_lib.baseboard_fab2(sch_1):nc_pvccio_cpu1_dnc3" )
			)
			( signal "NC_PVCCIO_CPU1_DNC4"
				( objectStatus "@baseboard_fab2_lib.baseboard_fab2(sch_1):nc_pvccio_cpu1_dnc4" )
			)
			( signal "PU_VR_PVCCIO_CPU1_FAULT1"
				( objectStatus "@baseboard_fab2_lib.baseboard_fab2(sch_1):pu_vr_pvccio_cpu1_fault1" )
			)
			( signal "PWRGD_PVCCIO_CPU1_R"
				( objectStatus "@baseboard_fab2_lib.baseboard_fab2(sch_1):pwrgd_pvccio_cpu1_r" )
			)
			( signal "SMB_VR_SCL_PVCCIO_CPU1"
				( objectStatus "@baseboard_fab2_lib.baseboard_fab2(sch_1):smb_vr_scl_pvccio_cpu1" )
			)
			( signal "SMB_VR_SDA_PVCCIO_CPU1"
				( objectStatus "@baseboard_fab2_lib.baseboard_fab2(sch_1):smb_vr_sda_pvccio_cpu1" )
			)
			( signal "SVID_ALERT_PVCCIO_CPU1"
				( objectStatus "@baseboard_fab2_lib.baseboard_fab2(sch_1):svid_alert_pvccio_cpu1" )
			)
			( signal "SVID_CLK_PVCCIO_CPU1"
				( objectStatus "@baseboard_fab2_lib.baseboard_fab2(sch_1):svid_clk_pvccio_cpu1" )
			)
			( signal "SVID_VDIO_PVCCIO_CPU1"
				( objectStatus "@baseboard_fab2_lib.baseboard_fab2(sch_1):svid_vdio_pvccio_cpu1" )
			)
			( signal "TP_PVCCIO_CPU1_BIREF1"
				( objectStatus "@baseboard_fab2_lib.baseboard_fab2(sch_1):tp_pvccio_cpu1_biref1" )
			)
			( signal "TP_PVCCIO_CPU1_BPWM1"
				( objectStatus "@baseboard_fab2_lib.baseboard_fab2(sch_1):tp_pvccio_cpu1_bpwm1" )
			)
			( signal "TP_PVCCIO_CPU1_BTSEN"
				( objectStatus "@baseboard_fab2_lib.baseboard_fab2(sch_1):tp_pvccio_cpu1_btsen" )
			)
			( signal "TP_PVCCIO_CPU1_BVREF"
				( objectStatus "@baseboard_fab2_lib.baseboard_fab2(sch_1):tp_pvccio_cpu1_bvref" )
			)
			( signal "TP_PVCCIO_CPU1_BVSEN"
				( objectStatus "@baseboard_fab2_lib.baseboard_fab2(sch_1):tp_pvccio_cpu1_bvsen" )
			)
			( signal "TP_PVCCIO_CPU1_PINALRT_N"
				( objectStatus "@baseboard_fab2_lib.baseboard_fab2(sch_1):tp_pvccio_cpu1_pinalrt_n" )
			)
			( signal "TP_PVCCIO_CPU1_RESET_N"
				( objectStatus "@baseboard_fab2_lib.baseboard_fab2(sch_1):tp_pvccio_cpu1_reset_n" )
			)
			( signal "TP_VR_PVCCIO_CPU1_AIINSEN"
				( objectStatus "@baseboard_fab2_lib.baseboard_fab2(sch_1):tp_vr_pvccio_cpu1_aiinsen" )
			)
			( signal "TP_VR_PVCCIO_CPU1_MP0"
				( objectStatus "@baseboard_fab2_lib.baseboard_fab2(sch_1):tp_vr_pvccio_cpu1_mp0" )
			)
			( signal "TP_VR_PVCCIO_CPU1_MP1"
				( objectStatus "@baseboard_fab2_lib.baseboard_fab2(sch_1):tp_vr_pvccio_cpu1_mp1" )
			)
			( signal "TP_VR_PVCCIO_CPU1_MP2"
				( objectStatus "@baseboard_fab2_lib.baseboard_fab2(sch_1):tp_vr_pvccio_cpu1_mp2" )
			)
			( signal "TP_VR_PVCCIO_CPU1_MP3"
				( objectStatus "@baseboard_fab2_lib.baseboard_fab2(sch_1):tp_vr_pvccio_cpu1_mp3" )
			)
			( signal "A_TSENSE_PVCCIO_CPU0"
				( attribute "VOLTAGE" "3.6"
					( Units "uVoltage" "V" 1.000000)
					( Status sAliasFlattened )
					( Origin gFrontEnd )
				)
				( objectStatus "@baseboard_fab2_lib.baseboard_fab2(sch_1):a_tsense_pvccio_cpu0" )
			)
			( signal "VR_PVCCIO_CPU1_AIREF1"
				( objectStatus "@baseboard_fab2_lib.baseboard_fab2(sch_1):vr_pvccio_cpu1_airef1" )
			)
			( signal "A_TSENSE_PVSA_CPU1"
				( objectStatus "@baseboard_fab2_lib.baseboard_fab2(sch_1):a_tsense_pvsa_cpu1" )
			)
			( signal "VR_PVCCIO_CPU1_AVSP"
				( attribute "VOLTAGE" "1.05"
					( Units "uVoltage" "V" 1.000000)
					( Status sAliasFlattened )
					( Origin gFrontEnd )
				)
				( objectStatus "@baseboard_fab2_lib.baseboard_fab2(sch_1):vr_pvccio_cpu1_avsp" )
			)
			( signal "PU_FAB2_MARKER_CPLD"
				( objectStatus "@baseboard_fab2_lib.baseboard_fab2(sch_1):pu_fab2_marker_cpld" )
			)
			( signal "VR_PVCCIO_CPU1_EN"
				( attribute "VOLTAGE" "3.3"
					( Units "uVoltage" "V" 1.000000)
					( Status sAliasFlattened )
					( Origin gFrontEnd )
				)
				( objectStatus "@baseboard_fab2_lib.baseboard_fab2(sch_1):vr_pvccio_cpu1_en" )
			)
			( signal "VR_PVCCIO_CPU1_PWM1"
				( attribute "VOLTAGE" "3.6"
					( Units "uVoltage" "V" 1.000000)
					( Status sAliasFlattened )
					( Origin gFrontEnd )
				)
				( objectStatus "@baseboard_fab2_lib.baseboard_fab2(sch_1):vr_pvccio_cpu1_pwm1" )
			)
			( signal "VR_PVCCIO_CPU1_VD12"
				( objectStatus "@baseboard_fab2_lib.baseboard_fab2(sch_1):vr_pvccio_cpu1_vd12" )
			)
			( signal "VR_PVCCIO_CPU1_VDD"
				( attribute "VOLTAGE" "3.3"
					( Units "uVoltage" "V" 1.000000)
					( Status sAliasFlattened )
					( Origin gFrontEnd )
				)
				( objectStatus "@baseboard_fab2_lib.baseboard_fab2(sch_1):vr_pvccio_cpu1_vdd" )
			)
			( signal "VR_PVCCIO_CPU1_VINSEN"
				( objectStatus "@baseboard_fab2_lib.baseboard_fab2(sch_1):vr_pvccio_cpu1_vinsen" )
			)
			( signal "VR_PVCCIO_CPU1_XADDR1"
				( attribute "VOLTAGE" "3.3"
					( Units "uVoltage" "V" 1.000000)
					( Status sAliasFlattened )
					( Origin gFrontEnd )
				)
				( objectStatus "@baseboard_fab2_lib.baseboard_fab2(sch_1):vr_pvccio_cpu1_xaddr1" )
			)
			( signal "VR_PVCCIO_CPU1_XADDR2"
				( attribute "VOLTAGE" "3.3"
					( Units "uVoltage" "V" 1.000000)
					( Status sAliasFlattened )
					( Origin gFrontEnd )
				)
				( objectStatus "@baseboard_fab2_lib.baseboard_fab2(sch_1):vr_pvccio_cpu1_xaddr2" )
			)
			( signal "VSENSE_PVCCIO_CPU1_AVSN"
				( attribute "VOLTAGE" "0.3"
					( Units "uVoltage" "V" 1.000000)
					( Status sAliasFlattened )
					( Origin gFrontEnd )
				)
				( objectStatus "@baseboard_fab2_lib.baseboard_fab2(sch_1):vsense_pvccio_cpu1_avsn" )
			)
			( signal "VSENSE_PVCCIO_CPU1_AVSP"
				( objectStatus "@baseboard_fab2_lib.baseboard_fab2(sch_1):vsense_pvccio_cpu1_avsp" )
			)
			( signal "NC_PVCCIO_CPU1_PH1_P31"
				( objectStatus "@baseboard_fab2_lib.baseboard_fab2(sch_1):nc_pvccio_cpu1_ph1_p31" )
			)
			( signal "TP_PVCCIO_CPU1_GL_0"
				( objectStatus "@baseboard_fab2_lib.baseboard_fab2(sch_1):tp_pvccio_cpu1_gl_0" )
			)
			( signal "TP_PVCCIO_CPU1_GL_1"
				( objectStatus "@baseboard_fab2_lib.baseboard_fab2(sch_1):tp_pvccio_cpu1_gl_1" )
			)
			( signal "VR_PVCCIO_CPU1_OCSET"
				( objectStatus "@baseboard_fab2_lib.baseboard_fab2(sch_1):vr_pvccio_cpu1_ocset" )
			)
			( signal "VR_PVCCIO_CPU1_PH1_BOOT"
				( objectStatus "@baseboard_fab2_lib.baseboard_fab2(sch_1):vr_pvccio_cpu1_ph1_boot" )
			)
			( signal "VR_PVCCIO_CPU1_PH1_PHASE"
				( objectStatus "@baseboard_fab2_lib.baseboard_fab2(sch_1):vr_pvccio_cpu1_ph1_phase" )
			)
			( signal "VR_PVCCIO_CPU1_PH1_SW"
				( objectStatus "@baseboard_fab2_lib.baseboard_fab2(sch_1):vr_pvccio_cpu1_ph1_sw" )
			)
			( signal "VR_PVCCIO_CPU1_PH1_VCIN"
				( objectStatus "@baseboard_fab2_lib.baseboard_fab2(sch_1):vr_pvccio_cpu1_ph1_vcin" )
			)
			( signal "IRQ_PVDDQ_ABC_VRHOT_LVT3_R_N"
				( objectStatus "@baseboard_fab2_lib.baseboard_fab2(sch_1):irq_pvddq_abc_vrhot_lvt3_r_n" )
			)
			( signal "ISENSE_PVDDQ_ABC_PH1_IMON"
				( objectStatus "@baseboard_fab2_lib.baseboard_fab2(sch_1):isense_pvddq_abc_ph1_imon" )
			)
			( signal "ISENSE_PVDDQ_ABC_PH2_IMON"
				( objectStatus "@baseboard_fab2_lib.baseboard_fab2(sch_1):isense_pvddq_abc_ph2_imon" )
			)
			( signal "NC_PVDDQ_ABC_DNC0"
				( objectStatus "@baseboard_fab2_lib.baseboard_fab2(sch_1):nc_pvddq_abc_dnc0" )
			)
			( signal "NC_PVDDQ_ABC_DNC1"
				( objectStatus "@baseboard_fab2_lib.baseboard_fab2(sch_1):nc_pvddq_abc_dnc1" )
			)
			( signal "PU_VR_PVDDQ_ABC_FAULT1"
				( objectStatus "@baseboard_fab2_lib.baseboard_fab2(sch_1):pu_vr_pvddq_abc_fault1" )
			)
			( signal "PWRGD_PVDDQ_ABC"
				( objectStatus "@baseboard_fab2_lib.baseboard_fab2(sch_1):pwrgd_pvddq_abc" )
			)
			( signal "PWRGD_PVDDQ_ABC_R"
				( objectStatus "@baseboard_fab2_lib.baseboard_fab2(sch_1):pwrgd_pvddq_abc_r" )
			)
			( signal "SMB_VR_SCL_VDDQ_ABC"
				( objectStatus "@baseboard_fab2_lib.baseboard_fab2(sch_1):smb_vr_scl_vddq_abc" )
			)
			( signal "SMB_VR_SDA_VDDQ_ABC"
				( objectStatus "@baseboard_fab2_lib.baseboard_fab2(sch_1):smb_vr_sda_vddq_abc" )
			)
			( signal "SVID_ALERT_PVDDQ_ABC"
				( objectStatus "@baseboard_fab2_lib.baseboard_fab2(sch_1):svid_alert_pvddq_abc" )
			)
			( signal "SVID_CLK_PVDDQ_ABC"
				( objectStatus "@baseboard_fab2_lib.baseboard_fab2(sch_1):svid_clk_pvddq_abc" )
			)
			( signal "SVID_VDIO_PVDDQ_ABC"
				( objectStatus "@baseboard_fab2_lib.baseboard_fab2(sch_1):svid_vdio_pvddq_abc" )
			)
			( signal "TP_PVDDQ_ABC_BPWM1"
				( objectStatus "@baseboard_fab2_lib.baseboard_fab2(sch_1):tp_pvddq_abc_bpwm1" )
			)
			( signal "TP_PVDDQ_ABC_BREF1"
				( objectStatus "@baseboard_fab2_lib.baseboard_fab2(sch_1):tp_pvddq_abc_bref1" )
			)
			( signal "TP_PVDDQ_ABC_BTSEN"
				( objectStatus "@baseboard_fab2_lib.baseboard_fab2(sch_1):tp_pvddq_abc_btsen" )
			)
			( signal "TP_PVDDQ_ABC_BVREF"
				( objectStatus "@baseboard_fab2_lib.baseboard_fab2(sch_1):tp_pvddq_abc_bvref" )
			)
			( signal "TP_PVDDQ_ABC_BVSEN"
				( objectStatus "@baseboard_fab2_lib.baseboard_fab2(sch_1):tp_pvddq_abc_bvsen" )
			)
			( signal "TP_PVDDQ_ABC_MP1"
				( objectStatus "@baseboard_fab2_lib.baseboard_fab2(sch_1):tp_pvddq_abc_mp1" )
			)
			( signal "TP_PVDDQ_ABC_MP2"
				( objectStatus "@baseboard_fab2_lib.baseboard_fab2(sch_1):tp_pvddq_abc_mp2" )
			)
			( signal "TP_PVDDQ_ABC_PH3_IMON"
				( objectStatus "@baseboard_fab2_lib.baseboard_fab2(sch_1):tp_pvddq_abc_ph3_imon" )
			)
			( signal "TP_PVDDQ_ABC_PH3_IMON_REF"
				( objectStatus "@baseboard_fab2_lib.baseboard_fab2(sch_1):tp_pvddq_abc_ph3_imon_ref" )
			)
			( signal "TP_PVDDQ_ABC_PINALRT_N"
				( objectStatus "@baseboard_fab2_lib.baseboard_fab2(sch_1):tp_pvddq_abc_pinalrt_n" )
			)
			( signal "TP_PVDDQ_ABC_PWM3"
				( objectStatus "@baseboard_fab2_lib.baseboard_fab2(sch_1):tp_pvddq_abc_pwm3" )
			)
			( signal "TP_PVDDQ_ABC_RESET_N"
				( objectStatus "@baseboard_fab2_lib.baseboard_fab2(sch_1):tp_pvddq_abc_reset_n" )
			)
			( signal "A_TSENSE_PVDDQ_DEF"
				( objectStatus "@baseboard_fab2_lib.baseboard_fab2(sch_1):a_tsense_pvddq_def" )
			)
			( signal "VR_FET_SW_P12V_STBY_PVDDQ_ABC"
				( objectStatus "@baseboard_fab2_lib.baseboard_fab2(sch_1):vr_fet_sw_p12v_stby_pvddq_abc" )
			)
			( signal "VR_PVDDQ_ABC_AIREF1"
				( objectStatus "@baseboard_fab2_lib.baseboard_fab2(sch_1):vr_pvddq_abc_airef1" )
			)
			( signal "VR_PVDDQ_ABC_AIREF2"
				( objectStatus "@baseboard_fab2_lib.baseboard_fab2(sch_1):vr_pvddq_abc_airef2" )
			)
			( signal "VR_PVDDQ_ABC_AVSP"
				( objectStatus "@baseboard_fab2_lib.baseboard_fab2(sch_1):vr_pvddq_abc_avsp" )
			)
			( signal "VR_PVDDQ_ABC_PWM1"
				( objectStatus "@baseboard_fab2_lib.baseboard_fab2(sch_1):vr_pvddq_abc_pwm1" )
			)
			( signal "VR_PVDDQ_ABC_PWM2"
				( objectStatus "@baseboard_fab2_lib.baseboard_fab2(sch_1):vr_pvddq_abc_pwm2" )
			)
			( signal "VR_PVDDQ_ABC_VD12"
				( objectStatus "@baseboard_fab2_lib.baseboard_fab2(sch_1):vr_pvddq_abc_vd12" )
			)
			( signal "VR_PVDDQ_ABC_VDD"
				( objectStatus "@baseboard_fab2_lib.baseboard_fab2(sch_1):vr_pvddq_abc_vdd" )
			)
			( signal "VR_PVDDQ_ABC_VINSEN"
				( objectStatus "@baseboard_fab2_lib.baseboard_fab2(sch_1):vr_pvddq_abc_vinsen" )
			)
			( signal "VR_PVDDQ_ABC_VREN"
				( objectStatus "@baseboard_fab2_lib.baseboard_fab2(sch_1):vr_pvddq_abc_vren" )
			)
			( signal "VR_PVDDQ_ABC_XADDR1"
				( objectStatus "@baseboard_fab2_lib.baseboard_fab2(sch_1):vr_pvddq_abc_xaddr1" )
			)
			( signal "VR_PVDDQ_ABC_XADDR2"
				( objectStatus "@baseboard_fab2_lib.baseboard_fab2(sch_1):vr_pvddq_abc_xaddr2" )
			)
			( signal "VSENSE_PVDDQ_ABC_N"
				( objectStatus "@baseboard_fab2_lib.baseboard_fab2(sch_1):vsense_pvddq_abc_n" )
			)
			( signal "VSENSE_PVDDQ_ABC_P"
				( objectStatus "@baseboard_fab2_lib.baseboard_fab2(sch_1):vsense_pvddq_abc_p" )
			)
			( signal "NC_PVDDQ_ABC_PH1_P31"
				( objectStatus "@baseboard_fab2_lib.baseboard_fab2(sch_1):nc_pvddq_abc_ph1_p31" )
			)
			( signal "NC_PVDDQ_ABC_PH2_P31"
				( objectStatus "@baseboard_fab2_lib.baseboard_fab2(sch_1):nc_pvddq_abc_ph2_p31" )
			)
			( signal "TP_PVDDQ_ABC_PH1_GL_0"
				( objectStatus "@baseboard_fab2_lib.baseboard_fab2(sch_1):tp_pvddq_abc_ph1_gl_0" )
			)
			( signal "TP_PVDDQ_ABC_PH1_GL_1"
				( objectStatus "@baseboard_fab2_lib.baseboard_fab2(sch_1):tp_pvddq_abc_ph1_gl_1" )
			)
			( signal "TP_PVDDQ_ABC_PH2_GL_0"
				( objectStatus "@baseboard_fab2_lib.baseboard_fab2(sch_1):tp_pvddq_abc_ph2_gl_0" )
			)
			( signal "TP_PVDDQ_ABC_PH2_GL_1"
				( objectStatus "@baseboard_fab2_lib.baseboard_fab2(sch_1):tp_pvddq_abc_ph2_gl_1" )
			)
			( signal "VR_PVDDQ_ABC_PH1_BOOT"
				( objectStatus "@baseboard_fab2_lib.baseboard_fab2(sch_1):vr_pvddq_abc_ph1_boot" )
			)
			( signal "VR_PVDDQ_ABC_PH1_OCSET"
				( attribute "VOLTAGE" "3.6"
					( Units "uVoltage" "V" 1.000000)
					( Status sAliasFlattened )
					( Origin gFrontEnd )
				)
				( objectStatus "@baseboard_fab2_lib.baseboard_fab2(sch_1):vr_pvddq_abc_ph1_ocset" )
			)
			( signal "VR_PVDDQ_ABC_PH1_PHASE"
				( objectStatus "@baseboard_fab2_lib.baseboard_fab2(sch_1):vr_pvddq_abc_ph1_phase" )
			)
			( signal "VR_PVDDQ_ABC_PH1_SW"
				( objectStatus "@baseboard_fab2_lib.baseboard_fab2(sch_1):vr_pvddq_abc_ph1_sw" )
			)
			( signal "VR_PVDDQ_ABC_PH1_VCIN"
				( objectStatus "@baseboard_fab2_lib.baseboard_fab2(sch_1):vr_pvddq_abc_ph1_vcin" )
			)
			( signal "VR_PVDDQ_ABC_PH2_BOOT"
				( objectStatus "@baseboard_fab2_lib.baseboard_fab2(sch_1):vr_pvddq_abc_ph2_boot" )
			)
			( signal "VR_PVDDQ_ABC_PH2_OCSET"
				( attribute "VOLTAGE" "3.6"
					( Units "uVoltage" "V" 1.000000)
					( Status sAliasFlattened )
					( Origin gFrontEnd )
				)
				( objectStatus "@baseboard_fab2_lib.baseboard_fab2(sch_1):vr_pvddq_abc_ph2_ocset" )
			)
			( signal "VR_PVDDQ_ABC_PH2_PHASE"
				( objectStatus "@baseboard_fab2_lib.baseboard_fab2(sch_1):vr_pvddq_abc_ph2_phase" )
			)
			( signal "VR_PVDDQ_ABC_PH2_SW"
				( objectStatus "@baseboard_fab2_lib.baseboard_fab2(sch_1):vr_pvddq_abc_ph2_sw" )
			)
			( signal "VR_PVDDQ_ABC_PH2_VCIN"
				( objectStatus "@baseboard_fab2_lib.baseboard_fab2(sch_1):vr_pvddq_abc_ph2_vcin" )
			)
			( signal "IRQ_PVDDQ_DEF_VRHOT_LVT3_R_N"
				( objectStatus "@baseboard_fab2_lib.baseboard_fab2(sch_1):irq_pvddq_def_vrhot_lvt3_r_n" )
			)
			( signal "ISENSE_PVDDQ_DEF_PH1_IMON"
				( objectStatus "@baseboard_fab2_lib.baseboard_fab2(sch_1):isense_pvddq_def_ph1_imon" )
			)
			( signal "ISENSE_PVDDQ_DEF_PH2_IMON"
				( objectStatus "@baseboard_fab2_lib.baseboard_fab2(sch_1):isense_pvddq_def_ph2_imon" )
			)
			( signal "NC_PVDDQ_DEF_DNC0"
				( objectStatus "@baseboard_fab2_lib.baseboard_fab2(sch_1):nc_pvddq_def_dnc0" )
			)
			( signal "NC_PVDDQ_DEF_DNC1"
				( objectStatus "@baseboard_fab2_lib.baseboard_fab2(sch_1):nc_pvddq_def_dnc1" )
			)
			( signal "PU_VR_PVDDQ_DEF_FAULT1"
				( objectStatus "@baseboard_fab2_lib.baseboard_fab2(sch_1):pu_vr_pvddq_def_fault1" )
			)
			( signal "PWRGD_PVDDQ_DEF"
				( objectStatus "@baseboard_fab2_lib.baseboard_fab2(sch_1):pwrgd_pvddq_def" )
			)
			( signal "PWRGD_PVDDQ_DEF_R"
				( objectStatus "@baseboard_fab2_lib.baseboard_fab2(sch_1):pwrgd_pvddq_def_r" )
			)
			( signal "SMB_VR_SCL_VDDQ_DEF"
				( objectStatus "@baseboard_fab2_lib.baseboard_fab2(sch_1):smb_vr_scl_vddq_def" )
			)
			( signal "SMB_VR_SDA_VDDQ_DEF"
				( objectStatus "@baseboard_fab2_lib.baseboard_fab2(sch_1):smb_vr_sda_vddq_def" )
			)
			( signal "SVID_ALERT_PVDDQ_DEF"
				( objectStatus "@baseboard_fab2_lib.baseboard_fab2(sch_1):svid_alert_pvddq_def" )
			)
			( signal "SVID_CLK_PVDDQ_DEF"
				( objectStatus "@baseboard_fab2_lib.baseboard_fab2(sch_1):svid_clk_pvddq_def" )
			)
			( signal "SVID_VDIO_PVDDQ_DEF"
				( objectStatus "@baseboard_fab2_lib.baseboard_fab2(sch_1):svid_vdio_pvddq_def" )
			)
			( signal "TP_PVDDQ_DEF_BPWM1"
				( objectStatus "@baseboard_fab2_lib.baseboard_fab2(sch_1):tp_pvddq_def_bpwm1" )
			)
			( signal "TP_PVDDQ_DEF_BREF1"
				( objectStatus "@baseboard_fab2_lib.baseboard_fab2(sch_1):tp_pvddq_def_bref1" )
			)
			( signal "TP_PVDDQ_DEF_BTSEN"
				( objectStatus "@baseboard_fab2_lib.baseboard_fab2(sch_1):tp_pvddq_def_btsen" )
			)
			( signal "TP_PVDDQ_DEF_BVREF"
				( objectStatus "@baseboard_fab2_lib.baseboard_fab2(sch_1):tp_pvddq_def_bvref" )
			)
			( signal "TP_PVDDQ_DEF_BVSEN"
				( objectStatus "@baseboard_fab2_lib.baseboard_fab2(sch_1):tp_pvddq_def_bvsen" )
			)
			( signal "TP_PVDDQ_DEF_MP1"
				( objectStatus "@baseboard_fab2_lib.baseboard_fab2(sch_1):tp_pvddq_def_mp1" )
			)
			( signal "TP_PVDDQ_DEF_MP2"
				( objectStatus "@baseboard_fab2_lib.baseboard_fab2(sch_1):tp_pvddq_def_mp2" )
			)
			( signal "TP_PVDDQ_DEF_PH3_IMON"
				( objectStatus "@baseboard_fab2_lib.baseboard_fab2(sch_1):tp_pvddq_def_ph3_imon" )
			)
			( signal "TP_PVDDQ_DEF_PH3_IMON_REF"
				( objectStatus "@baseboard_fab2_lib.baseboard_fab2(sch_1):tp_pvddq_def_ph3_imon_ref" )
			)
			( signal "TP_PVDDQ_DEF_PINALRT_N"
				( objectStatus "@baseboard_fab2_lib.baseboard_fab2(sch_1):tp_pvddq_def_pinalrt_n" )
			)
			( signal "TP_PVDDQ_DEF_PWM3"
				( objectStatus "@baseboard_fab2_lib.baseboard_fab2(sch_1):tp_pvddq_def_pwm3" )
			)
			( signal "TP_PVDDQ_DEF_RESET_N"
				( objectStatus "@baseboard_fab2_lib.baseboard_fab2(sch_1):tp_pvddq_def_reset_n" )
			)
			( signal "A_TSENSE_PVDDQ_GHJ"
				( objectStatus "@baseboard_fab2_lib.baseboard_fab2(sch_1):a_tsense_pvddq_ghj" )
			)
			( signal "VR_FET_SW_P12V_STBY_PVDDQ_DEF"
				( objectStatus "@baseboard_fab2_lib.baseboard_fab2(sch_1):vr_fet_sw_p12v_stby_pvddq_def" )
			)
			( signal "VR_PVDDQ_DEF_AIREF1"
				( objectStatus "@baseboard_fab2_lib.baseboard_fab2(sch_1):vr_pvddq_def_airef1" )
			)
			( signal "VR_PVDDQ_DEF_AIREF2"
				( objectStatus "@baseboard_fab2_lib.baseboard_fab2(sch_1):vr_pvddq_def_airef2" )
			)
			( signal "VR_PVDDQ_DEF_AVSP"
				( objectStatus "@baseboard_fab2_lib.baseboard_fab2(sch_1):vr_pvddq_def_avsp" )
			)
			( signal "VR_PVDDQ_DEF_PWM1"
				( objectStatus "@baseboard_fab2_lib.baseboard_fab2(sch_1):vr_pvddq_def_pwm1" )
			)
			( signal "VR_PVDDQ_DEF_PWM2"
				( objectStatus "@baseboard_fab2_lib.baseboard_fab2(sch_1):vr_pvddq_def_pwm2" )
			)
			( signal "VR_PVDDQ_DEF_VD12"
				( objectStatus "@baseboard_fab2_lib.baseboard_fab2(sch_1):vr_pvddq_def_vd12" )
			)
			( signal "VR_PVDDQ_DEF_VDD"
				( objectStatus "@baseboard_fab2_lib.baseboard_fab2(sch_1):vr_pvddq_def_vdd" )
			)
			( signal "VR_PVDDQ_DEF_VINSEN"
				( objectStatus "@baseboard_fab2_lib.baseboard_fab2(sch_1):vr_pvddq_def_vinsen" )
			)
			( signal "VR_PVDDQ_DEF_VREN"
				( objectStatus "@baseboard_fab2_lib.baseboard_fab2(sch_1):vr_pvddq_def_vren" )
			)
			( signal "VR_PVDDQ_DEF_XADDR1"
				( objectStatus "@baseboard_fab2_lib.baseboard_fab2(sch_1):vr_pvddq_def_xaddr1" )
			)
			( signal "VR_PVDDQ_DEF_XADDR2"
				( objectStatus "@baseboard_fab2_lib.baseboard_fab2(sch_1):vr_pvddq_def_xaddr2" )
			)
			( signal "VSENSE_PVDDQ_DEF_N"
				( objectStatus "@baseboard_fab2_lib.baseboard_fab2(sch_1):vsense_pvddq_def_n" )
			)
			( signal "VSENSE_PVDDQ_DEF_P"
				( objectStatus "@baseboard_fab2_lib.baseboard_fab2(sch_1):vsense_pvddq_def_p" )
			)
			( signal "NC_PVDDQ_DEF_PH1_P31"
				( objectStatus "@baseboard_fab2_lib.baseboard_fab2(sch_1):nc_pvddq_def_ph1_p31" )
			)
			( signal "NC_PVDDQ_DEF_PH2_P31"
				( objectStatus "@baseboard_fab2_lib.baseboard_fab2(sch_1):nc_pvddq_def_ph2_p31" )
			)
			( signal "TP_PVDDQ_DEF_PH1_GL_0"
				( objectStatus "@baseboard_fab2_lib.baseboard_fab2(sch_1):tp_pvddq_def_ph1_gl_0" )
			)
			( signal "TP_PVDDQ_DEF_PH1_GL_1"
				( objectStatus "@baseboard_fab2_lib.baseboard_fab2(sch_1):tp_pvddq_def_ph1_gl_1" )
			)
			( signal "TP_PVDDQ_DEF_PH2_GL_0"
				( objectStatus "@baseboard_fab2_lib.baseboard_fab2(sch_1):tp_pvddq_def_ph2_gl_0" )
			)
			( signal "TP_PVDDQ_DEF_PH2_GL_1"
				( objectStatus "@baseboard_fab2_lib.baseboard_fab2(sch_1):tp_pvddq_def_ph2_gl_1" )
			)
			( signal "VR_PVDDQ_DEF_PH1_BOOT"
				( objectStatus "@baseboard_fab2_lib.baseboard_fab2(sch_1):vr_pvddq_def_ph1_boot" )
			)
			( signal "VR_PVDDQ_DEF_PH1_OCSET"
				( attribute "VOLTAGE" "3.6"
					( Units "uVoltage" "V" 1.000000)
					( Status sAliasFlattened )
					( Origin gFrontEnd )
				)
				( objectStatus "@baseboard_fab2_lib.baseboard_fab2(sch_1):vr_pvddq_def_ph1_ocset" )
			)
			( signal "VR_PVDDQ_DEF_PH1_PHASE"
				( objectStatus "@baseboard_fab2_lib.baseboard_fab2(sch_1):vr_pvddq_def_ph1_phase" )
			)
			( signal "VR_PVDDQ_DEF_PH1_SW"
				( objectStatus "@baseboard_fab2_lib.baseboard_fab2(sch_1):vr_pvddq_def_ph1_sw" )
			)
			( signal "VR_PVDDQ_DEF_PH1_VCIN"
				( objectStatus "@baseboard_fab2_lib.baseboard_fab2(sch_1):vr_pvddq_def_ph1_vcin" )
			)
			( signal "VR_PVDDQ_DEF_PH2_BOOT"
				( objectStatus "@baseboard_fab2_lib.baseboard_fab2(sch_1):vr_pvddq_def_ph2_boot" )
			)
			( signal "VR_PVDDQ_DEF_PH2_OCSET"
				( attribute "VOLTAGE" "3.6"
					( Units "uVoltage" "V" 1.000000)
					( Status sAliasFlattened )
					( Origin gFrontEnd )
				)
				( objectStatus "@baseboard_fab2_lib.baseboard_fab2(sch_1):vr_pvddq_def_ph2_ocset" )
			)
			( signal "VR_PVDDQ_DEF_PH2_PHASE"
				( objectStatus "@baseboard_fab2_lib.baseboard_fab2(sch_1):vr_pvddq_def_ph2_phase" )
			)
			( signal "VR_PVDDQ_DEF_PH2_SW"
				( objectStatus "@baseboard_fab2_lib.baseboard_fab2(sch_1):vr_pvddq_def_ph2_sw" )
			)
			( signal "VR_PVDDQ_DEF_PH2_VCIN"
				( objectStatus "@baseboard_fab2_lib.baseboard_fab2(sch_1):vr_pvddq_def_ph2_vcin" )
			)
			( signal "FM_PVTT_ABC_EN_R"
				( objectStatus "@baseboard_fab2_lib.baseboard_fab2(sch_1):fm_pvtt_abc_en_r" )
			)
			( signal "PWRGD_PVTT_ABC_CPU0_R"
				( objectStatus "@baseboard_fab2_lib.baseboard_fab2(sch_1):pwrgd_pvtt_abc_cpu0_r" )
			)
			( signal "VR_PVTT_ABC_BIAS"
				( objectStatus "@baseboard_fab2_lib.baseboard_fab2(sch_1):vr_pvtt_abc_bias" )
			)
			( signal "VR_PVTT_ABC_SNS"
				( objectStatus "@baseboard_fab2_lib.baseboard_fab2(sch_1):vr_pvtt_abc_sns" )
			)
			( signal "VR_PVTT_ABC_VREF"
				( objectStatus "@baseboard_fab2_lib.baseboard_fab2(sch_1):vr_pvtt_abc_vref" )
			)
			( signal "VSENSE_PVDDQ_ABC_VTT"
				( objectStatus "@baseboard_fab2_lib.baseboard_fab2(sch_1):vsense_pvddq_abc_vtt" )
			)
			( signal "FM_PVTT_DEF_EN_R"
				( objectStatus "@baseboard_fab2_lib.baseboard_fab2(sch_1):fm_pvtt_def_en_r" )
			)
			( signal "PWRGD_PVTT_DEF_CPU0_R"
				( objectStatus "@baseboard_fab2_lib.baseboard_fab2(sch_1):pwrgd_pvtt_def_cpu0_r" )
			)
			( signal "VR_PVTT_DEF_BIAS"
				( objectStatus "@baseboard_fab2_lib.baseboard_fab2(sch_1):vr_pvtt_def_bias" )
			)
			( signal "VR_PVTT_DEF_SNS"
				( objectStatus "@baseboard_fab2_lib.baseboard_fab2(sch_1):vr_pvtt_def_sns" )
			)
			( signal "VR_PVTT_DEF_VREF"
				( objectStatus "@baseboard_fab2_lib.baseboard_fab2(sch_1):vr_pvtt_def_vref" )
			)
			( signal "VSENSE_PVDDQ_DEF_VTT"
				( objectStatus "@baseboard_fab2_lib.baseboard_fab2(sch_1):vsense_pvddq_def_vtt" )
			)
			( signal "IRQ_PVDDQ_GHJ_VRHOT_LVT3_R_N"
				( objectStatus "@baseboard_fab2_lib.baseboard_fab2(sch_1):irq_pvddq_ghj_vrhot_lvt3_r_n" )
			)
			( signal "ISENSE_PVDDQ_GHJ_PH1_IMON"
				( objectStatus "@baseboard_fab2_lib.baseboard_fab2(sch_1):isense_pvddq_ghj_ph1_imon" )
			)
			( signal "ISENSE_PVDDQ_GHJ_PH2_IMON"
				( objectStatus "@baseboard_fab2_lib.baseboard_fab2(sch_1):isense_pvddq_ghj_ph2_imon" )
			)
			( signal "NC_PVDDQ_GHJ_DNC0"
				( objectStatus "@baseboard_fab2_lib.baseboard_fab2(sch_1):nc_pvddq_ghj_dnc0" )
			)
			( signal "NC_PVDDQ_GHJ_DNC1"
				( objectStatus "@baseboard_fab2_lib.baseboard_fab2(sch_1):nc_pvddq_ghj_dnc1" )
			)
			( signal "NC_PVDDQ_GHJ_PINALRT_N"
				( objectStatus "@baseboard_fab2_lib.baseboard_fab2(sch_1):nc_pvddq_ghj_pinalrt_n" )
			)
			( signal "PU_VR_PVDDQ_GHJ_FAULT1"
				( objectStatus "@baseboard_fab2_lib.baseboard_fab2(sch_1):pu_vr_pvddq_ghj_fault1" )
			)
			( signal "PWRGD_PVDDQ_GHJ"
				( objectStatus "@baseboard_fab2_lib.baseboard_fab2(sch_1):pwrgd_pvddq_ghj" )
			)
			( signal "PWRGD_PVDDQ_GHJ_R"
				( objectStatus "@baseboard_fab2_lib.baseboard_fab2(sch_1):pwrgd_pvddq_ghj_r" )
			)
			( signal "SMB_VR_SCL_VDDQ_GHJ"
				( objectStatus "@baseboard_fab2_lib.baseboard_fab2(sch_1):smb_vr_scl_vddq_ghj" )
			)
			( signal "SMB_VR_SDA_VDDQ_GHJ"
				( objectStatus "@baseboard_fab2_lib.baseboard_fab2(sch_1):smb_vr_sda_vddq_ghj" )
			)
			( signal "SVID_ALERT_PVDDQ_GHJ"
				( objectStatus "@baseboard_fab2_lib.baseboard_fab2(sch_1):svid_alert_pvddq_ghj" )
			)
			( signal "SVID_CLK_PVDDQ_GHJ"
				( objectStatus "@baseboard_fab2_lib.baseboard_fab2(sch_1):svid_clk_pvddq_ghj" )
			)
			( signal "SVID_VDIO_PVDDQ_GHJ"
				( objectStatus "@baseboard_fab2_lib.baseboard_fab2(sch_1):svid_vdio_pvddq_ghj" )
			)
			( signal "TP_PVDDQ_GHJ_BPWM1"
				( objectStatus "@baseboard_fab2_lib.baseboard_fab2(sch_1):tp_pvddq_ghj_bpwm1" )
			)
			( signal "TP_PVDDQ_GHJ_BREF1"
				( objectStatus "@baseboard_fab2_lib.baseboard_fab2(sch_1):tp_pvddq_ghj_bref1" )
			)
			( signal "TP_PVDDQ_GHJ_BTSEN"
				( objectStatus "@baseboard_fab2_lib.baseboard_fab2(sch_1):tp_pvddq_ghj_btsen" )
			)
			( signal "TP_PVDDQ_GHJ_BVREF"
				( objectStatus "@baseboard_fab2_lib.baseboard_fab2(sch_1):tp_pvddq_ghj_bvref" )
			)
			( signal "TP_PVDDQ_GHJ_BVSEN"
				( objectStatus "@baseboard_fab2_lib.baseboard_fab2(sch_1):tp_pvddq_ghj_bvsen" )
			)
			( signal "TP_PVDDQ_GHJ_MP1"
				( objectStatus "@baseboard_fab2_lib.baseboard_fab2(sch_1):tp_pvddq_ghj_mp1" )
			)
			( signal "TP_PVDDQ_GHJ_MP2"
				( objectStatus "@baseboard_fab2_lib.baseboard_fab2(sch_1):tp_pvddq_ghj_mp2" )
			)
			( signal "TP_PVDDQ_GHJ_PH3_IMON"
				( objectStatus "@baseboard_fab2_lib.baseboard_fab2(sch_1):tp_pvddq_ghj_ph3_imon" )
			)
			( signal "TP_PVDDQ_GHJ_PH3_IMON_REF"
				( objectStatus "@baseboard_fab2_lib.baseboard_fab2(sch_1):tp_pvddq_ghj_ph3_imon_ref" )
			)
			( signal "TP_PVDDQ_GHJ_PWM3"
				( objectStatus "@baseboard_fab2_lib.baseboard_fab2(sch_1):tp_pvddq_ghj_pwm3" )
			)
			( signal "TP_PVDDQ_GHJ_RESET_N"
				( objectStatus "@baseboard_fab2_lib.baseboard_fab2(sch_1):tp_pvddq_ghj_reset_n" )
			)
			( signal "VR_FET_SW_P12V_STBY_PVDDQ_GHJ"
				( objectStatus "@baseboard_fab2_lib.baseboard_fab2(sch_1):vr_fet_sw_p12v_stby_pvddq_ghj" )
			)
			( signal "VR_PVDDQ_GHJ_AIREF1"
				( objectStatus "@baseboard_fab2_lib.baseboard_fab2(sch_1):vr_pvddq_ghj_airef1" )
			)
			( signal "VR_PVDDQ_GHJ_AIREF2"
				( objectStatus "@baseboard_fab2_lib.baseboard_fab2(sch_1):vr_pvddq_ghj_airef2" )
			)
			( signal "VR_PVDDQ_GHJ_AVSP"
				( objectStatus "@baseboard_fab2_lib.baseboard_fab2(sch_1):vr_pvddq_ghj_avsp" )
			)
			( signal "VR_PVDDQ_GHJ_PWM1"
				( objectStatus "@baseboard_fab2_lib.baseboard_fab2(sch_1):vr_pvddq_ghj_pwm1" )
			)
			( signal "VR_PVDDQ_GHJ_PWM2"
				( objectStatus "@baseboard_fab2_lib.baseboard_fab2(sch_1):vr_pvddq_ghj_pwm2" )
			)
			( signal "VR_PVDDQ_GHJ_VD12"
				( objectStatus "@baseboard_fab2_lib.baseboard_fab2(sch_1):vr_pvddq_ghj_vd12" )
			)
			( signal "VR_PVDDQ_GHJ_VDD"
				( objectStatus "@baseboard_fab2_lib.baseboard_fab2(sch_1):vr_pvddq_ghj_vdd" )
			)
			( signal "VR_PVDDQ_GHJ_VINSEN"
				( objectStatus "@baseboard_fab2_lib.baseboard_fab2(sch_1):vr_pvddq_ghj_vinsen" )
			)
			( signal "VR_PVDDQ_GHJ_VREN"
				( objectStatus "@baseboard_fab2_lib.baseboard_fab2(sch_1):vr_pvddq_ghj_vren" )
			)
			( signal "VR_PVDDQ_GHJ_XADDR1"
				( objectStatus "@baseboard_fab2_lib.baseboard_fab2(sch_1):vr_pvddq_ghj_xaddr1" )
			)
			( signal "VR_PVDDQ_GHJ_XADDR2"
				( objectStatus "@baseboard_fab2_lib.baseboard_fab2(sch_1):vr_pvddq_ghj_xaddr2" )
			)
			( signal "VSENSE_PVDDQ_GHJ_N"
				( objectStatus "@baseboard_fab2_lib.baseboard_fab2(sch_1):vsense_pvddq_ghj_n" )
			)
			( signal "VSENSE_PVDDQ_GHJ_P"
				( objectStatus "@baseboard_fab2_lib.baseboard_fab2(sch_1):vsense_pvddq_ghj_p" )
			)
			( signal "NC_PVDDQ_GHJ_PH1_P31"
				( objectStatus "@baseboard_fab2_lib.baseboard_fab2(sch_1):nc_pvddq_ghj_ph1_p31" )
			)
			( signal "NC_PVDDQ_GHJ_PH2_P31"
				( objectStatus "@baseboard_fab2_lib.baseboard_fab2(sch_1):nc_pvddq_ghj_ph2_p31" )
			)
			( signal "TP_PVDDQ_GHJ_PH1_GL_0"
				( objectStatus "@baseboard_fab2_lib.baseboard_fab2(sch_1):tp_pvddq_ghj_ph1_gl_0" )
			)
			( signal "TP_PVDDQ_GHJ_PH1_GL_1"
				( objectStatus "@baseboard_fab2_lib.baseboard_fab2(sch_1):tp_pvddq_ghj_ph1_gl_1" )
			)
			( signal "TP_PVDDQ_GHJ_PH2_GL_0"
				( objectStatus "@baseboard_fab2_lib.baseboard_fab2(sch_1):tp_pvddq_ghj_ph2_gl_0" )
			)
			( signal "TP_PVDDQ_GHJ_PH2_GL_1"
				( objectStatus "@baseboard_fab2_lib.baseboard_fab2(sch_1):tp_pvddq_ghj_ph2_gl_1" )
			)
			( signal "VR_PVDDQ_GHJ_PH1_BOOT"
				( objectStatus "@baseboard_fab2_lib.baseboard_fab2(sch_1):vr_pvddq_ghj_ph1_boot" )
			)
			( signal "VR_PVDDQ_GHJ_PH1_OCSET"
				( attribute "VOLTAGE" "3.6"
					( Units "uVoltage" "V" 1.000000)
					( Status sAliasFlattened )
					( Origin gFrontEnd )
				)
				( objectStatus "@baseboard_fab2_lib.baseboard_fab2(sch_1):vr_pvddq_ghj_ph1_ocset" )
			)
			( signal "VR_PVDDQ_GHJ_PH1_PHASE"
				( objectStatus "@baseboard_fab2_lib.baseboard_fab2(sch_1):vr_pvddq_ghj_ph1_phase" )
			)
			( signal "VR_PVDDQ_GHJ_PH1_SW"
				( objectStatus "@baseboard_fab2_lib.baseboard_fab2(sch_1):vr_pvddq_ghj_ph1_sw" )
			)
			( signal "VR_PVDDQ_GHJ_PH1_VCIN"
				( objectStatus "@baseboard_fab2_lib.baseboard_fab2(sch_1):vr_pvddq_ghj_ph1_vcin" )
			)
			( signal "VR_PVDDQ_GHJ_PH2_BOOT"
				( objectStatus "@baseboard_fab2_lib.baseboard_fab2(sch_1):vr_pvddq_ghj_ph2_boot" )
			)
			( signal "VR_PVDDQ_GHJ_PH2_OCSET"
				( attribute "VOLTAGE" "3.6"
					( Units "uVoltage" "V" 1.000000)
					( Status sAliasFlattened )
					( Origin gFrontEnd )
				)
				( objectStatus "@baseboard_fab2_lib.baseboard_fab2(sch_1):vr_pvddq_ghj_ph2_ocset" )
			)
			( signal "VR_PVDDQ_GHJ_PH2_PHASE"
				( objectStatus "@baseboard_fab2_lib.baseboard_fab2(sch_1):vr_pvddq_ghj_ph2_phase" )
			)
			( signal "VR_PVDDQ_GHJ_PH2_SW"
				( objectStatus "@baseboard_fab2_lib.baseboard_fab2(sch_1):vr_pvddq_ghj_ph2_sw" )
			)
			( signal "VR_PVDDQ_GHJ_PH2_VCIN"
				( objectStatus "@baseboard_fab2_lib.baseboard_fab2(sch_1):vr_pvddq_ghj_ph2_vcin" )
			)
			( signal "IRQ_PVDDQ_KLM_VRHOT_LVT3_R_N"
				( objectStatus "@baseboard_fab2_lib.baseboard_fab2(sch_1):irq_pvddq_klm_vrhot_lvt3_r_n" )
			)
			( signal "ISENSE_PVDDQ_KLM_PH1_IMON"
				( objectStatus "@baseboard_fab2_lib.baseboard_fab2(sch_1):isense_pvddq_klm_ph1_imon" )
			)
			( signal "ISENSE_PVDDQ_KLM_PH2_IMON"
				( objectStatus "@baseboard_fab2_lib.baseboard_fab2(sch_1):isense_pvddq_klm_ph2_imon" )
			)
			( signal "NC_PVDDQ_KLM_DNC0"
				( objectStatus "@baseboard_fab2_lib.baseboard_fab2(sch_1):nc_pvddq_klm_dnc0" )
			)
			( signal "NC_PVDDQ_KLM_DNC1"
				( objectStatus "@baseboard_fab2_lib.baseboard_fab2(sch_1):nc_pvddq_klm_dnc1" )
			)
			( signal "NC_PVDDQ_KLM_GP0"
				( objectStatus "@baseboard_fab2_lib.baseboard_fab2(sch_1):nc_pvddq_klm_gp0" )
			)
			( signal "NC_PVDDQ_KLM_GP1"
				( objectStatus "@baseboard_fab2_lib.baseboard_fab2(sch_1):nc_pvddq_klm_gp1" )
			)
			( signal "NC_PVDDQ_KLM_PINALRT_N"
				( objectStatus "@baseboard_fab2_lib.baseboard_fab2(sch_1):nc_pvddq_klm_pinalrt_n" )
			)
			( signal "NC_PVDDQ_KLM_PWM3"
				( objectStatus "@baseboard_fab2_lib.baseboard_fab2(sch_1):nc_pvddq_klm_pwm3" )
			)
			( signal "PU_VR_PVDDQ_KLM_FAULT1"
				( objectStatus "@baseboard_fab2_lib.baseboard_fab2(sch_1):pu_vr_pvddq_klm_fault1" )
			)
			( signal "PWRGD_PVDDQ_KLM"
				( objectStatus "@baseboard_fab2_lib.baseboard_fab2(sch_1):pwrgd_pvddq_klm" )
			)
			( signal "PWRGD_PVDDQ_KLM_R"
				( objectStatus "@baseboard_fab2_lib.baseboard_fab2(sch_1):pwrgd_pvddq_klm_r" )
			)
			( signal "SMB_VR_SCL_VDDQ_KLM"
				( objectStatus "@baseboard_fab2_lib.baseboard_fab2(sch_1):smb_vr_scl_vddq_klm" )
			)
			( signal "SMB_VR_SDA_VDDQ_KLM"
				( objectStatus "@baseboard_fab2_lib.baseboard_fab2(sch_1):smb_vr_sda_vddq_klm" )
			)
			( signal "SVID_ALERT_PVDDQ_KLM"
				( objectStatus "@baseboard_fab2_lib.baseboard_fab2(sch_1):svid_alert_pvddq_klm" )
			)
			( signal "SVID_CLK_PVDDQ_KLM"
				( objectStatus "@baseboard_fab2_lib.baseboard_fab2(sch_1):svid_clk_pvddq_klm" )
			)
			( signal "SVID_VDIO_PVDDQ_KLM"
				( objectStatus "@baseboard_fab2_lib.baseboard_fab2(sch_1):svid_vdio_pvddq_klm" )
			)
			( signal "TP_PVDDQ_KLM_BPWM1"
				( objectStatus "@baseboard_fab2_lib.baseboard_fab2(sch_1):tp_pvddq_klm_bpwm1" )
			)
			( signal "TP_PVDDQ_KLM_BREF1"
				( objectStatus "@baseboard_fab2_lib.baseboard_fab2(sch_1):tp_pvddq_klm_bref1" )
			)
			( signal "TP_PVDDQ_KLM_BTSEN"
				( objectStatus "@baseboard_fab2_lib.baseboard_fab2(sch_1):tp_pvddq_klm_btsen" )
			)
			( signal "TP_PVDDQ_KLM_BVREF"
				( objectStatus "@baseboard_fab2_lib.baseboard_fab2(sch_1):tp_pvddq_klm_bvref" )
			)
			( signal "TP_PVDDQ_KLM_BVSEN"
				( objectStatus "@baseboard_fab2_lib.baseboard_fab2(sch_1):tp_pvddq_klm_bvsen" )
			)
			( signal "TP_PVDDQ_KLM_PH3_IMON"
				( objectStatus "@baseboard_fab2_lib.baseboard_fab2(sch_1):tp_pvddq_klm_ph3_imon" )
			)
			( signal "TP_PVDDQ_KLM_PH3_IMON_REF"
				( objectStatus "@baseboard_fab2_lib.baseboard_fab2(sch_1):tp_pvddq_klm_ph3_imon_ref" )
			)
			( signal "TP_PVDDQ_KLM_RESET_N"
				( objectStatus "@baseboard_fab2_lib.baseboard_fab2(sch_1):tp_pvddq_klm_reset_n" )
			)
			( signal "VR_FET_SW_P12V_STBY_PVDDQ_KLM"
				( objectStatus "@baseboard_fab2_lib.baseboard_fab2(sch_1):vr_fet_sw_p12v_stby_pvddq_klm" )
			)
			( signal "VR_PVDDQ_KLM_AIREF1"
				( objectStatus "@baseboard_fab2_lib.baseboard_fab2(sch_1):vr_pvddq_klm_airef1" )
			)
			( signal "VR_PVDDQ_KLM_AIREF2"
				( objectStatus "@baseboard_fab2_lib.baseboard_fab2(sch_1):vr_pvddq_klm_airef2" )
			)
			( signal "VR_PVDDQ_KLM_AVSP"
				( objectStatus "@baseboard_fab2_lib.baseboard_fab2(sch_1):vr_pvddq_klm_avsp" )
			)
			( signal "VR_PVDDQ_KLM_PWM1"
				( objectStatus "@baseboard_fab2_lib.baseboard_fab2(sch_1):vr_pvddq_klm_pwm1" )
			)
			( signal "VR_PVDDQ_KLM_PWM2"
				( objectStatus "@baseboard_fab2_lib.baseboard_fab2(sch_1):vr_pvddq_klm_pwm2" )
			)
			( signal "VR_PVDDQ_KLM_VD12"
				( objectStatus "@baseboard_fab2_lib.baseboard_fab2(sch_1):vr_pvddq_klm_vd12" )
			)
			( signal "VR_PVDDQ_KLM_VDD"
				( objectStatus "@baseboard_fab2_lib.baseboard_fab2(sch_1):vr_pvddq_klm_vdd" )
			)
			( signal "VR_PVDDQ_KLM_VINSEN"
				( objectStatus "@baseboard_fab2_lib.baseboard_fab2(sch_1):vr_pvddq_klm_vinsen" )
			)
			( signal "VR_PVDDQ_KLM_VREN"
				( objectStatus "@baseboard_fab2_lib.baseboard_fab2(sch_1):vr_pvddq_klm_vren" )
			)
			( signal "VR_PVDDQ_KLM_XADDR1"
				( objectStatus "@baseboard_fab2_lib.baseboard_fab2(sch_1):vr_pvddq_klm_xaddr1" )
			)
			( signal "VR_PVDDQ_KLM_XADDR2"
				( objectStatus "@baseboard_fab2_lib.baseboard_fab2(sch_1):vr_pvddq_klm_xaddr2" )
			)
			( signal "VSENSE_PVDDQ_KLM_N"
				( objectStatus "@baseboard_fab2_lib.baseboard_fab2(sch_1):vsense_pvddq_klm_n" )
			)
			( signal "VSENSE_PVDDQ_KLM_P"
				( objectStatus "@baseboard_fab2_lib.baseboard_fab2(sch_1):vsense_pvddq_klm_p" )
			)
			( signal "NC_PVDDQ_KLM_PH1_P31"
				( objectStatus "@baseboard_fab2_lib.baseboard_fab2(sch_1):nc_pvddq_klm_ph1_p31" )
			)
			( signal "NC_PVDDQ_KLM_PH2_P31"
				( objectStatus "@baseboard_fab2_lib.baseboard_fab2(sch_1):nc_pvddq_klm_ph2_p31" )
			)
			( signal "TP_PVDDQ_KLM_PH1_GL_0"
				( objectStatus "@baseboard_fab2_lib.baseboard_fab2(sch_1):tp_pvddq_klm_ph1_gl_0" )
			)
			( signal "TP_PVDDQ_KLM_PH1_GL_1"
				( objectStatus "@baseboard_fab2_lib.baseboard_fab2(sch_1):tp_pvddq_klm_ph1_gl_1" )
			)
			( signal "TP_PVDDQ_KLM_PH2_GL_0"
				( objectStatus "@baseboard_fab2_lib.baseboard_fab2(sch_1):tp_pvddq_klm_ph2_gl_0" )
			)
			( signal "TP_PVDDQ_KLM_PH2_GL_1"
				( objectStatus "@baseboard_fab2_lib.baseboard_fab2(sch_1):tp_pvddq_klm_ph2_gl_1" )
			)
			( signal "VR_PVDDQ_KLM_PH1_BOOT"
				( objectStatus "@baseboard_fab2_lib.baseboard_fab2(sch_1):vr_pvddq_klm_ph1_boot" )
			)
			( signal "VR_PVDDQ_KLM_PH1_OCSET"
				( attribute "VOLTAGE" "3.6"
					( Units "uVoltage" "V" 1.000000)
					( Status sAliasFlattened )
					( Origin gFrontEnd )
				)
				( objectStatus "@baseboard_fab2_lib.baseboard_fab2(sch_1):vr_pvddq_klm_ph1_ocset" )
			)
			( signal "VR_PVDDQ_KLM_PH1_PHASE"
				( objectStatus "@baseboard_fab2_lib.baseboard_fab2(sch_1):vr_pvddq_klm_ph1_phase" )
			)
			( signal "VR_PVDDQ_KLM_PH1_SW"
				( objectStatus "@baseboard_fab2_lib.baseboard_fab2(sch_1):vr_pvddq_klm_ph1_sw" )
			)
			( signal "VR_PVDDQ_KLM_PH1_VCIN"
				( objectStatus "@baseboard_fab2_lib.baseboard_fab2(sch_1):vr_pvddq_klm_ph1_vcin" )
			)
			( signal "VR_PVDDQ_KLM_PH2_BOOT"
				( objectStatus "@baseboard_fab2_lib.baseboard_fab2(sch_1):vr_pvddq_klm_ph2_boot" )
			)
			( signal "VR_PVDDQ_KLM_PH2_OCSET"
				( attribute "VOLTAGE" "3.6"
					( Units "uVoltage" "V" 1.000000)
					( Status sAliasFlattened )
					( Origin gFrontEnd )
				)
				( objectStatus "@baseboard_fab2_lib.baseboard_fab2(sch_1):vr_pvddq_klm_ph2_ocset" )
			)
			( signal "VR_PVDDQ_KLM_PH2_PHASE"
				( objectStatus "@baseboard_fab2_lib.baseboard_fab2(sch_1):vr_pvddq_klm_ph2_phase" )
			)
			( signal "VR_PVDDQ_KLM_PH2_SW"
				( objectStatus "@baseboard_fab2_lib.baseboard_fab2(sch_1):vr_pvddq_klm_ph2_sw" )
			)
			( signal "VR_PVDDQ_KLM_PH2_VCIN"
				( objectStatus "@baseboard_fab2_lib.baseboard_fab2(sch_1):vr_pvddq_klm_ph2_vcin" )
			)
			( signal "FM_PVTT_GHJ_EN_R"
				( objectStatus "@baseboard_fab2_lib.baseboard_fab2(sch_1):fm_pvtt_ghj_en_r" )
			)
			( signal "PWRGD_PVTT_GHJ_CPU1_R"
				( objectStatus "@baseboard_fab2_lib.baseboard_fab2(sch_1):pwrgd_pvtt_ghj_cpu1_r" )
			)
			( signal "VR_PVTT_GHJ_BIAS"
				( objectStatus "@baseboard_fab2_lib.baseboard_fab2(sch_1):vr_pvtt_ghj_bias" )
			)
			( signal "VR_PVTT_GHJ_SNS"
				( objectStatus "@baseboard_fab2_lib.baseboard_fab2(sch_1):vr_pvtt_ghj_sns" )
			)
			( signal "VR_PVTT_GHJ_VREF"
				( objectStatus "@baseboard_fab2_lib.baseboard_fab2(sch_1):vr_pvtt_ghj_vref" )
			)
			( signal "VSENSE_PVDDQ_GHJ_VTT"
				( objectStatus "@baseboard_fab2_lib.baseboard_fab2(sch_1):vsense_pvddq_ghj_vtt" )
			)
			( signal "FM_PVTT_KLM_EN_R"
				( objectStatus "@baseboard_fab2_lib.baseboard_fab2(sch_1):fm_pvtt_klm_en_r" )
			)
			( signal "PWRGD_PVTT_KLM_CPU1_R"
				( objectStatus "@baseboard_fab2_lib.baseboard_fab2(sch_1):pwrgd_pvtt_klm_cpu1_r" )
			)
			( signal "VR_PVTT_KLM_BIAS"
				( objectStatus "@baseboard_fab2_lib.baseboard_fab2(sch_1):vr_pvtt_klm_bias" )
			)
			( signal "VR_PVTT_KLM_SNS"
				( objectStatus "@baseboard_fab2_lib.baseboard_fab2(sch_1):vr_pvtt_klm_sns" )
			)
			( signal "VR_PVTT_KLM_VREF"
				( objectStatus "@baseboard_fab2_lib.baseboard_fab2(sch_1):vr_pvtt_klm_vref" )
			)
			( signal "VSENSE_PVDDQ_KLM_VTT"
				( objectStatus "@baseboard_fab2_lib.baseboard_fab2(sch_1):vsense_pvddq_klm_vtt" )
			)
			( signal "AGND_PVPP_ABC"
				( attribute "VOLTAGE" "0.0V"
					( Units "uVoltage" "V" 1.000000)
					( Status sAliasFlattened )
					( Origin gFrontEnd )
				)
				( objectStatus "@baseboard_fab2_lib.baseboard_fab2(sch_1):agnd_pvpp_abc" )
			)
			( signal "FM_PVPP_PVDDQ_CPU0_EN_ABC"
				( objectStatus "@baseboard_fab2_lib.baseboard_fab2(sch_1):fm_pvpp_pvddq_cpu0_en_abc" )
			)
			( signal "PWRGD_PVPP_ABC_R"
				( objectStatus "@baseboard_fab2_lib.baseboard_fab2(sch_1):pwrgd_pvpp_abc_r" )
			)
			( signal "VR_COMP_PVPP_ABC"
				( objectStatus "@baseboard_fab2_lib.baseboard_fab2(sch_1):vr_comp_pvpp_abc" )
			)
			( signal "VR_COMP_PVPP_ABC_3"
				( objectStatus "@baseboard_fab2_lib.baseboard_fab2(sch_1):vr_comp_pvpp_abc_3" )
			)
			( signal "VR_COMP_RC_PVPP_ABC"
				( objectStatus "@baseboard_fab2_lib.baseboard_fab2(sch_1):vr_comp_rc_pvpp_abc" )
			)
			( signal "VR_FB_PVPP_ABC"
				( objectStatus "@baseboard_fab2_lib.baseboard_fab2(sch_1):vr_fb_pvpp_abc" )
			)
			( signal "VR_FET_SW_P12V_STBY_PVPP_ABC"
				( objectStatus "@baseboard_fab2_lib.baseboard_fab2(sch_1):vr_fet_sw_p12v_stby_pvpp_abc" )
			)
			( signal "VR_PVPP_ABC_BOOT"
				( objectStatus "@baseboard_fab2_lib.baseboard_fab2(sch_1):vr_pvpp_abc_boot" )
			)
			( signal "VR_PVPP_ABC_BOOT_R"
				( objectStatus "@baseboard_fab2_lib.baseboard_fab2(sch_1):vr_pvpp_abc_boot_r" )
			)
			( signal "VR_PVPP_ABC_ISET"
				( objectStatus "@baseboard_fab2_lib.baseboard_fab2(sch_1):vr_pvpp_abc_iset" )
			)
			( signal "VR_PVPP_ABC_PHASE"
				( objectStatus "@baseboard_fab2_lib.baseboard_fab2(sch_1):vr_pvpp_abc_phase" )
			)
			( signal "VR_PVPP_ABC_SNUB"
				( objectStatus "@baseboard_fab2_lib.baseboard_fab2(sch_1):vr_pvpp_abc_snub" )
			)
			( signal "VR_PVPP_ABC_SS"
				( objectStatus "@baseboard_fab2_lib.baseboard_fab2(sch_1):vr_pvpp_abc_ss" )
			)
			( signal "VR_VB_PVPP_ABC"
				( objectStatus "@baseboard_fab2_lib.baseboard_fab2(sch_1):vr_vb_pvpp_abc" )
			)
			( signal "VSENSE_PVPP_ABC"
				( objectStatus "@baseboard_fab2_lib.baseboard_fab2(sch_1):vsense_pvpp_abc" )
			)
			( signal "AGND_PVPP_DEF"
				( attribute "VOLTAGE" "0.0V"
					( Units "uVoltage" "V" 1.000000)
					( Status sAliasFlattened )
					( Origin gFrontEnd )
				)
				( objectStatus "@baseboard_fab2_lib.baseboard_fab2(sch_1):agnd_pvpp_def" )
			)
			( signal "FM_PVPP_PVDDQ_CPU0_EN_DEF"
				( objectStatus "@baseboard_fab2_lib.baseboard_fab2(sch_1):fm_pvpp_pvddq_cpu0_en_def" )
			)
			( signal "PWRGD_PVPP_DEF_R"
				( objectStatus "@baseboard_fab2_lib.baseboard_fab2(sch_1):pwrgd_pvpp_def_r" )
			)
			( signal "VR_COMP_PVPP_DEF"
				( objectStatus "@baseboard_fab2_lib.baseboard_fab2(sch_1):vr_comp_pvpp_def" )
			)
			( signal "VR_COMP_PVPP_DEF_3"
				( objectStatus "@baseboard_fab2_lib.baseboard_fab2(sch_1):vr_comp_pvpp_def_3" )
			)
			( signal "VR_COMP_RC_PVPP_DEF"
				( objectStatus "@baseboard_fab2_lib.baseboard_fab2(sch_1):vr_comp_rc_pvpp_def" )
			)
			( signal "VR_FB_PVPP_DEF"
				( objectStatus "@baseboard_fab2_lib.baseboard_fab2(sch_1):vr_fb_pvpp_def" )
			)
			( signal "VR_FET_SW_P12V_STBY_PVPP_DEF"
				( objectStatus "@baseboard_fab2_lib.baseboard_fab2(sch_1):vr_fet_sw_p12v_stby_pvpp_def" )
			)
			( signal "VR_PVPP_DEF_BOOT"
				( objectStatus "@baseboard_fab2_lib.baseboard_fab2(sch_1):vr_pvpp_def_boot" )
			)
			( signal "VR_PVPP_DEF_BOOT_R"
				( objectStatus "@baseboard_fab2_lib.baseboard_fab2(sch_1):vr_pvpp_def_boot_r" )
			)
			( signal "VR_PVPP_DEF_ISET"
				( objectStatus "@baseboard_fab2_lib.baseboard_fab2(sch_1):vr_pvpp_def_iset" )
			)
			( signal "VR_PVPP_DEF_PHASE"
				( objectStatus "@baseboard_fab2_lib.baseboard_fab2(sch_1):vr_pvpp_def_phase" )
			)
			( signal "VR_PVPP_DEF_SNUB"
				( objectStatus "@baseboard_fab2_lib.baseboard_fab2(sch_1):vr_pvpp_def_snub" )
			)
			( signal "VR_PVPP_DEF_SS"
				( objectStatus "@baseboard_fab2_lib.baseboard_fab2(sch_1):vr_pvpp_def_ss" )
			)
			( signal "VR_VB_PVPP_DEF"
				( objectStatus "@baseboard_fab2_lib.baseboard_fab2(sch_1):vr_vb_pvpp_def" )
			)
			( signal "VSENSE_PVPP_DEF"
				( objectStatus "@baseboard_fab2_lib.baseboard_fab2(sch_1):vsense_pvpp_def" )
			)
			( signal "AGND_PVPP_GHJ"
				( attribute "VOLTAGE" "0.0V"
					( Units "uVoltage" "V" 1.000000)
					( Status sAliasFlattened )
					( Origin gFrontEnd )
				)
				( objectStatus "@baseboard_fab2_lib.baseboard_fab2(sch_1):agnd_pvpp_ghj" )
			)
			( signal "FM_PVPP_PVDDQ_CPU1_EN_GHJ"
				( objectStatus "@baseboard_fab2_lib.baseboard_fab2(sch_1):fm_pvpp_pvddq_cpu1_en_ghj" )
			)
			( signal "PWRGD_PVPP_GHJ_R"
				( objectStatus "@baseboard_fab2_lib.baseboard_fab2(sch_1):pwrgd_pvpp_ghj_r" )
			)
			( signal "VR_COMP_PVPP_GHJ"
				( objectStatus "@baseboard_fab2_lib.baseboard_fab2(sch_1):vr_comp_pvpp_ghj" )
			)
			( signal "VR_COMP_PVPP_GHJ_3"
				( objectStatus "@baseboard_fab2_lib.baseboard_fab2(sch_1):vr_comp_pvpp_ghj_3" )
			)
			( signal "VR_COMP_RC_PVPP_GHJ"
				( objectStatus "@baseboard_fab2_lib.baseboard_fab2(sch_1):vr_comp_rc_pvpp_ghj" )
			)
			( signal "VR_FB_PVPP_GHJ"
				( objectStatus "@baseboard_fab2_lib.baseboard_fab2(sch_1):vr_fb_pvpp_ghj" )
			)
			( signal "VR_FET_SW_P12V_STBY_PVPP_GHJ"
				( objectStatus "@baseboard_fab2_lib.baseboard_fab2(sch_1):vr_fet_sw_p12v_stby_pvpp_ghj" )
			)
			( signal "VR_PVPP_GHJ_BOOT"
				( objectStatus "@baseboard_fab2_lib.baseboard_fab2(sch_1):vr_pvpp_ghj_boot" )
			)
			( signal "VR_PVPP_GHJ_BOOT_R"
				( objectStatus "@baseboard_fab2_lib.baseboard_fab2(sch_1):vr_pvpp_ghj_boot_r" )
			)
			( signal "VR_PVPP_GHJ_ISET"
				( objectStatus "@baseboard_fab2_lib.baseboard_fab2(sch_1):vr_pvpp_ghj_iset" )
			)
			( signal "VR_PVPP_GHJ_PHASE"
				( objectStatus "@baseboard_fab2_lib.baseboard_fab2(sch_1):vr_pvpp_ghj_phase" )
			)
			( signal "VR_PVPP_GHJ_SNUB"
				( objectStatus "@baseboard_fab2_lib.baseboard_fab2(sch_1):vr_pvpp_ghj_snub" )
			)
			( signal "VR_PVPP_GHJ_SS"
				( objectStatus "@baseboard_fab2_lib.baseboard_fab2(sch_1):vr_pvpp_ghj_ss" )
			)
			( signal "VR_VB_PVPP_GHJ"
				( objectStatus "@baseboard_fab2_lib.baseboard_fab2(sch_1):vr_vb_pvpp_ghj" )
			)
			( signal "VSENSE_PVPP_GHJ"
				( objectStatus "@baseboard_fab2_lib.baseboard_fab2(sch_1):vsense_pvpp_ghj" )
			)
			( signal "AGND_PVPP_KLM"
				( attribute "VOLTAGE" "0.0V"
					( Units "uVoltage" "V" 1.000000)
					( Status sAliasFlattened )
					( Origin gFrontEnd )
				)
				( objectStatus "@baseboard_fab2_lib.baseboard_fab2(sch_1):agnd_pvpp_klm" )
			)
			( signal "FM_PVPP_PVDDQ_CPU1_EN_KLM"
				( objectStatus "@baseboard_fab2_lib.baseboard_fab2(sch_1):fm_pvpp_pvddq_cpu1_en_klm" )
			)
			( signal "PWRGD_PVPP_KLM_R"
				( objectStatus "@baseboard_fab2_lib.baseboard_fab2(sch_1):pwrgd_pvpp_klm_r" )
			)
			( signal "VR_COMP_PVPP_KLM"
				( objectStatus "@baseboard_fab2_lib.baseboard_fab2(sch_1):vr_comp_pvpp_klm" )
			)
			( signal "VR_COMP_PVPP_KLM_3"
				( objectStatus "@baseboard_fab2_lib.baseboard_fab2(sch_1):vr_comp_pvpp_klm_3" )
			)
			( signal "VR_COMP_RC_PVPP_KLM"
				( objectStatus "@baseboard_fab2_lib.baseboard_fab2(sch_1):vr_comp_rc_pvpp_klm" )
			)
			( signal "VR_FB_PVPP_KLM"
				( objectStatus "@baseboard_fab2_lib.baseboard_fab2(sch_1):vr_fb_pvpp_klm" )
			)
			( signal "VR_FET_SW_P12V_STBY_PVPP_KLM"
				( objectStatus "@baseboard_fab2_lib.baseboard_fab2(sch_1):vr_fet_sw_p12v_stby_pvpp_klm" )
			)
			( signal "VR_PVPP_KLM_BOOT"
				( objectStatus "@baseboard_fab2_lib.baseboard_fab2(sch_1):vr_pvpp_klm_boot" )
			)
			( signal "VR_PVPP_KLM_BOOT_R"
				( objectStatus "@baseboard_fab2_lib.baseboard_fab2(sch_1):vr_pvpp_klm_boot_r" )
			)
			( signal "VR_PVPP_KLM_ISET"
				( objectStatus "@baseboard_fab2_lib.baseboard_fab2(sch_1):vr_pvpp_klm_iset" )
			)
			( signal "VR_PVPP_KLM_PHASE"
				( objectStatus "@baseboard_fab2_lib.baseboard_fab2(sch_1):vr_pvpp_klm_phase" )
			)
			( signal "VR_PVPP_KLM_SNUB"
				( objectStatus "@baseboard_fab2_lib.baseboard_fab2(sch_1):vr_pvpp_klm_snub" )
			)
			( signal "VR_PVPP_KLM_SS"
				( objectStatus "@baseboard_fab2_lib.baseboard_fab2(sch_1):vr_pvpp_klm_ss" )
			)
			( signal "VR_VB_PVPP_KLM"
				( objectStatus "@baseboard_fab2_lib.baseboard_fab2(sch_1):vr_vb_pvpp_klm" )
			)
			( signal "VSENSE_PVPP_KLM"
				( objectStatus "@baseboard_fab2_lib.baseboard_fab2(sch_1):vsense_pvpp_klm" )
			)
			( signal "IRQ_PVNN_PCH_VRHOT_N"
				( objectStatus "@baseboard_fab2_lib.baseboard_fab2(sch_1):irq_pvnn_pch_vrhot_n" )
			)
			( signal "ISENSE_P1V05_PCH_STBY_PH1_IMON"
				( objectStatus "@baseboard_fab2_lib.baseboard_fab2(sch_1):isense_p1v05_pch_stby_ph1_imon" )
			)
			( signal "ISENSE_PVNN_PCH_PH1_IMON"
				( objectStatus "@baseboard_fab2_lib.baseboard_fab2(sch_1):isense_pvnn_pch_ph1_imon" )
			)
			( signal "NC_PVNN_PCH_DNC0"
				( objectStatus "@baseboard_fab2_lib.baseboard_fab2(sch_1):nc_pvnn_pch_dnc0" )
			)
			( signal "NC_PVNN_PCH_DNC1"
				( objectStatus "@baseboard_fab2_lib.baseboard_fab2(sch_1):nc_pvnn_pch_dnc1" )
			)
			( signal "NC_PVNN_PCH_DNC2"
				( objectStatus "@baseboard_fab2_lib.baseboard_fab2(sch_1):nc_pvnn_pch_dnc2" )
			)
			( signal "NC_PVNN_PCH_DNC3"
				( objectStatus "@baseboard_fab2_lib.baseboard_fab2(sch_1):nc_pvnn_pch_dnc3" )
			)
			( signal "NC_PVNN_PCH_DNC4"
				( objectStatus "@baseboard_fab2_lib.baseboard_fab2(sch_1):nc_pvnn_pch_dnc4" )
			)
			( signal "PU_VR_PVNN_PCH_FAULT1"
				( objectStatus "@baseboard_fab2_lib.baseboard_fab2(sch_1):pu_vr_pvnn_pch_fault1" )
			)
			( signal "PWRGD_P1V8_PCH_STBY"
				( objectStatus "@baseboard_fab2_lib.baseboard_fab2(sch_1):pwrgd_p1v8_pch_stby" )
			)
			( signal "PWRGD_PVNN_PCH_R"
				( objectStatus "@baseboard_fab2_lib.baseboard_fab2(sch_1):pwrgd_pvnn_pch_r" )
			)
			( signal "SMB_VR_SCL_PVNN_PCH"
				( objectStatus "@baseboard_fab2_lib.baseboard_fab2(sch_1):smb_vr_scl_pvnn_pch" )
			)
			( signal "SMB_VR_SDA_PVNN_PCH"
				( objectStatus "@baseboard_fab2_lib.baseboard_fab2(sch_1):smb_vr_sda_pvnn_pch" )
			)
			( signal "TP_PVNN_PCH_MP2"
				( objectStatus "@baseboard_fab2_lib.baseboard_fab2(sch_1):tp_pvnn_pch_mp2" )
			)
			( signal "TP_PVNN_PCH_MP3"
				( objectStatus "@baseboard_fab2_lib.baseboard_fab2(sch_1):tp_pvnn_pch_mp3" )
			)
			( signal "TP_PVNN_PCH_PINALRT_N"
				( objectStatus "@baseboard_fab2_lib.baseboard_fab2(sch_1):tp_pvnn_pch_pinalrt_n" )
			)
			( signal "TP_PVNN_PCH_RESET_N"
				( objectStatus "@baseboard_fab2_lib.baseboard_fab2(sch_1):tp_pvnn_pch_reset_n" )
			)
			( signal "TP_PVNN_PCH_SVID_ALERT"
				( objectStatus "@baseboard_fab2_lib.baseboard_fab2(sch_1):tp_pvnn_pch_svid_alert" )
			)
			( signal "TP_PVNN_PCH_VCLK"
				( objectStatus "@baseboard_fab2_lib.baseboard_fab2(sch_1):tp_pvnn_pch_vclk" )
			)
			( signal "TP_PVNN_PCH_VDIO"
				( objectStatus "@baseboard_fab2_lib.baseboard_fab2(sch_1):tp_pvnn_pch_vdio" )
			)
			( signal "TP_VR_PVNN_PCH_AIINSEN"
				( objectStatus "@baseboard_fab2_lib.baseboard_fab2(sch_1):tp_vr_pvnn_pch_aiinsen" )
			)
			( signal "A_TSENSE_PVCCIN_CPU0"
				( objectStatus "@baseboard_fab2_lib.baseboard_fab2(sch_1):a_tsense_pvccin_cpu0" )
			)
			( signal "A_TSENSE_PVSA_CPU0"
				( objectStatus "@baseboard_fab2_lib.baseboard_fab2(sch_1):a_tsense_pvsa_cpu0" )
			)
			( signal "VR_P1V05_PCH_BIREF1"
				( objectStatus "@baseboard_fab2_lib.baseboard_fab2(sch_1):vr_p1v05_pch_biref1" )
			)
			( signal "VR_P1V05_PCH_STBY_AVSP"
				( objectStatus "@baseboard_fab2_lib.baseboard_fab2(sch_1):vr_p1v05_pch_stby_avsp" )
			)
			( signal "VR_P1V05_PCH_STBY_PWM1"
				( objectStatus "@baseboard_fab2_lib.baseboard_fab2(sch_1):vr_p1v05_pch_stby_pwm1" )
			)
			( signal "VR_PVNN_P1V05_PCH_VD12"
				( objectStatus "@baseboard_fab2_lib.baseboard_fab2(sch_1):vr_pvnn_p1v05_pch_vd12" )
			)
			( signal "VR_PVNN_PCH_AIREF1"
				( objectStatus "@baseboard_fab2_lib.baseboard_fab2(sch_1):vr_pvnn_pch_airef1" )
			)
			( signal "VR_PVNN_PCH_AVSP"
				( objectStatus "@baseboard_fab2_lib.baseboard_fab2(sch_1):vr_pvnn_pch_avsp" )
			)
			( signal "VR_PVNN_PCH_PWM1"
				( objectStatus "@baseboard_fab2_lib.baseboard_fab2(sch_1):vr_pvnn_pch_pwm1" )
			)
			( signal "VR_PVNN_PCH_VDD"
				( objectStatus "@baseboard_fab2_lib.baseboard_fab2(sch_1):vr_pvnn_pch_vdd" )
			)
			( signal "VR_PVNN_PCH_VINSEN"
				( objectStatus "@baseboard_fab2_lib.baseboard_fab2(sch_1):vr_pvnn_pch_vinsen" )
			)
			( signal "VR_PVNN_PCH_VREN"
				( objectStatus "@baseboard_fab2_lib.baseboard_fab2(sch_1):vr_pvnn_pch_vren" )
			)
			( signal "VR_PVNN_PCH_XADDR1"
				( objectStatus "@baseboard_fab2_lib.baseboard_fab2(sch_1):vr_pvnn_pch_xaddr1" )
			)
			( signal "VR_PVNN_PCH_XADDR2"
				( objectStatus "@baseboard_fab2_lib.baseboard_fab2(sch_1):vr_pvnn_pch_xaddr2" )
			)
			( signal "VSENSE_P1V05_PCH_STBY_AVSN"
				( objectStatus "@baseboard_fab2_lib.baseboard_fab2(sch_1):vsense_p1v05_pch_stby_avsn" )
			)
			( signal "VSENSE_P1V05_PCH_STBY_AVSP"
				( objectStatus "@baseboard_fab2_lib.baseboard_fab2(sch_1):vsense_p1v05_pch_stby_avsp" )
			)
			( signal "VSENSE_PVNN_PCH_STBY_AVSN"
				( objectStatus "@baseboard_fab2_lib.baseboard_fab2(sch_1):vsense_pvnn_pch_stby_avsn" )
			)
			( signal "VSENSE_PVNN_PCH_STBY_AVSP"
				( objectStatus "@baseboard_fab2_lib.baseboard_fab2(sch_1):vsense_pvnn_pch_stby_avsp" )
			)
			( signal "NC_P1V05_PCH_STBY_PH1_P31"
				( objectStatus "@baseboard_fab2_lib.baseboard_fab2(sch_1):nc_p1v05_pch_stby_ph1_p31" )
			)
			( signal "NC_PVNN_PCH_PH1_P31"
				( objectStatus "@baseboard_fab2_lib.baseboard_fab2(sch_1):nc_pvnn_pch_ph1_p31" )
			)
			( signal "TP_P1V05_PCH_GL_0"
				( objectStatus "@baseboard_fab2_lib.baseboard_fab2(sch_1):tp_p1v05_pch_gl_0" )
			)
			( signal "TP_P1V05_PCH_GL_1"
				( objectStatus "@baseboard_fab2_lib.baseboard_fab2(sch_1):tp_p1v05_pch_gl_1" )
			)
			( signal "TP_PVNN_PCH_GL_0"
				( objectStatus "@baseboard_fab2_lib.baseboard_fab2(sch_1):tp_pvnn_pch_gl_0" )
			)
			( signal "TP_PVNN_PCH_GL_1"
				( objectStatus "@baseboard_fab2_lib.baseboard_fab2(sch_1):tp_pvnn_pch_gl_1" )
			)
			( signal "VR_P1V05_PCH_STBY_OCSET"
				( objectStatus "@baseboard_fab2_lib.baseboard_fab2(sch_1):vr_p1v05_pch_stby_ocset" )
			)
			( signal "VR_P1V05_PCH_STBY_PH1_BOOT"
				( objectStatus "@baseboard_fab2_lib.baseboard_fab2(sch_1):vr_p1v05_pch_stby_ph1_boot" )
			)
			( signal "VR_P1V05_PCH_STBY_PH1_PHASE"
				( objectStatus "@baseboard_fab2_lib.baseboard_fab2(sch_1):vr_p1v05_pch_stby_ph1_phase" )
			)
			( signal "VR_P1V05_PCH_STBY_PH1_PHASE_SW"
				( objectStatus "@baseboard_fab2_lib.baseboard_fab2(sch_1):vr_p1v05_pch_stby_ph1_phase_sw" )
			)
			( signal "VR_P1V05_PCH_STBY_PH1_VCIN"
				( objectStatus "@baseboard_fab2_lib.baseboard_fab2(sch_1):vr_p1v05_pch_stby_ph1_vcin" )
			)
			( signal "VR_PVNN_PCH_PH1_BOOT"
				( objectStatus "@baseboard_fab2_lib.baseboard_fab2(sch_1):vr_pvnn_pch_ph1_boot" )
			)
			( signal "VR_PVNN_PCH_PH1_PHASE"
				( objectStatus "@baseboard_fab2_lib.baseboard_fab2(sch_1):vr_pvnn_pch_ph1_phase" )
			)
			( signal "VR_PVNN_PCH_PH1_PHASE_SW"
				( objectStatus "@baseboard_fab2_lib.baseboard_fab2(sch_1):vr_pvnn_pch_ph1_phase_sw" )
			)
			( signal "VR_PVNN_PCH_PH1_VCIN"
				( objectStatus "@baseboard_fab2_lib.baseboard_fab2(sch_1):vr_pvnn_pch_ph1_vcin" )
			)
			( signal "VR_PVNN_PCH_STBY_OCSET"
				( objectStatus "@baseboard_fab2_lib.baseboard_fab2(sch_1):vr_pvnn_pch_stby_ocset" )
			)
			( signal "PWRGD_P1V8_PCH_STBY_R"
				( objectStatus "@baseboard_fab2_lib.baseboard_fab2(sch_1):pwrgd_p1v8_pch_stby_r" )
			)
			( signal "VR_P1V8_PCH_STBY_FB"
				( objectStatus "@baseboard_fab2_lib.baseboard_fab2(sch_1):vr_p1v8_pch_stby_fb" )
			)
			( signal "PWRGD_P1V26_BMC_STBY_R"
				( objectStatus "@baseboard_fab2_lib.baseboard_fab2(sch_1):pwrgd_p1v26_bmc_stby_r" )
			)
			( signal "PWRGD_P1V538_BMC_STBY"
				( objectStatus "@baseboard_fab2_lib.baseboard_fab2(sch_1):pwrgd_p1v538_bmc_stby" )
			)
			( signal "VR_P1V26_BMC_STBY_FB"
				( objectStatus "@baseboard_fab2_lib.baseboard_fab2(sch_1):vr_p1v26_bmc_stby_fb" )
			)
			( signal "PWRGD_P1V538_BMC_STBY_R"
				( objectStatus "@baseboard_fab2_lib.baseboard_fab2(sch_1):pwrgd_p1v538_bmc_stby_r" )
			)
			( signal "VR_P1V538_BMC_STBY_FB"
				( objectStatus "@baseboard_fab2_lib.baseboard_fab2(sch_1):vr_p1v538_bmc_stby_fb" )
			)
			( signal "AGND_P3V3_STBY"
				( attribute "VOLTAGE" "0V"
					( Units "uVoltage" "V" 1.000000)
					( Status sAliasFlattened )
					( Origin gFrontEnd )
				)
				( objectStatus "@baseboard_fab2_lib.baseboard_fab2(sch_1):agnd_p3v3_stby" )
			)
			( signal "PWRGD_P3V3_STBY_R"
				( objectStatus "@baseboard_fab2_lib.baseboard_fab2(sch_1):pwrgd_p3v3_stby_r" )
			)
			( signal "PWRGD_P5V_STBY"
				( objectStatus "@baseboard_fab2_lib.baseboard_fab2(sch_1):pwrgd_p5v_stby" )
			)
			( signal "VR_FET_SW_P12V_STBY_P3V3_STBY"
				( objectStatus "@baseboard_fab2_lib.baseboard_fab2(sch_1):vr_fet_sw_p12v_stby_p3v3_stby" )
			)
			( signal "VR_P3V3_STBY_BOOT"
				( objectStatus "@baseboard_fab2_lib.baseboard_fab2(sch_1):vr_p3v3_stby_boot" )
			)
			( signal "VR_P3V3_STBY_BOOT_R"
				( objectStatus "@baseboard_fab2_lib.baseboard_fab2(sch_1):vr_p3v3_stby_boot_r" )
			)
			( signal "VR_P3V3_STBY_EN"
				( objectStatus "@baseboard_fab2_lib.baseboard_fab2(sch_1):vr_p3v3_stby_en" )
			)
			( signal "VR_P3V3_STBY_LGATE"
				( objectStatus "@baseboard_fab2_lib.baseboard_fab2(sch_1):vr_p3v3_stby_lgate" )
			)
			( signal "VR_P3V3_STBY_OCSELECT"
				( objectStatus "@baseboard_fab2_lib.baseboard_fab2(sch_1):vr_p3v3_stby_ocselect" )
			)
			( signal "VR_P3V3_STBY_PHASE"
				( objectStatus "@baseboard_fab2_lib.baseboard_fab2(sch_1):vr_p3v3_stby_phase" )
			)
			( signal "VR_P3V3_STBY_SNUB"
				( objectStatus "@baseboard_fab2_lib.baseboard_fab2(sch_1):vr_p3v3_stby_snub" )
			)
			( signal "VR_P3V3_STBY_UGATE"
				( objectStatus "@baseboard_fab2_lib.baseboard_fab2(sch_1):vr_p3v3_stby_ugate" )
			)
			( signal "VSENSE_P3V3_STBY"
				( objectStatus "@baseboard_fab2_lib.baseboard_fab2(sch_1):vsense_p3v3_stby" )
			)
			( signal "VSENSE_RGND_P3V3_STBY"
				( objectStatus "@baseboard_fab2_lib.baseboard_fab2(sch_1):vsense_rgnd_p3v3_stby" )
			)
			( signal "VSENSE_VOUT_P3V3_STBY"
				( objectStatus "@baseboard_fab2_lib.baseboard_fab2(sch_1):vsense_vout_p3v3_stby" )
			)
			( signal "AGND_P5V_STBY"
				( attribute "VOLTAGE" "0"
					( Units "uVoltage" "V" 1.000000)
					( Status sAliasFlattened )
					( Origin gFrontEnd )
				)
				( objectStatus "@baseboard_fab2_lib.baseboard_fab2(sch_1):agnd_p5v_stby" )
			)
			( signal "PWRGD_P5V_STBY_R"
				( objectStatus "@baseboard_fab2_lib.baseboard_fab2(sch_1):pwrgd_p5v_stby_r" )
			)
			( signal "VR_FET_SW_P5V_STBY_PVIN"
				( objectStatus "@baseboard_fab2_lib.baseboard_fab2(sch_1):vr_fet_sw_p5v_stby_pvin" )
			)
			( signal "VR_P5V_STBY_BOOT"
				( objectStatus "@baseboard_fab2_lib.baseboard_fab2(sch_1):vr_p5v_stby_boot" )
			)
			( signal "VR_P5V_STBY_COMP"
				( objectStatus "@baseboard_fab2_lib.baseboard_fab2(sch_1):vr_p5v_stby_comp" )
			)
			( signal "VR_P5V_STBY_EN"
				( objectStatus "@baseboard_fab2_lib.baseboard_fab2(sch_1):vr_p5v_stby_en" )
			)
			( signal "VR_P5V_STBY_PHASE"
				( objectStatus "@baseboard_fab2_lib.baseboard_fab2(sch_1):vr_p5v_stby_phase" )
			)
			( signal "VR_P5V_STBY_RC_COMP"
				( objectStatus "@baseboard_fab2_lib.baseboard_fab2(sch_1):vr_p5v_stby_rc_comp" )
			)
			( signal "VR_P5V_STBY_RT"
				( objectStatus "@baseboard_fab2_lib.baseboard_fab2(sch_1):vr_p5v_stby_rt" )
			)
			( signal "VR_P5V_STBY_SS"
				( objectStatus "@baseboard_fab2_lib.baseboard_fab2(sch_1):vr_p5v_stby_ss" )
			)
			( signal "VR_P5V_STBY_VIN"
				( objectStatus "@baseboard_fab2_lib.baseboard_fab2(sch_1):vr_p5v_stby_vin" )
			)
			( signal "VR_P5V_STBY_VSENSE"
				( objectStatus "@baseboard_fab2_lib.baseboard_fab2(sch_1):vr_p5v_stby_vsense" )
			)
			( signal "VR_P5V_STBY_VSENSE_R"
				( objectStatus "@baseboard_fab2_lib.baseboard_fab2(sch_1):vr_p5v_stby_vsense_r" )
			)
			( signal "A_TSENSE_P1V05_PCH_STBY_TMON"
				( objectStatus "@baseboard_fab2_lib.baseboard_fab2(sch_1):a_tsense_p1v05_pch_stby_tmon" )
			)
			( signal "A_TSENSE_PVCCIN_CPU1"
				( attribute "VOLTAGE" "3.6"
					( Units "uVoltage" "V" 1.000000)
					( Status sAliasFlattened )
					( Origin gFrontEnd )
				)
				( objectStatus "@baseboard_fab2_lib.baseboard_fab2(sch_1):a_tsense_pvccin_cpu1" )
			)
			( signal "A_TSENSE_PVCCIO_CPU1"
				( objectStatus "@baseboard_fab2_lib.baseboard_fab2(sch_1):a_tsense_pvccio_cpu1" )
			)
			( signal "FM_BATTERY_SENSE_EN_N"
				( objectStatus "@baseboard_fab2_lib.baseboard_fab2(sch_1):fm_battery_sense_en_n" )
			)
			( signal "H_CPU1_MEMKLM_MEMHOT_PCH_N"
				( objectStatus "@baseboard_fab2_lib.baseboard_fab2(sch_1):h_cpu1_memklm_memhot_pch_n" )
			)
			( signal "FM_CPU0_PROCHOT_PCH_N"
				( objectStatus "@baseboard_fab2_lib.baseboard_fab2(sch_1):fm_cpu0_prochot_pch_n" )
			)
			( gate "R6N10"
				( objectStatus "@baseboard_fab2_lib.baseboard_fab2(sch_1):page21_i149" )
				( pin "R6N10.1"
					( objectStatus "a" )
				)
				( pin "R6N10.2"
					( objectStatus "b" )
				)
			)
			( gate "R6N12"
				( objectStatus "@baseboard_fab2_lib.baseboard_fab2(sch_1):page21_i150" )
				( pin "R6N12.1"
					( objectStatus "a" )
				)
				( pin "R6N12.2"
					( objectStatus "b" )
				)
			)
			( gate "R6N11"
				( objectStatus "@baseboard_fab2_lib.baseboard_fab2(sch_1):page21_i151" )
				( pin "R6N11.1"
					( objectStatus "a" )
				)
				( pin "R6N11.2"
					( objectStatus "b" )
				)
			)
			( gate "R6B3"
				( objectStatus "@baseboard_fab2_lib.baseboard_fab2(sch_1):page21_i152" )
				( pin "R6B3.1"
					( objectStatus "a" )
				)
				( pin "R6B3.2"
					( objectStatus "b" )
				)
			)
			( gate "R6B5"
				( objectStatus "@baseboard_fab2_lib.baseboard_fab2(sch_1):page21_i153" )
				( pin "R6B5.1"
					( objectStatus "a" )
				)
				( pin "R6B5.2"
					( objectStatus "b" )
				)
			)
			( gate "R6B4"
				( objectStatus "@baseboard_fab2_lib.baseboard_fab2(sch_1):page21_i154" )
				( pin "R6B4.1"
					( objectStatus "a" )
				)
				( pin "R6B4.2"
					( objectStatus "b" )
				)
			)
			( gate "R6B2"
				( objectStatus "@baseboard_fab2_lib.baseboard_fab2(sch_1):page21_i159" )
				( pin "R6B2.1"
					( objectStatus "a" )
				)
				( pin "R6B2.2"
					( objectStatus "b" )
				)
			)
			( gate "R6B1"
				( objectStatus "@baseboard_fab2_lib.baseboard_fab2(sch_1):page21_i161" )
				( pin "R6B1.1"
					( objectStatus "a" )
				)
				( pin "R6B1.2"
					( objectStatus "b" )
				)
			)
			( gate "R6N2"
				( objectStatus "@baseboard_fab2_lib.baseboard_fab2(sch_1):page21_i163" )
				( pin "R6N2.1"
					( objectStatus "a" )
				)
				( pin "R6N2.2"
					( objectStatus "b" )
				)
			)
			( gate "R6N1"
				( objectStatus "@baseboard_fab2_lib.baseboard_fab2(sch_1):page21_i164" )
				( pin "R6N1.1"
					( objectStatus "a" )
				)
				( pin "R6N1.2"
					( objectStatus "b" )
				)
			)
			( gate "R5D1"
				( objectStatus "@baseboard_fab2_lib.baseboard_fab2(sch_1):page21_i177" )
				( pin "R5D1.1"
					( objectStatus "a" )
				)
				( pin "R5D1.2"
					( objectStatus "b" )
				)
			)
			( gate "R5D2"
				( objectStatus "@baseboard_fab2_lib.baseboard_fab2(sch_1):page21_i178" )
				( pin "R5D2.1"
					( objectStatus "a" )
				)
				( pin "R5D2.2"
					( objectStatus "b" )
				)
			)
			( gate "R6D1"
				( objectStatus "@baseboard_fab2_lib.baseboard_fab2(sch_1):page21_i179" )
				( pin "R6D1.1"
					( objectStatus "a" )
				)
				( pin "R6D1.2"
					( objectStatus "b" )
				)
			)
			( gate "R4P8"
				( objectStatus "@baseboard_fab2_lib.baseboard_fab2(sch_1):page21_i180" )
				( pin "R4P8.1"
					( objectStatus "a" )
				)
				( pin "R4P8.2"
					( objectStatus "b" )
				)
			)
			( gate "R4P10"
				( objectStatus "@baseboard_fab2_lib.baseboard_fab2(sch_1):page21_i181" )
				( pin "R4P10.1"
					( objectStatus "a" )
				)
				( pin "R4P10.2"
					( objectStatus "b" )
				)
			)
			( gate "R4P11"
				( objectStatus "@baseboard_fab2_lib.baseboard_fab2(sch_1):page21_i182" )
				( pin "R4P11.1"
					( objectStatus "a" )
				)
				( pin "R4P11.2"
					( objectStatus "b" )
				)
			)
			( gate "R6D11"
				( objectStatus "@baseboard_fab2_lib.baseboard_fab2(sch_1):page21_i184" )
				( pin "R6D11.1"
					( objectStatus "a" )
				)
				( pin "R6D11.2"
					( objectStatus "b" )
				)
			)
			( gate "R4P3"
				( objectStatus "@baseboard_fab2_lib.baseboard_fab2(sch_1):page21_i186" )
				( pin "R4P3.1"
					( objectStatus "a" )
				)
				( pin "R4P3.2"
					( objectStatus "b" )
				)
			)
			( gate "R4P2"
				( objectStatus "@baseboard_fab2_lib.baseboard_fab2(sch_1):page21_i188" )
				( pin "R4P2.1"
					( objectStatus "a" )
				)
				( pin "R4P2.2"
					( objectStatus "b" )
				)
			)
			( gate "R4P4"
				( objectStatus "@baseboard_fab2_lib.baseboard_fab2(sch_1):page21_i189" )
				( pin "R4P4.1"
					( objectStatus "a" )
				)
				( pin "R4P4.2"
					( objectStatus "b" )
				)
			)
			( gate "R6D2"
				( objectStatus "@baseboard_fab2_lib.baseboard_fab2(sch_1):page21_i204" )
				( pin "R6D2.1"
					( objectStatus "a" )
				)
				( pin "R6D2.2"
					( objectStatus "b" )
				)
			)
			( gate "XRU1"
				( objectStatus "@baseboard_fab2_lib.baseboard_fab2(sch_1):page21_i216" )
			)
			( gate "XLU1"
				( objectStatus "@baseboard_fab2_lib.baseboard_fab2(sch_1):page21_i217" )
			)
			( gate "R4P19"
				( objectStatus "@baseboard_fab2_lib.baseboard_fab2(sch_1):page21_i219" )
				( pin "R4P19.1"
					( objectStatus "a" )
				)
				( pin "R4P19.2"
					( objectStatus "b" )
				)
			)
			( gate "R5N2"
				( objectStatus "@baseboard_fab2_lib.baseboard_fab2(sch_1):page21_i227" )
				( pin "R5N2.1"
					( objectStatus "a" )
				)
				( pin "R5N2.2"
					( objectStatus "b" )
				)
			)
			( gate "R5N1"
				( objectStatus "@baseboard_fab2_lib.baseboard_fab2(sch_1):page21_i238" )
				( pin "R5N1.1"
					( objectStatus "a" )
				)
				( pin "R5N1.2"
					( objectStatus "b" )
				)
			)
			( gate "R5N5"
				( objectStatus "@baseboard_fab2_lib.baseboard_fab2(sch_1):page21_i239" )
				( pin "R5N5.1"
					( objectStatus "a" )
				)
				( pin "R5N5.2"
					( objectStatus "b" )
				)
			)
			( gate "R5N3"
				( objectStatus "@baseboard_fab2_lib.baseboard_fab2(sch_1):page21_i240" )
				( pin "R5N3.1"
					( objectStatus "a" )
				)
				( pin "R5N3.2"
					( objectStatus "b" )
				)
			)
			( gate "R5N4"
				( objectStatus "@baseboard_fab2_lib.baseboard_fab2(sch_1):page21_i241" )
				( pin "R5N4.1"
					( objectStatus "a" )
				)
				( pin "R5N4.2"
					( objectStatus "b" )
				)
			)
			( gate "R4P18"
				( objectStatus "@baseboard_fab2_lib.baseboard_fab2(sch_1):page21_i244" )
				( pin "R4P18.1"
					( objectStatus "a" )
				)
				( pin "R4P18.2"
					( objectStatus "b" )
				)
			)
			( gate "R4R5"
				( objectStatus "@baseboard_fab2_lib.baseboard_fab2(sch_1):page21_i258" )
				( pin "R4R5.1"
					( objectStatus "a" )
				)
				( pin "R4R5.2"
					( objectStatus "b" )
				)
			)
			( gate "U5D1"
				( objectStatus "@baseboard_fab2_lib.baseboard_fab2(sch_1):page21_i259" )
				( pin "U5D1.AU24"
					( objectStatus "bclk0_dn" )
				)
				( pin "U5D1.AW24"
					( objectStatus "bclk0_dp" )
				)
				( pin "U5D1.CR26"
					( objectStatus "bclk1_dn" )
				)
				( pin "U5D1.CP27"
					( objectStatus "bclk1_dp" )
				)
				( pin "U5D1.CT25"
					( objectStatus "bclk2_dn" )
				)
				( pin "U5D1.CU26"
					( objectStatus "bclk2_dp" )
				)
				( pin "U5D1.BA20"
					( objectStatus "bist_enable" )
				)
				( pin "U5D1.BD23"
					( objectStatus "bmcinit" )
				)
				( pin "U5D1.AJ10"
					( objectStatus "bpm_n(0)" )
				)
				( pin "U5D1.AH11"
					( objectStatus "bpm_n(1)" )
				)
				( pin "U5D1.AG10"
					( objectStatus "bpm_n(2)" )
				)
				( pin "U5D1.AF11"
					( objectStatus "bpm_n(3)" )
				)
				( pin "U5D1.AA12"
					( objectStatus "bpm_n(4)" )
				)
				( pin "U5D1.Y11"
					( objectStatus "bpm_n(5)" )
				)
				( pin "U5D1.AE12"
					( objectStatus "bpm_n(6)" )
				)
				( pin "U5D1.AC12"
					( objectStatus "bpm_n(7)" )
				)
				( pin "U5D1.AL14"
					( objectStatus "caterr_n" )
				)
				( pin "U5D1.AJ64"
					( objectStatus "ddr0_cavref" )
				)
				( pin "U5D1.AK63"
					( objectStatus "ddr1_cavref" )
				)
				( pin "U5D1.AH63"
					( objectStatus "ddr2_cavref" )
				)
				( pin "U5D1.CP61"
					( objectStatus "ddr3_cavref" )
				)
				( pin "U5D1.CT61"
					( objectStatus "ddr4_cavref" )
				)
				( pin "U5D1.CV61"
					( objectStatus "ddr5_cavref" )
				)
				( pin "U5D1.AN30"
					( objectStatus "ddr012_dram_pwr_ok" )
				)
				( pin "U5D1.Y43"
					( objectStatus "ddr012_rcomp(0)" )
				)
				( pin "U5D1.AB43"
					( objectStatus "ddr012_rcomp(1)" )
				)
				( pin "U5D1.AC42"
					( objectStatus "ddr012_rcomp(2)" )
				)
				( pin "U5D1.U64"
					( objectStatus "ddr012_reset_n" )
				)
				( pin "U5D1.AJ18"
					( objectStatus "ddr012_spdscl" )
				)
				( pin "U5D1.AF17"
					( objectStatus "ddr012_spdsda" )
				)
				( pin "U5D1.CR28"
					( objectStatus "ddr345_dram_pwr_ok" )
				)
				( pin "U5D1.DC48"
					( objectStatus "ddr345_rcomp(0)" )
				)
				( pin "U5D1.DD47"
					( objectStatus "ddr345_rcomp(1)" )
				)
				( pin "U5D1.DD49"
					( objectStatus "ddr345_rcomp(2)" )
				)
				( pin "U5D1.DV63"
					( objectStatus "ddr345_reset_n" )
				)
				( pin "U5D1.AE18"
					( objectStatus "ddr345_spdscl" )
				)
				( pin "U5D1.AD17"
					( objectStatus "ddr345_spdsda" )
				)
				( pin "U5D1.AJ14"
					( objectStatus "ear_n" )
				)
				( pin "U5D1.AJ12"
					( objectStatus "error_n(0)" )
				)
				( pin "U5D1.AK11"
					( objectStatus "error_n(1)" )
				)
				( pin "U5D1.AL12"
					( objectStatus "error_n(2)" )
				)
				( pin "U5D1.AV17"
					( objectStatus "frmagent" )
				)
				( pin "U5D1.AE20"
					( objectStatus "legacy_skt" )
				)
				( pin "U5D1.CU32"
					( objectStatus "mcp01_rbias(0)" )
				)
				( pin "U5D1.CT31"
					( objectStatus "mcp01_rbias(1)" )
				)
				( pin "U5D1.AH13"
					( objectStatus "mem_hot_c012_n" )
				)
				( pin "U5D1.AF13"
					( objectStatus "mem_hot_c345_n" )
				)
				( pin "U5D1.AN20"
					( objectStatus "msmi_n" )
				)
				( pin "U5D1.AP11"
					( objectStatus "nmi" )
				)
				( pin "U5D1.CP29"
					( objectStatus "pe3_rbias(0)" )
				)
				( pin "U5D1.CR30"
					( objectStatus "pe3_rbias(1)" )
				)
				( pin "U5D1.CN30"
					( objectStatus "pe012_rbias(0)" )
				)
				( pin "U5D1.CL30"
					( objectStatus "pe012_rbias(1)" )
				)
				( pin "U5D1.AM19"
					( objectStatus "pe_hp_scl" )
				)
				( pin "U5D1.AL18"
					( objectStatus "pe_hp_sda" )
				)
				( pin "U5D1.AU12"
					( objectStatus "peci" )
				)
				( pin "U5D1.CU58"
					( objectStatus "pirom_addr(0)" )
				)
				( pin "U5D1.CV57"
					( objectStatus "pirom_addr(1)" )
				)
				( pin "U5D1.CW56"
					( objectStatus "pirom_addr(2)" )
				)
				( pin "U5D1.DC72"
					( objectStatus "pkgid(0)" )
				)
				( pin "U5D1.CW72"
					( objectStatus "pkgid(1)" )
				)
				( pin "U5D1.DA72"
					( objectStatus "pkgid(2)" )
				)
				( pin "U5D1.AF15"
					( objectStatus "pm_fast_wake_n" )
				)
				( pin "U5D1.AR14"
					( objectStatus "pmsync" )
				)
				( pin "U5D1.AT19"
					( objectStatus "pmsync_clk" )
				)
				( pin "U5D1.AG16"
					( objectStatus "prdy_n" )
				)
				( pin "U5D1.AR12"
					( objectStatus "preq_n" )
				)
				( pin "U5D1.CY71"
					( objectStatus "proc_id(0)" )
				)
				( pin "U5D1.DB71"
					( objectStatus "proc_id(1)" )
				)
				( pin "U5D1.AB17"
					( objectStatus "procdis_n" )
				)
				( pin "U5D1.AC16"
					( objectStatus "prochot_n" )
				)
				( pin "U5D1.BC24"
					( objectStatus "pwrgood" )
				)
				( pin "U5D1.AP21"
					( objectStatus "reset_n" )
				)
				( pin "U5D1.AR18"
					( objectStatus "safe_mode_boot" )
				)
				( pin "U5D1.AB13"
					( objectStatus "sktocc_n" )
				)
				( pin "U5D1.CV59"
					( objectStatus "sm_wp" )
				)
				( pin "U5D1.CT59"
					( objectStatus "smbclk" )
				)
				( pin "U5D1.CW58"
					( objectStatus "smbdat" )
				)
				( pin "U5D1.AU22"
					( objectStatus "socket_id(0)" )
				)
				( pin "U5D1.AU16"
					( objectStatus "socket_id(1)" )
				)
				( pin "U5D1.AU20"
					( objectStatus "socket_id(2)" )
				)
				( pin "U5D1.DE44"
					( objectStatus "svidalert_n(0)" )
				)
				( pin "U5D1.DL44"
					( objectStatus "svidalert_n(1)" )
				)
				( pin "U5D1.DC44"
					( objectStatus "svidclk(0)" )
				)
				( pin "U5D1.DG44"
					( objectStatus "svidclk(1)" )
				)
				( pin "U5D1.DB45"
					( objectStatus "sviddata(0)" )
				)
				( pin "U5D1.DJ44"
					( objectStatus "sviddata(1)" )
				)
				( pin "U5D1.AA14"
					( objectStatus "tck" )
				)
				( pin "U5D1.AC14"
					( objectStatus "tdi" )
				)
				( pin "U5D1.AE14"
					( objectStatus "tdo" )
				)
				( pin "U5D1.AY19"
					( objectStatus "test_12" )
				)
				( pin "U5D1.DB51"
					( objectStatus "test_13" )
				)
				( pin "U5D1.DC50"
					( objectStatus "test_14" )
				)
				( pin "U5D1.AW14"
					( objectStatus "test_15" )
				)
				( pin "U5D1.AB15"
					( objectStatus "thermtrip_n" )
				)
				( pin "U5D1.W14"
					( objectStatus "tms" )
				)
				( pin "U5D1.Y13"
					( objectStatus "trst_n" )
				)
				( pin "U5D1.AM11"
					( objectStatus "tsc_sync" )
				)
				( pin "U5D1.AW18"
					( objectStatus "txt_agent" )
				)
				( pin "U5D1.AV15"
					( objectStatus "txt_plten" )
				)
				( pin "U5D1.AT29"
					( objectStatus "upi01_rbias(0)" )
				)
				( pin "U5D1.AP29"
					( objectStatus "upi01_rbias(1)" )
				)
				( pin "U5D1.CL28"
					( objectStatus "upi2_rbias(0)" )
				)
				( pin "U5D1.CK29"
					( objectStatus "upi2_rbias(1)" )
				)
			)
			( gate "R5R1"
				( objectStatus "@baseboard_fab2_lib.baseboard_fab2(sch_1):page22_i188" )
				( pin "R5R1.1"
					( objectStatus "a" )
				)
				( pin "R5R1.2"
					( objectStatus "b" )
				)
			)
			( gate "R5P4"
				( objectStatus "@baseboard_fab2_lib.baseboard_fab2(sch_1):page22_i190" )
				( pin "R5P4.1"
					( objectStatus "a" )
				)
				( pin "R5P4.2"
					( objectStatus "b" )
				)
			)
			( gate "U5D1"
				( objectStatus "@baseboard_fab2_lib.baseboard_fab2(sch_1):page22_i204" )
				( pin "U5D1.AV21"
					( objectStatus "debug_en_n" )
				)
				( pin "U5D1.AW12"
					( objectStatus "dmimode_override" )
				)
				( pin "U5D1.AU14"
					( objectStatus "fivr_fault" )
				)
				( pin "U5D1.AP17"
					( objectStatus "pwr_debug_n" )
				)
				( pin "U5D1.AP61"
					( objectStatus "rsvd(194)" )
				)
				( pin "U5D1.AP27"
					( objectStatus "rsvd(195)" )
				)
				( pin "U5D1.AP25"
					( objectStatus "rsvd(196)" )
				)
				( pin "U5D1.AP23"
					( objectStatus "rsvd(197)" )
				)
				( pin "U5D1.AN62"
					( objectStatus "rsvd(198)" )
				)
				( pin "U5D1.AN60"
					( objectStatus "rsvd(199)" )
				)
				( pin "U5D1.AN26"
					( objectStatus "rsvd(200)" )
				)
				( pin "U5D1.AN24"
					( objectStatus "rsvd(201)" )
				)
				( pin "U5D1.AN22"
					( objectStatus "rsvd(202)" )
				)
				( pin "U5D1.AN18"
					( objectStatus "rsvd(203)" )
				)
				( pin "U5D1.AM61"
					( objectStatus "rsvd(204)" )
				)
				( pin "U5D1.AM59"
					( objectStatus "rsvd(205)" )
				)
				( pin "U5D1.AM27"
					( objectStatus "rsvd(206)" )
				)
				( pin "U5D1.AM25"
					( objectStatus "rsvd(207)" )
				)
				( pin "U5D1.AM23"
					( objectStatus "rsvd(208)" )
				)
				( pin "U5D1.AM21"
					( objectStatus "rsvd(209)" )
				)
				( pin "U5D1.AL62"
					( objectStatus "rsvd(210)" )
				)
				( pin "U5D1.AL60"
					( objectStatus "rsvd(211)" )
				)
				( pin "U5D1.AL58"
					( objectStatus "rsvd(212)" )
				)
				( pin "U5D1.AL26"
					( objectStatus "rsvd(213)" )
				)
				( pin "U5D1.AL22"
					( objectStatus "rsvd(214)" )
				)
				( pin "U5D1.AL20"
					( objectStatus "rsvd(215)" )
				)
				( pin "U5D1.AK69"
					( objectStatus "rsvd(216)" )
				)
				( pin "U5D1.AK61"
					( objectStatus "rsvd(217)" )
				)
				( pin "U5D1.AK59"
					( objectStatus "rsvd(218)" )
				)
				( pin "U5D1.AK57"
					( objectStatus "rsvd(219)" )
				)
				( pin "U5D1.AK27"
					( objectStatus "rsvd(220)" )
				)
				( pin "U5D1.AK21"
					( objectStatus "rsvd(221)" )
				)
				( pin "U5D1.AJ70"
					( objectStatus "rsvd(222)" )
				)
				( pin "U5D1.AJ62"
					( objectStatus "rsvd(223)" )
				)
				( pin "U5D1.AJ60"
					( objectStatus "rsvd(224)" )
				)
				( pin "U5D1.AJ58"
					( objectStatus "rsvd(225)" )
				)
				( pin "U5D1.AJ56"
					( objectStatus "rsvd(226)" )
				)
				( pin "U5D1.AJ20"
					( objectStatus "rsvd(227)" )
				)
				( pin "U5D1.AH73"
					( objectStatus "rsvd(228)" )
				)
				( pin "U5D1.AH71"
					( objectStatus "rsvd(229)" )
				)
				( pin "U5D1.AH57"
					( objectStatus "rsvd(230)" )
				)
				( pin "U5D1.AH55"
					( objectStatus "rsvd(231)" )
				)
				( pin "U5D1.AH19"
					( objectStatus "rsvd(232)" )
				)
				( pin "U5D1.AH15"
					( objectStatus "rsvd(233)" )
				)
				( pin "U5D1.AG72"
					( objectStatus "rsvd(234)" )
				)
				( pin "U5D1.AG56"
					( objectStatus "rsvd(235)" )
				)
				( pin "U5D1.AG54"
					( objectStatus "rsvd(236)" )
				)
				( pin "U5D1.AG52"
					( objectStatus "rsvd(237)" )
				)
				( pin "U5D1.AG50"
					( objectStatus "rsvd(238)" )
				)
				( pin "U5D1.AG48"
					( objectStatus "rsvd(239)" )
				)
				( pin "U5D1.AG20"
					( objectStatus "rsvd(240)" )
				)
				( pin "U5D1.AF71"
					( objectStatus "rsvd(241)" )
				)
				( pin "U5D1.AF53"
					( objectStatus "rsvd(242)" )
				)
				( pin "U5D1.AF51"
					( objectStatus "rsvd(243)" )
				)
				( pin "U5D1.AF49"
					( objectStatus "rsvd(244)" )
				)
				( pin "U5D1.AF47"
					( objectStatus "rsvd(245)" )
				)
				( pin "U5D1.AF19"
					( objectStatus "rsvd(246)" )
				)
				( pin "U5D1.AE72"
					( objectStatus "rsvd(247)" )
				)
				( pin "U5D1.AE52"
					( objectStatus "rsvd(248)" )
				)
				( pin "U5D1.AE50"
					( objectStatus "rsvd(249)" )
				)
				( pin "U5D1.AE48"
					( objectStatus "rsvd(250)" )
				)
				( pin "U5D1.AE46"
					( objectStatus "rsvd(251)" )
				)
				( pin "U5D1.AD51"
					( objectStatus "rsvd(252)" )
				)
				( pin "U5D1.AD49"
					( objectStatus "rsvd(253)" )
				)
				( pin "U5D1.AD47"
					( objectStatus "rsvd(254)" )
				)
				( pin "U5D1.Y65"
					( objectStatus "rsvd(256)" )
				)
				( pin "U5D1.Y23"
					( objectStatus "rsvd(257)" )
				)
				( pin "U5D1.W66"
					( objectStatus "rsvd(258)" )
				)
				( pin "U5D1.V67"
					( objectStatus "rsvd(259)" )
				)
				( pin "U5D1.V65"
					( objectStatus "rsvd(260)" )
				)
				( pin "U5D1.U66"
					( objectStatus "rsvd(261)" )
				)
				( pin "U5D1.T67"
					( objectStatus "rsvd(262)" )
				)
				( pin "U5D1.R66"
					( objectStatus "rsvd(263)" )
				)
				( pin "U5D1.R62"
					( objectStatus "rsvd(264)" )
				)
				( pin "U5D1.P65"
					( objectStatus "rsvd(265)" )
				)
				( pin "U5D1.M63"
					( objectStatus "rsvd(266)" )
				)
				( pin "U5D1.K61"
					( objectStatus "rsvd(267)" )
				)
				( pin "U5D1.J62"
					( objectStatus "rsvd(268)" )
				)
				( pin "U5D1.J46"
					( objectStatus "rsvd(269)" )
				)
				( pin "U5D1.H85"
					( objectStatus "rsvd(270)" )
				)
				( pin "U5D1.H83"
					( objectStatus "rsvd(271)" )
				)
				( pin "U5D1.H1"
					( objectStatus "rsvd(272)" )
				)
				( pin "U5D1.G84"
					( objectStatus "rsvd(273)" )
				)
				( pin "U5D1.G64"
					( objectStatus "rsvd(274)" )
				)
				( pin "U5D1.G2"
					( objectStatus "rsvd(275)" )
				)
				( pin "U5D1.F83"
					( objectStatus "rsvd(276)" )
				)
				( pin "U5D1.F65"
					( objectStatus "rsvd(277)" )
				)
				( pin "U5D1.F23"
					( objectStatus "rsvd(278)" )
				)
				( pin "U5D1.F3"
					( objectStatus "rsvd(279)" )
				)
				( pin "U5D1.E84"
					( objectStatus "rsvd(280)" )
				)
				( pin "U5D1.E24"
					( objectStatus "rsvd(281)" )
				)
				( pin "U5D1.E4"
					( objectStatus "rsvd(282)" )
				)
				( pin "U5D1.E2"
					( objectStatus "rsvd(283)" )
				)
				( pin "U5D1.D83"
					( objectStatus "rsvd(284)" )
				)
				( pin "U5D1.D65"
					( objectStatus "rsvd(285)" )
				)
				( pin "U5D1.D17"
					( objectStatus "rsvd(286)" )
				)
				( pin "U5D1.D5"
					( objectStatus "rsvd(287)" )
				)
				( pin "U5D1.C82"
					( objectStatus "rsvd(288)" )
				)
				( pin "U5D1.C24"
					( objectStatus "rsvd(289)" )
				)
				( pin "U5D1.C18"
					( objectStatus "rsvd(290)" )
				)
				( pin "U5D1.C6"
					( objectStatus "rsvd(291)" )
				)
				( pin "U5D1.B81"
					( objectStatus "rsvd(292)" )
				)
				( pin "U5D1.B77"
					( objectStatus "rsvd(293)" )
				)
				( pin "U5D1.B17"
					( objectStatus "rsvd(294)" )
				)
				( pin "U5D1.B15"
					( objectStatus "rsvd(295)" )
				)
				( pin "U5D1.B13"
					( objectStatus "rsvd(296)" )
				)
				( pin "U5D1.B7"
					( objectStatus "rsvd(298)" )
				)
				( pin "U5D1.B3"
					( objectStatus "rsvd(299)" )
				)
				( pin "U5D1.A24"
					( objectStatus "rsvd(300)" )
				)
				( pin "U5D1.A16"
					( objectStatus "rsvd(301)" )
				)
				( pin "U5D1.A14"
					( objectStatus "rsvd(302)" )
				)
				( pin "U5D1.A6"
					( objectStatus "rsvd(303)" )
				)
				( pin "U5D1.A4"
					( objectStatus "rsvd(304)" )
				)
				( pin "U5D1.AF45"
					( objectStatus "test_1" )
				)
				( pin "U5D1.AG46"
					( objectStatus "test_2" )
				)
				( pin "U5D1.AM13"
					( objectStatus "test_3" )
				)
				( pin "U5D1.AN12"
					( objectStatus "test_4" )
				)
				( pin "U5D1.AN14"
					( objectStatus "test_5" )
				)
				( pin "U5D1.AY13"
					( objectStatus "test_11" )
				)
			)
			( gate "U5D1"
				( objectStatus "@baseboard_fab2_lib.baseboard_fab2(sch_1):page23_i172" )
				( pin "U5D1.J60"
					( objectStatus "ddr0_act_n" )
				)
				( pin "U5D1.B61"
					( objectStatus "ddr0_alert_n" )
				)
				( pin "U5D1.C52"
					( objectStatus "ddr0_ba(0)" )
				)
				( pin "U5D1.G54"
					( objectStatus "ddr0_ba(1)" )
				)
				( pin "U5D1.D61"
					( objectStatus "ddr0_bg(0)" )
				)
				( pin "U5D1.F63"
					( objectStatus "ddr0_bg(1)" )
				)
				( pin "U5D1.G46"
					( objectStatus "ddr0_cid(2)" )
				)
				( pin "U5D1.C62"
					( objectStatus "ddr0_cke(0)" )
				)
				( pin "U5D1.C64"
					( objectStatus "ddr0_cke(1)" )
				)
				( pin "U5D1.B63"
					( objectStatus "ddr0_cke(2)" )
				)
				( pin "U5D1.D63"
					( objectStatus "ddr0_cke(3)" )
				)
				( pin "U5D1.F55"
					( objectStatus "ddr0_clk_dn(0)" )
				)
				( pin "U5D1.C54"
					( objectStatus "ddr0_clk_dn(1)" )
				)
				( pin "U5D1.J56"
					( objectStatus "ddr0_clk_dn(2)" )
				)
				( pin "U5D1.C56"
					( objectStatus "ddr0_clk_dn(3)" )
				)
				( pin "U5D1.D55"
					( objectStatus "ddr0_clk_dp(0)" )
				)
				( pin "U5D1.B55"
					( objectStatus "ddr0_clk_dp(1)" )
				)
				( pin "U5D1.G56"
					( objectStatus "ddr0_clk_dp(2)" )
				)
				( pin "U5D1.B57"
					( objectStatus "ddr0_clk_dp(3)" )
				)
				( pin "U5D1.G52"
					( objectStatus "ddr0_cs_n(0)" )
				)
				( pin "U5D1.F49"
					( objectStatus "ddr0_cs_n(1)" )
				)
				( pin "U5D1.D47"
					( objectStatus "ddr0_cs_n(2)" )
				)
				( pin "U5D1.F47"
					( objectStatus "ddr0_cs_n(3)" )
				)
				( pin "U5D1.B51"
					( objectStatus "ddr0_cs_n(4)" )
				)
				( pin "U5D1.D49"
					( objectStatus "ddr0_cs_n(5)" )
				)
				( pin "U5D1.F45"
					( objectStatus "ddr0_cs_n(6)" )
				)
				( pin "U5D1.K45"
					( objectStatus "ddr0_cs_n(7)" )
				)
				( pin "U5D1.AN86"
					( objectStatus "ddr0_dq(0)" )
				)
				( pin "U5D1.AN84"
					( objectStatus "ddr0_dq(1)" )
				)
				( pin "U5D1.AE86"
					( objectStatus "ddr0_dq(2)" )
				)
				( pin "U5D1.AE84"
					( objectStatus "ddr0_dq(3)" )
				)
				( pin "U5D1.AR86"
					( objectStatus "ddr0_dq(4)" )
				)
				( pin "U5D1.AR84"
					( objectStatus "ddr0_dq(5)" )
				)
				( pin "U5D1.AG86"
					( objectStatus "ddr0_dq(6)" )
				)
				( pin "U5D1.AG84"
					( objectStatus "ddr0_dq(7)" )
				)
				( pin "U5D1.W86"
					( objectStatus "ddr0_dq(8)" )
				)
				( pin "U5D1.W84"
					( objectStatus "ddr0_dq(9)" )
				)
				( pin "U5D1.L86"
					( objectStatus "ddr0_dq(10)" )
				)
				( pin "U5D1.L84"
					( objectStatus "ddr0_dq(11)" )
				)
				( pin "U5D1.AA86"
					( objectStatus "ddr0_dq(12)" )
				)
				( pin "U5D1.AA84"
					( objectStatus "ddr0_dq(13)" )
				)
				( pin "U5D1.N86"
					( objectStatus "ddr0_dq(14)" )
				)
				( pin "U5D1.N84"
					( objectStatus "ddr0_dq(15)" )
				)
				( pin "U5D1.V81"
					( objectStatus "ddr0_dq(16)" )
				)
				( pin "U5D1.T79"
					( objectStatus "ddr0_dq(17)" )
				)
				( pin "U5D1.N82"
					( objectStatus "ddr0_dq(18)" )
				)
				( pin "U5D1.M81"
					( objectStatus "ddr0_dq(19)" )
				)
				( pin "U5D1.W80"
					( objectStatus "ddr0_dq(20)" )
				)
				( pin "U5D1.V79"
					( objectStatus "ddr0_dq(21)" )
				)
				( pin "U5D1.R82"
					( objectStatus "ddr0_dq(22)" )
				)
				( pin "U5D1.N80"
					( objectStatus "ddr0_dq(23)" )
				)
				( pin "U5D1.L76"
					( objectStatus "ddr0_dq(24)" )
				)
				( pin "U5D1.R76"
					( objectStatus "ddr0_dq(25)" )
				)
				( pin "U5D1.M73"
					( objectStatus "ddr0_dq(26)" )
				)
				( pin "U5D1.P73"
					( objectStatus "ddr0_dq(27)" )
				)
				( pin "U5D1.M77"
					( objectStatus "ddr0_dq(28)" )
				)
				( pin "U5D1.P77"
					( objectStatus "ddr0_dq(29)" )
				)
				( pin "U5D1.L74"
					( objectStatus "ddr0_dq(30)" )
				)
				( pin "U5D1.R74"
					( objectStatus "ddr0_dq(31)" )
				)
				( pin "U5D1.C42"
					( objectStatus "ddr0_dq(32)" )
				)
				( pin "U5D1.B41"
					( objectStatus "ddr0_dq(33)" )
				)
				( pin "U5D1.C38"
					( objectStatus "ddr0_dq(34)" )
				)
				( pin "U5D1.E38"
					( objectStatus "ddr0_dq(35)" )
				)
				( pin "U5D1.E42"
					( objectStatus "ddr0_dq(36)" )
				)
				( pin "U5D1.F41"
					( objectStatus "ddr0_dq(37)" )
				)
				( pin "U5D1.B39"
					( objectStatus "ddr0_dq(38)" )
				)
				( pin "U5D1.F39"
					( objectStatus "ddr0_dq(39)" )
				)
				( pin "U5D1.K37"
					( objectStatus "ddr0_dq(40)" )
				)
				( pin "U5D1.P37"
					( objectStatus "ddr0_dq(41)" )
				)
				( pin "U5D1.L34"
					( objectStatus "ddr0_dq(42)" )
				)
				( pin "U5D1.N34"
					( objectStatus "ddr0_dq(43)" )
				)
				( pin "U5D1.L38"
					( objectStatus "ddr0_dq(44)" )
				)
				( pin "U5D1.N38"
					( objectStatus "ddr0_dq(45)" )
				)
				( pin "U5D1.K35"
					( objectStatus "ddr0_dq(46)" )
				)
				( pin "U5D1.P35"
					( objectStatus "ddr0_dq(47)" )
				)
				( pin "U5D1.K31"
					( objectStatus "ddr0_dq(48)" )
				)
				( pin "U5D1.P31"
					( objectStatus "ddr0_dq(49)" )
				)
				( pin "U5D1.L28"
					( objectStatus "ddr0_dq(50)" )
				)
				( pin "U5D1.N28"
					( objectStatus "ddr0_dq(51)" )
				)
				( pin "U5D1.L32"
					( objectStatus "ddr0_dq(52)" )
				)
				( pin "U5D1.N32"
					( objectStatus "ddr0_dq(53)" )
				)
				( pin "U5D1.K29"
					( objectStatus "ddr0_dq(54)" )
				)
				( pin "U5D1.P29"
					( objectStatus "ddr0_dq(55)" )
				)
				( pin "U5D1.K25"
					( objectStatus "ddr0_dq(56)" )
				)
				( pin "U5D1.P25"
					( objectStatus "ddr0_dq(57)" )
				)
				( pin "U5D1.P23"
					( objectStatus "ddr0_dq(58)" )
				)
				( pin "U5D1.T23"
					( objectStatus "ddr0_dq(59)" )
				)
				( pin "U5D1.L26"
					( objectStatus "ddr0_dq(60)" )
				)
				( pin "U5D1.N26"
					( objectStatus "ddr0_dq(61)" )
				)
				( pin "U5D1.H23"
					( objectStatus "ddr0_dq(62)" )
				)
				( pin "U5D1.K23"
					( objectStatus "ddr0_dq(63)" )
				)
				( pin "U5D1.AJ84"
					( objectStatus "ddr0_dqs_dn(0)" )
				)
				( pin "U5D1.R84"
					( objectStatus "ddr0_dqs_dn(1)" )
				)
				( pin "U5D1.P79"
					( objectStatus "ddr0_dqs_dn(2)" )
				)
				( pin "U5D1.T75"
					( objectStatus "ddr0_dqs_dn(3)" )
				)
				( pin "U5D1.G40"
					( objectStatus "ddr0_dqs_dn(4)" )
				)
				( pin "U5D1.R36"
					( objectStatus "ddr0_dqs_dn(5)" )
				)
				( pin "U5D1.R30"
					( objectStatus "ddr0_dqs_dn(6)" )
				)
				( pin "U5D1.N24"
					( objectStatus "ddr0_dqs_dn(7)" )
				)
				( pin "U5D1.AH67"
					( objectStatus "ddr0_dqs_dn(8)" )
				)
				( pin "U5D1.AL84"
					( objectStatus "ddr0_dqs_dn(9)" )
				)
				( pin "U5D1.U84"
					( objectStatus "ddr0_dqs_dn(10)" )
				)
				( pin "U5D1.U82"
					( objectStatus "ddr0_dqs_dn(11)" )
				)
				( pin "U5D1.K75"
					( objectStatus "ddr0_dqs_dn(12)" )
				)
				( pin "U5D1.A40"
					( objectStatus "ddr0_dqs_dn(13)" )
				)
				( pin "U5D1.J36"
					( objectStatus "ddr0_dqs_dn(14)" )
				)
				( pin "U5D1.J30"
					( objectStatus "ddr0_dqs_dn(15)" )
				)
				( pin "U5D1.J24"
					( objectStatus "ddr0_dqs_dn(16)" )
				)
				( pin "U5D1.AB67"
					( objectStatus "ddr0_dqs_dn(17)" )
				)
				( pin "U5D1.AH85"
					( objectStatus "ddr0_dqs_dp(0)" )
				)
				( pin "U5D1.P85"
					( objectStatus "ddr0_dqs_dp(1)" )
				)
				( pin "U5D1.R80"
					( objectStatus "ddr0_dqs_dp(2)" )
				)
				( pin "U5D1.P75"
					( objectStatus "ddr0_dqs_dp(3)" )
				)
				( pin "U5D1.E40"
					( objectStatus "ddr0_dqs_dp(4)" )
				)
				( pin "U5D1.N36"
					( objectStatus "ddr0_dqs_dp(5)" )
				)
				( pin "U5D1.N30"
					( objectStatus "ddr0_dqs_dp(6)" )
				)
				( pin "U5D1.R24"
					( objectStatus "ddr0_dqs_dp(7)" )
				)
				( pin "U5D1.AF67"
					( objectStatus "ddr0_dqs_dp(8)" )
				)
				( pin "U5D1.AM85"
					( objectStatus "ddr0_dqs_dp(9)" )
				)
				( pin "U5D1.V85"
					( objectStatus "ddr0_dqs_dp(10)" )
				)
				( pin "U5D1.T81"
					( objectStatus "ddr0_dqs_dp(11)" )
				)
				( pin "U5D1.M75"
					( objectStatus "ddr0_dqs_dp(12)" )
				)
				( pin "U5D1.C40"
					( objectStatus "ddr0_dqs_dp(13)" )
				)
				( pin "U5D1.L36"
					( objectStatus "ddr0_dqs_dp(14)" )
				)
				( pin "U5D1.L30"
					( objectStatus "ddr0_dqs_dp(15)" )
				)
				( pin "U5D1.L24"
					( objectStatus "ddr0_dqs_dp(16)" )
				)
				( pin "U5D1.AD67"
					( objectStatus "ddr0_dqs_dp(17)" )
				)
				( pin "U5D1.AC68"
					( objectStatus "ddr0_ecc(0)" )
				)
				( pin "U5D1.AG68"
					( objectStatus "ddr0_ecc(1)" )
				)
				( pin "U5D1.AD65"
					( objectStatus "ddr0_ecc(2)" )
				)
				( pin "U5D1.AF65"
					( objectStatus "ddr0_ecc(3)" )
				)
				( pin "U5D1.AD69"
					( objectStatus "ddr0_ecc(4)" )
				)
				( pin "U5D1.AF69"
					( objectStatus "ddr0_ecc(5)" )
				)
				( pin "U5D1.AC66"
					( objectStatus "ddr0_ecc(6)" )
				)
				( pin "U5D1.AG66"
					( objectStatus "ddr0_ecc(7)" )
				)
				( pin "U5D1.F53"
					( objectStatus "ddr0_ma(0)" )
				)
				( pin "U5D1.F57"
					( objectStatus "ddr0_ma(1)" )
				)
				( pin "U5D1.D57"
					( objectStatus "ddr0_ma(2)" )
				)
				( pin "U5D1.C58"
					( objectStatus "ddr0_ma(3)" )
				)
				( pin "U5D1.G58"
					( objectStatus "ddr0_ma(4)" )
				)
				( pin "U5D1.F59"
					( objectStatus "ddr0_ma(5)" )
				)
				( pin "U5D1.D59"
					( objectStatus "ddr0_ma(6)" )
				)
				( pin "U5D1.G60"
					( objectStatus "ddr0_ma(7)" )
				)
				( pin "U5D1.C60"
					( objectStatus "ddr0_ma(8)" )
				)
				( pin "U5D1.F61"
					( objectStatus "ddr0_ma(9)" )
				)
				( pin "U5D1.J54"
					( objectStatus "ddr0_ma(10)" )
				)
				( pin "U5D1.G62"
					( objectStatus "ddr0_ma(11)" )
				)
				( pin "U5D1.J64"
					( objectStatus "ddr0_ma(12)" )
				)
				( pin "U5D1.J48"
					( objectStatus "ddr0_ma(13)" )
				)
				( pin "U5D1.F51"
					( objectStatus "ddr0_ma(14)" )
				)
				( pin "U5D1.K49"
					( objectStatus "ddr0_ma(15)" )
				)
				( pin "U5D1.D51"
					( objectStatus "ddr0_ma(16)" )
				)
				( pin "U5D1.K47"
					( objectStatus "ddr0_ma(17)" )
				)
				( pin "U5D1.C50"
					( objectStatus "ddr0_odt(0)" )
				)
				( pin "U5D1.C48"
					( objectStatus "ddr0_odt(1)" )
				)
				( pin "U5D1.G50"
					( objectStatus "ddr0_odt(2)" )
				)
				( pin "U5D1.G48"
					( objectStatus "ddr0_odt(3)" )
				)
				( pin "U5D1.D53"
					( objectStatus "ddr0_par" )
				)
			)
			( gate "U5D1"
				( objectStatus "@baseboard_fab2_lib.baseboard_fab2(sch_1):page24_i172" )
				( pin "U5D1.T63"
					( objectStatus "ddr1_act_n" )
				)
				( pin "U5D1.W62"
					( objectStatus "ddr1_alert_n" )
				)
				( pin "U5D1.T53"
					( objectStatus "ddr1_ba(0)" )
				)
				( pin "U5D1.K55"
					( objectStatus "ddr1_ba(1)" )
				)
				( pin "U5D1.M61"
					( objectStatus "ddr1_bg(0)" )
				)
				( pin "U5D1.N60"
					( objectStatus "ddr1_bg(1)" )
				)
				( pin "U5D1.M47"
					( objectStatus "ddr1_cid(2)" )
				)
				( pin "U5D1.N62"
					( objectStatus "ddr1_cke(0)" )
				)
				( pin "U5D1.R64"
					( objectStatus "ddr1_cke(1)" )
				)
				( pin "U5D1.K63"
					( objectStatus "ddr1_cke(2)" )
				)
				( pin "U5D1.L64"
					( objectStatus "ddr1_cke(3)" )
				)
				( pin "U5D1.M53"
					( objectStatus "ddr1_clk_dn(0)" )
				)
				( pin "U5D1.R54"
					( objectStatus "ddr1_clk_dn(1)" )
				)
				( pin "U5D1.N56"
					( objectStatus "ddr1_clk_dn(2)" )
				)
				( pin "U5D1.R56"
					( objectStatus "ddr1_clk_dn(3)" )
				)
				( pin "U5D1.N54"
					( objectStatus "ddr1_clk_dp(0)" )
				)
				( pin "U5D1.T55"
					( objectStatus "ddr1_clk_dp(1)" )
				)
				( pin "U5D1.M57"
					( objectStatus "ddr1_clk_dp(2)" )
				)
				( pin "U5D1.T57"
					( objectStatus "ddr1_clk_dp(3)" )
				)
				( pin "U5D1.K51"
					( objectStatus "ddr1_cs_n(0)" )
				)
				( pin "U5D1.R50"
					( objectStatus "ddr1_cs_n(1)" )
				)
				( pin "U5D1.N46"
					( objectStatus "ddr1_cs_n(2)" )
				)
				( pin "U5D1.V47"
					( objectStatus "ddr1_cs_n(3)" )
				)
				( pin "U5D1.J50"
					( objectStatus "ddr1_cs_n(4)" )
				)
				( pin "U5D1.T49"
					( objectStatus "ddr1_cs_n(5)" )
				)
				( pin "U5D1.M45"
					( objectStatus "ddr1_cs_n(6)" )
				)
				( pin "U5D1.R46"
					( objectStatus "ddr1_cs_n(7)" )
				)
				( pin "U5D1.AV81"
					( objectStatus "ddr1_dq(0)" )
				)
				( pin "U5D1.AT79"
					( objectStatus "ddr1_dq(1)" )
				)
				( pin "U5D1.AN82"
					( objectStatus "ddr1_dq(2)" )
				)
				( pin "U5D1.AM81"
					( objectStatus "ddr1_dq(3)" )
				)
				( pin "U5D1.AW80"
					( objectStatus "ddr1_dq(4)" )
				)
				( pin "U5D1.AV79"
					( objectStatus "ddr1_dq(5)" )
				)
				( pin "U5D1.AR82"
					( objectStatus "ddr1_dq(6)" )
				)
				( pin "U5D1.AN80"
					( objectStatus "ddr1_dq(7)" )
				)
				( pin "U5D1.AH81"
					( objectStatus "ddr1_dq(8)" )
				)
				( pin "U5D1.AF79"
					( objectStatus "ddr1_dq(9)" )
				)
				( pin "U5D1.AC82"
					( objectStatus "ddr1_dq(10)" )
				)
				( pin "U5D1.AB81"
					( objectStatus "ddr1_dq(11)" )
				)
				( pin "U5D1.AJ80"
					( objectStatus "ddr1_dq(12)" )
				)
				( pin "U5D1.AH79"
					( objectStatus "ddr1_dq(13)" )
				)
				( pin "U5D1.AE82"
					( objectStatus "ddr1_dq(14)" )
				)
				( pin "U5D1.AC80"
					( objectStatus "ddr1_dq(15)" )
				)
				( pin "U5D1.E80"
					( objectStatus "ddr1_dq(16)" )
				)
				( pin "U5D1.J80"
					( objectStatus "ddr1_dq(17)" )
				)
				( pin "U5D1.F77"
					( objectStatus "ddr1_dq(18)" )
				)
				( pin "U5D1.H77"
					( objectStatus "ddr1_dq(19)" )
				)
				( pin "U5D1.F81"
					( objectStatus "ddr1_dq(20)" )
				)
				( pin "U5D1.H81"
					( objectStatus "ddr1_dq(21)" )
				)
				( pin "U5D1.E78"
					( objectStatus "ddr1_dq(22)" )
				)
				( pin "U5D1.J78"
					( objectStatus "ddr1_dq(23)" )
				)
				( pin "U5D1.D75"
					( objectStatus "ddr1_dq(24)" )
				)
				( pin "U5D1.C74"
					( objectStatus "ddr1_dq(25)" )
				)
				( pin "U5D1.D71"
					( objectStatus "ddr1_dq(26)" )
				)
				( pin "U5D1.F71"
					( objectStatus "ddr1_dq(27)" )
				)
				( pin "U5D1.F75"
					( objectStatus "ddr1_dq(28)" )
				)
				( pin "U5D1.G74"
					( objectStatus "ddr1_dq(29)" )
				)
				( pin "U5D1.C72"
					( objectStatus "ddr1_dq(30)" )
				)
				( pin "U5D1.G72"
					( objectStatus "ddr1_dq(31)" )
				)
				( pin "U5D1.K43"
					( objectStatus "ddr1_dq(32)" )
				)
				( pin "U5D1.H43"
					( objectStatus "ddr1_dq(33)" )
				)
				( pin "U5D1.L40"
					( objectStatus "ddr1_dq(34)" )
				)
				( pin "U5D1.N40"
					( objectStatus "ddr1_dq(35)" )
				)
				( pin "U5D1.P43"
					( objectStatus "ddr1_dq(36)" )
				)
				( pin "U5D1.T43"
					( objectStatus "ddr1_dq(37)" )
				)
				( pin "U5D1.K41"
					( objectStatus "ddr1_dq(38)" )
				)
				( pin "U5D1.P41"
					( objectStatus "ddr1_dq(39)" )
				)
				( pin "U5D1.C36"
					( objectStatus "ddr1_dq(40)" )
				)
				( pin "U5D1.B35"
					( objectStatus "ddr1_dq(41)" )
				)
				( pin "U5D1.C32"
					( objectStatus "ddr1_dq(42)" )
				)
				( pin "U5D1.E32"
					( objectStatus "ddr1_dq(43)" )
				)
				( pin "U5D1.E36"
					( objectStatus "ddr1_dq(44)" )
				)
				( pin "U5D1.F35"
					( objectStatus "ddr1_dq(45)" )
				)
				( pin "U5D1.B33"
					( objectStatus "ddr1_dq(46)" )
				)
				( pin "U5D1.F33"
					( objectStatus "ddr1_dq(47)" )
				)
				( pin "U5D1.C30"
					( objectStatus "ddr1_dq(48)" )
				)
				( pin "U5D1.B29"
					( objectStatus "ddr1_dq(49)" )
				)
				( pin "U5D1.C26"
					( objectStatus "ddr1_dq(50)" )
				)
				( pin "U5D1.E26"
					( objectStatus "ddr1_dq(51)" )
				)
				( pin "U5D1.E30"
					( objectStatus "ddr1_dq(52)" )
				)
				( pin "U5D1.F29"
					( objectStatus "ddr1_dq(53)" )
				)
				( pin "U5D1.B27"
					( objectStatus "ddr1_dq(54)" )
				)
				( pin "U5D1.F27"
					( objectStatus "ddr1_dq(55)" )
				)
				( pin "U5D1.U28"
					( objectStatus "ddr1_dq(56)" )
				)
				( pin "U5D1.AA28"
					( objectStatus "ddr1_dq(57)" )
				)
				( pin "U5D1.V25"
					( objectStatus "ddr1_dq(58)" )
				)
				( pin "U5D1.Y25"
					( objectStatus "ddr1_dq(59)" )
				)
				( pin "U5D1.V29"
					( objectStatus "ddr1_dq(60)" )
				)
				( pin "U5D1.Y29"
					( objectStatus "ddr1_dq(61)" )
				)
				( pin "U5D1.U26"
					( objectStatus "ddr1_dq(62)" )
				)
				( pin "U5D1.AA26"
					( objectStatus "ddr1_dq(63)" )
				)
				( pin "U5D1.AP79"
					( objectStatus "ddr1_dqs_dn(0)" )
				)
				( pin "U5D1.AD79"
					( objectStatus "ddr1_dqs_dn(1)" )
				)
				( pin "U5D1.K79"
					( objectStatus "ddr1_dqs_dn(2)" )
				)
				( pin "U5D1.H73"
					( objectStatus "ddr1_dqs_dn(3)" )
				)
				( pin "U5D1.N42"
					( objectStatus "ddr1_dqs_dn(4)" )
				)
				( pin "U5D1.G34"
					( objectStatus "ddr1_dqs_dn(5)" )
				)
				( pin "U5D1.G28"
					( objectStatus "ddr1_dqs_dn(6)" )
				)
				( pin "U5D1.AB27"
					( objectStatus "ddr1_dqs_dn(7)" )
				)
				( pin "U5D1.N68"
					( objectStatus "ddr1_dqs_dn(8)" )
				)
				( pin "U5D1.AU82"
					( objectStatus "ddr1_dqs_dn(9)" )
				)
				( pin "U5D1.AG82"
					( objectStatus "ddr1_dqs_dn(10)" )
				)
				( pin "U5D1.D79"
					( objectStatus "ddr1_dqs_dn(11)" )
				)
				( pin "U5D1.B73"
					( objectStatus "ddr1_dqs_dn(12)" )
				)
				( pin "U5D1.J42"
					( objectStatus "ddr1_dqs_dn(13)" )
				)
				( pin "U5D1.A34"
					( objectStatus "ddr1_dqs_dn(14)" )
				)
				( pin "U5D1.A28"
					( objectStatus "ddr1_dqs_dn(15)" )
				)
				( pin "U5D1.T27"
					( objectStatus "ddr1_dqs_dn(16)" )
				)
				( pin "U5D1.G68"
					( objectStatus "ddr1_dqs_dn(17)" )
				)
				( pin "U5D1.AR80"
					( objectStatus "ddr1_dqs_dp(0)" )
				)
				( pin "U5D1.AE80"
					( objectStatus "ddr1_dqs_dp(1)" )
				)
				( pin "U5D1.H79"
					( objectStatus "ddr1_dqs_dp(2)" )
				)
				( pin "U5D1.F73"
					( objectStatus "ddr1_dqs_dp(3)" )
				)
				( pin "U5D1.R42"
					( objectStatus "ddr1_dqs_dp(4)" )
				)
				( pin "U5D1.E34"
					( objectStatus "ddr1_dqs_dp(5)" )
				)
				( pin "U5D1.E28"
					( objectStatus "ddr1_dqs_dp(6)" )
				)
				( pin "U5D1.Y27"
					( objectStatus "ddr1_dqs_dp(7)" )
				)
				( pin "U5D1.L68"
					( objectStatus "ddr1_dqs_dp(8)" )
				)
				( pin "U5D1.AT81"
					( objectStatus "ddr1_dqs_dp(9)" )
				)
				( pin "U5D1.AF81"
					( objectStatus "ddr1_dqs_dp(10)" )
				)
				( pin "U5D1.F79"
					( objectStatus "ddr1_dqs_dp(11)" )
				)
				( pin "U5D1.D73"
					( objectStatus "ddr1_dqs_dp(12)" )
				)
				( pin "U5D1.L42"
					( objectStatus "ddr1_dqs_dp(13)" )
				)
				( pin "U5D1.C34"
					( objectStatus "ddr1_dqs_dp(14)" )
				)
				( pin "U5D1.C28"
					( objectStatus "ddr1_dqs_dp(15)" )
				)
				( pin "U5D1.V27"
					( objectStatus "ddr1_dqs_dp(16)" )
				)
				( pin "U5D1.J68"
					( objectStatus "ddr1_dqs_dp(17)" )
				)
				( pin "U5D1.J70"
					( objectStatus "ddr1_ecc(0)" )
				)
				( pin "U5D1.H69"
					( objectStatus "ddr1_ecc(1)" )
				)
				( pin "U5D1.J66"
					( objectStatus "ddr1_ecc(2)" )
				)
				( pin "U5D1.L66"
					( objectStatus "ddr1_ecc(3)" )
				)
				( pin "U5D1.L70"
					( objectStatus "ddr1_ecc(4)" )
				)
				( pin "U5D1.M69"
					( objectStatus "ddr1_ecc(5)" )
				)
				( pin "U5D1.H67"
					( objectStatus "ddr1_ecc(6)" )
				)
				( pin "U5D1.M67"
					( objectStatus "ddr1_ecc(7)" )
				)
				( pin "U5D1.J52"
					( objectStatus "ddr1_ma(0)" )
				)
				( pin "U5D1.J58"
					( objectStatus "ddr1_ma(1)" )
				)
				( pin "U5D1.K57"
					( objectStatus "ddr1_ma(2)" )
				)
				( pin "U5D1.N58"
					( objectStatus "ddr1_ma(3)" )
				)
				( pin "U5D1.M59"
					( objectStatus "ddr1_ma(4)" )
				)
				( pin "U5D1.R58"
					( objectStatus "ddr1_ma(5)" )
				)
				( pin "U5D1.T59"
					( objectStatus "ddr1_ma(6)" )
				)
				( pin "U5D1.V61"
					( objectStatus "ddr1_ma(7)" )
				)
				( pin "U5D1.W60"
					( objectStatus "ddr1_ma(8)" )
				)
				( pin "U5D1.K59"
					( objectStatus "ddr1_ma(9)" )
				)
				( pin "U5D1.M55"
					( objectStatus "ddr1_ma(10)" )
				)
				( pin "U5D1.R60"
					( objectStatus "ddr1_ma(11)" )
				)
				( pin "U5D1.T61"
					( objectStatus "ddr1_ma(12)" )
				)
				( pin "U5D1.M51"
					( objectStatus "ddr1_ma(13)" )
				)
				( pin "U5D1.T51"
					( objectStatus "ddr1_ma(14)" )
				)
				( pin "U5D1.N52"
					( objectStatus "ddr1_ma(15)" )
				)
				( pin "U5D1.R52"
					( objectStatus "ddr1_ma(16)" )
				)
				( pin "U5D1.N48"
					( objectStatus "ddr1_ma(17)" )
				)
				( pin "U5D1.N50"
					( objectStatus "ddr1_odt(0)" )
				)
				( pin "U5D1.R48"
					( objectStatus "ddr1_odt(1)" )
				)
				( pin "U5D1.M49"
					( objectStatus "ddr1_odt(2)" )
				)
				( pin "U5D1.T47"
					( objectStatus "ddr1_odt(3)" )
				)
				( pin "U5D1.K53"
					( objectStatus "ddr1_par" )
				)
			)
			( gate "U5D1"
				( objectStatus "@baseboard_fab2_lib.baseboard_fab2(sch_1):page25_i172" )
				( pin "U5D1.AB61"
					( objectStatus "ddr2_act_n" )
				)
				( pin "U5D1.AD61"
					( objectStatus "ddr2_alert_n" )
				)
				( pin "U5D1.W52"
					( objectStatus "ddr2_ba(0)" )
				)
				( pin "U5D1.AE56"
					( objectStatus "ddr2_ba(1)" )
				)
				( pin "U5D1.AA60"
					( objectStatus "ddr2_bg(0)" )
				)
				( pin "U5D1.AE62"
					( objectStatus "ddr2_bg(1)" )
				)
				( pin "U5D1.AB45"
					( objectStatus "ddr2_cid(2)" )
				)
				( pin "U5D1.AA62"
					( objectStatus "ddr2_cke(0)" )
				)
				( pin "U5D1.AD63"
					( objectStatus "ddr2_cke(1)" )
				)
				( pin "U5D1.V63"
					( objectStatus "ddr2_cke(2)" )
				)
				( pin "U5D1.AB63"
					( objectStatus "ddr2_cke(3)" )
				)
				( pin "U5D1.AA54"
					( objectStatus "ddr2_clk_dn(0)" )
				)
				( pin "U5D1.W54"
					( objectStatus "ddr2_clk_dn(1)" )
				)
				( pin "U5D1.AA56"
					( objectStatus "ddr2_clk_dn(2)" )
				)
				( pin "U5D1.W56"
					( objectStatus "ddr2_clk_dn(3)" )
				)
				( pin "U5D1.AB55"
					( objectStatus "ddr2_clk_dp(0)" )
				)
				( pin "U5D1.V55"
					( objectStatus "ddr2_clk_dp(1)" )
				)
				( pin "U5D1.AB57"
					( objectStatus "ddr2_clk_dp(2)" )
				)
				( pin "U5D1.V57"
					( objectStatus "ddr2_clk_dp(3)" )
				)
				( pin "U5D1.V51"
					( objectStatus "ddr2_cs_n(0)" )
				)
				( pin "U5D1.AB49"
					( objectStatus "ddr2_cs_n(1)" )
				)
				( pin "U5D1.W46"
					( objectStatus "ddr2_cs_n(2)" )
				)
				( pin "U5D1.AA46"
					( objectStatus "ddr2_cs_n(3)" )
				)
				( pin "U5D1.AB51"
					( objectStatus "ddr2_cs_n(4)" )
				)
				( pin "U5D1.W48"
					( objectStatus "ddr2_cs_n(5)" )
				)
				( pin "U5D1.T45"
					( objectStatus "ddr2_cs_n(6)" )
				)
				( pin "U5D1.V45"
					( objectStatus "ddr2_cs_n(7)" )
				)
				( pin "U5D1.AR76"
					( objectStatus "ddr2_dq(0)" )
				)
				( pin "U5D1.AN74"
					( objectStatus "ddr2_dq(1)" )
				)
				( pin "U5D1.AK77"
					( objectStatus "ddr2_dq(2)" )
				)
				( pin "U5D1.AJ76"
					( objectStatus "ddr2_dq(3)" )
				)
				( pin "U5D1.AT75"
					( objectStatus "ddr2_dq(4)" )
				)
				( pin "U5D1.AR74"
					( objectStatus "ddr2_dq(5)" )
				)
				( pin "U5D1.AM77"
					( objectStatus "ddr2_dq(6)" )
				)
				( pin "U5D1.AK75"
					( objectStatus "ddr2_dq(7)" )
				)
				( pin "U5D1.AE76"
					( objectStatus "ddr2_dq(8)" )
				)
				( pin "U5D1.AC74"
					( objectStatus "ddr2_dq(9)" )
				)
				( pin "U5D1.Y77"
					( objectStatus "ddr2_dq(10)" )
				)
				( pin "U5D1.W76"
					( objectStatus "ddr2_dq(11)" )
				)
				( pin "U5D1.AF75"
					( objectStatus "ddr2_dq(12)" )
				)
				( pin "U5D1.AE74"
					( objectStatus "ddr2_dq(13)" )
				)
				( pin "U5D1.AB77"
					( objectStatus "ddr2_dq(14)" )
				)
				( pin "U5D1.Y75"
					( objectStatus "ddr2_dq(15)" )
				)
				( pin "U5D1.W72"
					( objectStatus "ddr2_dq(16)" )
				)
				( pin "U5D1.AA70"
					( objectStatus "ddr2_dq(17)" )
				)
				( pin "U5D1.R70"
					( objectStatus "ddr2_dq(18)" )
				)
				( pin "U5D1.T69"
					( objectStatus "ddr2_dq(19)" )
				)
				( pin "U5D1.AA72"
					( objectStatus "ddr2_dq(20)" )
				)
				( pin "U5D1.AB71"
					( objectStatus "ddr2_dq(21)" )
				)
				( pin "U5D1.T71"
					( objectStatus "ddr2_dq(22)" )
				)
				( pin "U5D1.V69"
					( objectStatus "ddr2_dq(23)" )
				)
				( pin "U5D1.AM67"
					( objectStatus "ddr2_dq(24)" )
				)
				( pin "U5D1.AT67"
					( objectStatus "ddr2_dq(25)" )
				)
				( pin "U5D1.AN64"
					( objectStatus "ddr2_dq(26)" )
				)
				( pin "U5D1.AR64"
					( objectStatus "ddr2_dq(27)" )
				)
				( pin "U5D1.AN68"
					( objectStatus "ddr2_dq(28)" )
				)
				( pin "U5D1.AR68"
					( objectStatus "ddr2_dq(29)" )
				)
				( pin "U5D1.AM65"
					( objectStatus "ddr2_dq(30)" )
				)
				( pin "U5D1.AT65"
					( objectStatus "ddr2_dq(31)" )
				)
				( pin "U5D1.U40"
					( objectStatus "ddr2_dq(32)" )
				)
				( pin "U5D1.AA40"
					( objectStatus "ddr2_dq(33)" )
				)
				( pin "U5D1.V37"
					( objectStatus "ddr2_dq(34)" )
				)
				( pin "U5D1.Y37"
					( objectStatus "ddr2_dq(35)" )
				)
				( pin "U5D1.V41"
					( objectStatus "ddr2_dq(36)" )
				)
				( pin "U5D1.Y41"
					( objectStatus "ddr2_dq(37)" )
				)
				( pin "U5D1.U38"
					( objectStatus "ddr2_dq(38)" )
				)
				( pin "U5D1.AA38"
					( objectStatus "ddr2_dq(39)" )
				)
				( pin "U5D1.U34"
					( objectStatus "ddr2_dq(40)" )
				)
				( pin "U5D1.AA34"
					( objectStatus "ddr2_dq(41)" )
				)
				( pin "U5D1.V31"
					( objectStatus "ddr2_dq(42)" )
				)
				( pin "U5D1.Y31"
					( objectStatus "ddr2_dq(43)" )
				)
				( pin "U5D1.V35"
					( objectStatus "ddr2_dq(44)" )
				)
				( pin "U5D1.Y35"
					( objectStatus "ddr2_dq(45)" )
				)
				( pin "U5D1.U32"
					( objectStatus "ddr2_dq(46)" )
				)
				( pin "U5D1.AA32"
					( objectStatus "ddr2_dq(47)" )
				)
				( pin "U5D1.AD31"
					( objectStatus "ddr2_dq(48)" )
				)
				( pin "U5D1.AH31"
					( objectStatus "ddr2_dq(49)" )
				)
				( pin "U5D1.AE28"
					( objectStatus "ddr2_dq(50)" )
				)
				( pin "U5D1.AG28"
					( objectStatus "ddr2_dq(51)" )
				)
				( pin "U5D1.AE32"
					( objectStatus "ddr2_dq(52)" )
				)
				( pin "U5D1.AG32"
					( objectStatus "ddr2_dq(53)" )
				)
				( pin "U5D1.AD29"
					( objectStatus "ddr2_dq(54)" )
				)
				( pin "U5D1.AH29"
					( objectStatus "ddr2_dq(55)" )
				)
				( pin "U5D1.AD25"
					( objectStatus "ddr2_dq(56)" )
				)
				( pin "U5D1.AH25"
					( objectStatus "ddr2_dq(57)" )
				)
				( pin "U5D1.AE22"
					( objectStatus "ddr2_dq(58)" )
				)
				( pin "U5D1.AG22"
					( objectStatus "ddr2_dq(59)" )
				)
				( pin "U5D1.AE26"
					( objectStatus "ddr2_dq(60)" )
				)
				( pin "U5D1.AG26"
					( objectStatus "ddr2_dq(61)" )
				)
				( pin "U5D1.AD23"
					( objectStatus "ddr2_dq(62)" )
				)
				( pin "U5D1.AH23"
					( objectStatus "ddr2_dq(63)" )
				)
				( pin "U5D1.AL74"
					( objectStatus "ddr2_dqs_dn(0)" )
				)
				( pin "U5D1.AA74"
					( objectStatus "ddr2_dqs_dn(1)" )
				)
				( pin "U5D1.Y69"
					( objectStatus "ddr2_dqs_dn(2)" )
				)
				( pin "U5D1.AU66"
					( objectStatus "ddr2_dqs_dn(3)" )
				)
				( pin "U5D1.AB39"
					( objectStatus "ddr2_dqs_dn(4)" )
				)
				( pin "U5D1.AB33"
					( objectStatus "ddr2_dqs_dn(5)" )
				)
				( pin "U5D1.AJ30"
					( objectStatus "ddr2_dqs_dn(6)" )
				)
				( pin "U5D1.AJ24"
					( objectStatus "ddr2_dqs_dn(7)" )
				)
				( pin "U5D1.BB71"
					( objectStatus "ddr2_dqs_dn(8)" )
				)
				( pin "U5D1.AP77"
					( objectStatus "ddr2_dqs_dn(9)" )
				)
				( pin "U5D1.AD77"
					( objectStatus "ddr2_dqs_dn(10)" )
				)
				( pin "U5D1.U72"
					( objectStatus "ddr2_dqs_dn(11)" )
				)
				( pin "U5D1.AL66"
					( objectStatus "ddr2_dqs_dn(12)" )
				)
				( pin "U5D1.T39"
					( objectStatus "ddr2_dqs_dn(13)" )
				)
				( pin "U5D1.T33"
					( objectStatus "ddr2_dqs_dn(14)" )
				)
				( pin "U5D1.AC30"
					( objectStatus "ddr2_dqs_dn(15)" )
				)
				( pin "U5D1.AC24"
					( objectStatus "ddr2_dqs_dn(16)" )
				)
				( pin "U5D1.AT71"
					( objectStatus "ddr2_dqs_dn(17)" )
				)
				( pin "U5D1.AM75"
					( objectStatus "ddr2_dqs_dp(0)" )
				)
				( pin "U5D1.AB75"
					( objectStatus "ddr2_dqs_dp(1)" )
				)
				( pin "U5D1.W70"
					( objectStatus "ddr2_dqs_dp(2)" )
				)
				( pin "U5D1.AR66"
					( objectStatus "ddr2_dqs_dp(3)" )
				)
				( pin "U5D1.Y39"
					( objectStatus "ddr2_dqs_dp(4)" )
				)
				( pin "U5D1.Y33"
					( objectStatus "ddr2_dqs_dp(5)" )
				)
				( pin "U5D1.AG30"
					( objectStatus "ddr2_dqs_dp(6)" )
				)
				( pin "U5D1.AG24"
					( objectStatus "ddr2_dqs_dp(7)" )
				)
				( pin "U5D1.AY71"
					( objectStatus "ddr2_dqs_dp(8)" )
				)
				( pin "U5D1.AN76"
					( objectStatus "ddr2_dqs_dp(9)" )
				)
				( pin "U5D1.AC76"
					( objectStatus "ddr2_dqs_dp(10)" )
				)
				( pin "U5D1.V71"
					( objectStatus "ddr2_dqs_dp(11)" )
				)
				( pin "U5D1.AN66"
					( objectStatus "ddr2_dqs_dp(12)" )
				)
				( pin "U5D1.V39"
					( objectStatus "ddr2_dqs_dp(13)" )
				)
				( pin "U5D1.V33"
					( objectStatus "ddr2_dqs_dp(14)" )
				)
				( pin "U5D1.AE30"
					( objectStatus "ddr2_dqs_dp(15)" )
				)
				( pin "U5D1.AE24"
					( objectStatus "ddr2_dqs_dp(16)" )
				)
				( pin "U5D1.AV71"
					( objectStatus "ddr2_dqs_dp(17)" )
				)
				( pin "U5D1.AU72"
					( objectStatus "ddr2_ecc(0)" )
				)
				( pin "U5D1.BA72"
					( objectStatus "ddr2_ecc(1)" )
				)
				( pin "U5D1.AV69"
					( objectStatus "ddr2_ecc(2)" )
				)
				( pin "U5D1.AY69"
					( objectStatus "ddr2_ecc(3)" )
				)
				( pin "U5D1.AV73"
					( objectStatus "ddr2_ecc(4)" )
				)
				( pin "U5D1.AY73"
					( objectStatus "ddr2_ecc(5)" )
				)
				( pin "U5D1.AU70"
					( objectStatus "ddr2_ecc(6)" )
				)
				( pin "U5D1.BA70"
					( objectStatus "ddr2_ecc(7)" )
				)
				( pin "U5D1.AB53"
					( objectStatus "ddr2_ma(0)" )
				)
				( pin "U5D1.AE58"
					( objectStatus "ddr2_ma(1)" )
				)
				( pin "U5D1.AD57"
					( objectStatus "ddr2_ma(2)" )
				)
				( pin "U5D1.W58"
					( objectStatus "ddr2_ma(3)" )
				)
				( pin "U5D1.AA58"
					( objectStatus "ddr2_ma(4)" )
				)
				( pin "U5D1.V59"
					( objectStatus "ddr2_ma(5)" )
				)
				( pin "U5D1.AB59"
					( objectStatus "ddr2_ma(6)" )
				)
				( pin "U5D1.AE60"
					( objectStatus "ddr2_ma(7)" )
				)
				( pin "U5D1.AD59"
					( objectStatus "ddr2_ma(8)" )
				)
				( pin "U5D1.AG58"
					( objectStatus "ddr2_ma(9)" )
				)
				( pin "U5D1.AD55"
					( objectStatus "ddr2_ma(10)" )
				)
				( pin "U5D1.AG60"
					( objectStatus "ddr2_ma(11)" )
				)
				( pin "U5D1.AG62"
					( objectStatus "ddr2_ma(12)" )
				)
				( pin "U5D1.AD53"
					( objectStatus "ddr2_ma(13)" )
				)
				( pin "U5D1.W50"
					( objectStatus "ddr2_ma(14)" )
				)
				( pin "U5D1.AE54"
					( objectStatus "ddr2_ma(15)" )
				)
				( pin "U5D1.AA52"
					( objectStatus "ddr2_ma(16)" )
				)
				( pin "U5D1.AC46"
					( objectStatus "ddr2_ma(17)" )
				)
				( pin "U5D1.AA50"
					( objectStatus "ddr2_odt(0)" )
				)
				( pin "U5D1.AA48"
					( objectStatus "ddr2_odt(1)" )
				)
				( pin "U5D1.V49"
					( objectStatus "ddr2_odt(2)" )
				)
				( pin "U5D1.AB47"
					( objectStatus "ddr2_odt(3)" )
				)
				( pin "U5D1.V53"
					( objectStatus "ddr2_par" )
				)
			)
			( gate "U5D1"
				( objectStatus "@baseboard_fab2_lib.baseboard_fab2(sch_1):page26_i172" )
				( pin "U5D1.DW60"
					( objectStatus "ddr3_act_n" )
				)
				( pin "U5D1.ED63"
					( objectStatus "ddr3_alert_n" )
				)
				( pin "U5D1.EE52"
					( objectStatus "ddr3_ba(0)" )
				)
				( pin "U5D1.EA54"
					( objectStatus "ddr3_ba(1)" )
				)
				( pin "U5D1.ED61"
					( objectStatus "ddr3_bg(0)" )
				)
				( pin "U5D1.DW62"
					( objectStatus "ddr3_bg(1)" )
				)
				( pin "U5D1.DV47"
					( objectStatus "ddr3_cid(2)" )
				)
				( pin "U5D1.EE62"
					( objectStatus "ddr3_cke(0)" )
				)
				( pin "U5D1.EF63"
					( objectStatus "ddr3_cke(1)" )
				)
				( pin "U5D1.EA62"
					( objectStatus "ddr3_cke(2)" )
				)
				( pin "U5D1.EB63"
					( objectStatus "ddr3_cke(3)" )
				)
				( pin "U5D1.ED55"
					( objectStatus "ddr3_clk_dn(0)" )
				)
				( pin "U5D1.EF55"
					( objectStatus "ddr3_clk_dn(1)" )
				)
				( pin "U5D1.DW56"
					( objectStatus "ddr3_clk_dn(2)" )
				)
				( pin "U5D1.EF57"
					( objectStatus "ddr3_clk_dn(3)" )
				)
				( pin "U5D1.EB55"
					( objectStatus "ddr3_clk_dp(0)" )
				)
				( pin "U5D1.EE54"
					( objectStatus "ddr3_clk_dp(1)" )
				)
				( pin "U5D1.EA56"
					( objectStatus "ddr3_clk_dp(2)" )
				)
				( pin "U5D1.EE56"
					( objectStatus "ddr3_clk_dp(3)" )
				)
				( pin "U5D1.EF51"
					( objectStatus "ddr3_cs_n(0)" )
				)
				( pin "U5D1.ED49"
					( objectStatus "ddr3_cs_n(1)" )
				)
				( pin "U5D1.ED47"
					( objectStatus "ddr3_cs_n(2)" )
				)
				( pin "U5D1.EB47"
					( objectStatus "ddr3_cs_n(3)" )
				)
				( pin "U5D1.EB51"
					( objectStatus "ddr3_cs_n(4)" )
				)
				( pin "U5D1.EB49"
					( objectStatus "ddr3_cs_n(5)" )
				)
				( pin "U5D1.DV45"
					( objectStatus "ddr3_cs_n(6)" )
				)
				( pin "U5D1.EB45"
					( objectStatus "ddr3_cs_n(7)" )
				)
				( pin "U5D1.CN84"
					( objectStatus "ddr3_dq(0)" )
				)
				( pin "U5D1.CN86"
					( objectStatus "ddr3_dq(1)" )
				)
				( pin "U5D1.DA86"
					( objectStatus "ddr3_dq(2)" )
				)
				( pin "U5D1.DA84"
					( objectStatus "ddr3_dq(3)" )
				)
				( pin "U5D1.CL84"
					( objectStatus "ddr3_dq(4)" )
				)
				( pin "U5D1.CL86"
					( objectStatus "ddr3_dq(5)" )
				)
				( pin "U5D1.CW86"
					( objectStatus "ddr3_dq(6)" )
				)
				( pin "U5D1.CW84"
					( objectStatus "ddr3_dq(7)" )
				)
				( pin "U5D1.DG84"
					( objectStatus "ddr3_dq(8)" )
				)
				( pin "U5D1.DH85"
					( objectStatus "ddr3_dq(9)" )
				)
				( pin "U5D1.DV83"
					( objectStatus "ddr3_dq(10)" )
				)
				( pin "U5D1.DY83"
					( objectStatus "ddr3_dq(11)" )
				)
				( pin "U5D1.DD85"
					( objectStatus "ddr3_dq(12)" )
				)
				( pin "U5D1.DE84"
					( objectStatus "ddr3_dq(13)" )
				)
				( pin "U5D1.DR84"
					( objectStatus "ddr3_dq(14)" )
				)
				( pin "U5D1.DV85"
					( objectStatus "ddr3_dq(15)" )
				)
				( pin "U5D1.DM79"
					( objectStatus "ddr3_dq(16)" )
				)
				( pin "U5D1.DK81"
					( objectStatus "ddr3_dq(17)" )
				)
				( pin "U5D1.DT81"
					( objectStatus "ddr3_dq(18)" )
				)
				( pin "U5D1.DR82"
					( objectStatus "ddr3_dq(19)" )
				)
				( pin "U5D1.DK79"
					( objectStatus "ddr3_dq(20)" )
				)
				( pin "U5D1.DJ80"
					( objectStatus "ddr3_dq(21)" )
				)
				( pin "U5D1.DR80"
					( objectStatus "ddr3_dq(22)" )
				)
				( pin "U5D1.DN82"
					( objectStatus "ddr3_dq(23)" )
				)
				( pin "U5D1.DN76"
					( objectStatus "ddr3_dq(24)" )
				)
				( pin "U5D1.DU76"
					( objectStatus "ddr3_dq(25)" )
				)
				( pin "U5D1.DP73"
					( objectStatus "ddr3_dq(26)" )
				)
				( pin "U5D1.DT73"
					( objectStatus "ddr3_dq(27)" )
				)
				( pin "U5D1.DP77"
					( objectStatus "ddr3_dq(28)" )
				)
				( pin "U5D1.DT77"
					( objectStatus "ddr3_dq(29)" )
				)
				( pin "U5D1.DN74"
					( objectStatus "ddr3_dq(30)" )
				)
				( pin "U5D1.DU74"
					( objectStatus "ddr3_dq(31)" )
				)
				( pin "U5D1.EC40"
					( objectStatus "ddr3_dq(32)" )
				)
				( pin "U5D1.ED39"
					( objectStatus "ddr3_dq(33)" )
				)
				( pin "U5D1.EA36"
					( objectStatus "ddr3_dq(34)" )
				)
				( pin "U5D1.EC36"
					( objectStatus "ddr3_dq(35)" )
				)
				( pin "U5D1.DY39"
					( objectStatus "ddr3_dq(36)" )
				)
				( pin "U5D1.EA40"
					( objectStatus "ddr3_dq(37)" )
				)
				( pin "U5D1.DY37"
					( objectStatus "ddr3_dq(38)" )
				)
				( pin "U5D1.ED37"
					( objectStatus "ddr3_dq(39)" )
				)
				( pin "U5D1.DN36"
					( objectStatus "ddr3_dq(40)" )
				)
				( pin "U5D1.DU36"
					( objectStatus "ddr3_dq(41)" )
				)
				( pin "U5D1.DP33"
					( objectStatus "ddr3_dq(42)" )
				)
				( pin "U5D1.DT33"
					( objectStatus "ddr3_dq(43)" )
				)
				( pin "U5D1.DP37"
					( objectStatus "ddr3_dq(44)" )
				)
				( pin "U5D1.DT37"
					( objectStatus "ddr3_dq(45)" )
				)
				( pin "U5D1.DN34"
					( objectStatus "ddr3_dq(46)" )
				)
				( pin "U5D1.DU34"
					( objectStatus "ddr3_dq(47)" )
				)
				( pin "U5D1.DN30"
					( objectStatus "ddr3_dq(48)" )
				)
				( pin "U5D1.DU30"
					( objectStatus "ddr3_dq(49)" )
				)
				( pin "U5D1.DP27"
					( objectStatus "ddr3_dq(50)" )
				)
				( pin "U5D1.DT27"
					( objectStatus "ddr3_dq(51)" )
				)
				( pin "U5D1.DP31"
					( objectStatus "ddr3_dq(52)" )
				)
				( pin "U5D1.DT31"
					( objectStatus "ddr3_dq(53)" )
				)
				( pin "U5D1.DN28"
					( objectStatus "ddr3_dq(54)" )
				)
				( pin "U5D1.DU28"
					( objectStatus "ddr3_dq(55)" )
				)
				( pin "U5D1.DN24"
					( objectStatus "ddr3_dq(56)" )
				)
				( pin "U5D1.DU24"
					( objectStatus "ddr3_dq(57)" )
				)
				( pin "U5D1.DY21"
					( objectStatus "ddr3_dq(58)" )
				)
				( pin "U5D1.EB21"
					( objectStatus "ddr3_dq(59)" )
				)
				( pin "U5D1.DP25"
					( objectStatus "ddr3_dq(60)" )
				)
				( pin "U5D1.DT25"
					( objectStatus "ddr3_dq(61)" )
				)
				( pin "U5D1.EC22"
					( objectStatus "ddr3_dq(62)" )
				)
				( pin "U5D1.DW22"
					( objectStatus "ddr3_dq(63)" )
				)
				( pin "U5D1.CU84"
					( objectStatus "ddr3_dqs_dn(0)" )
				)
				( pin "U5D1.DN84"
					( objectStatus "ddr3_dqs_dn(1)" )
				)
				( pin "U5D1.DL82"
					( objectStatus "ddr3_dqs_dn(2)" )
				)
				( pin "U5D1.DV75"
					( objectStatus "ddr3_dqs_dn(3)" )
				)
				( pin "U5D1.EE38"
					( objectStatus "ddr3_dqs_dn(4)" )
				)
				( pin "U5D1.DV35"
					( objectStatus "ddr3_dqs_dn(5)" )
				)
				( pin "U5D1.DV29"
					( objectStatus "ddr3_dqs_dn(6)" )
				)
				( pin "U5D1.DV23"
					( objectStatus "ddr3_dqs_dn(7)" )
				)
				( pin "U5D1.DF67"
					( objectStatus "ddr3_dqs_dn(8)" )
				)
				( pin "U5D1.CR84"
					( objectStatus "ddr3_dqs_dn(9)" )
				)
				( pin "U5D1.DM85"
					( objectStatus "ddr3_dqs_dn(10)" )
				)
				( pin "U5D1.DN80"
					( objectStatus "ddr3_dqs_dn(11)" )
				)
				( pin "U5D1.DP75"
					( objectStatus "ddr3_dqs_dn(12)" )
				)
				( pin "U5D1.EA38"
					( objectStatus "ddr3_dqs_dn(13)" )
				)
				( pin "U5D1.DP35"
					( objectStatus "ddr3_dqs_dn(14)" )
				)
				( pin "U5D1.DM29"
					( objectStatus "ddr3_dqs_dn(15)" )
				)
				( pin "U5D1.DM23"
					( objectStatus "ddr3_dqs_dn(16)" )
				)
				( pin "U5D1.DB67"
					( objectStatus "ddr3_dqs_dn(17)" )
				)
				( pin "U5D1.CV85"
					( objectStatus "ddr3_dqs_dp(0)" )
				)
				( pin "U5D1.DP85"
					( objectStatus "ddr3_dqs_dp(1)" )
				)
				( pin "U5D1.DM81"
					( objectStatus "ddr3_dqs_dp(2)" )
				)
				( pin "U5D1.DT75"
					( objectStatus "ddr3_dqs_dp(3)" )
				)
				( pin "U5D1.EC38"
					( objectStatus "ddr3_dqs_dp(4)" )
				)
				( pin "U5D1.DT35"
					( objectStatus "ddr3_dqs_dp(5)" )
				)
				( pin "U5D1.DT29"
					( objectStatus "ddr3_dqs_dp(6)" )
				)
				( pin "U5D1.DT23"
					( objectStatus "ddr3_dqs_dp(7)" )
				)
				( pin "U5D1.DD67"
					( objectStatus "ddr3_dqs_dp(8)" )
				)
				( pin "U5D1.CP85"
					( objectStatus "ddr3_dqs_dp(9)" )
				)
				( pin "U5D1.DL84"
					( objectStatus "ddr3_dqs_dp(10)" )
				)
				( pin "U5D1.DP79"
					( objectStatus "ddr3_dqs_dp(11)" )
				)
				( pin "U5D1.DM75"
					( objectStatus "ddr3_dqs_dp(12)" )
				)
				( pin "U5D1.DW38"
					( objectStatus "ddr3_dqs_dp(13)" )
				)
				( pin "U5D1.DM35"
					( objectStatus "ddr3_dqs_dp(14)" )
				)
				( pin "U5D1.DP29"
					( objectStatus "ddr3_dqs_dp(15)" )
				)
				( pin "U5D1.DP23"
					( objectStatus "ddr3_dqs_dp(16)" )
				)
				( pin "U5D1.CY67"
					( objectStatus "ddr3_dqs_dp(17)" )
				)
				( pin "U5D1.DA68"
					( objectStatus "ddr3_ecc(0)" )
				)
				( pin "U5D1.DE68"
					( objectStatus "ddr3_ecc(1)" )
				)
				( pin "U5D1.DB65"
					( objectStatus "ddr3_ecc(2)" )
				)
				( pin "U5D1.DD65"
					( objectStatus "ddr3_ecc(3)" )
				)
				( pin "U5D1.DB69"
					( objectStatus "ddr3_ecc(4)" )
				)
				( pin "U5D1.DD69"
					( objectStatus "ddr3_ecc(5)" )
				)
				( pin "U5D1.DA66"
					( objectStatus "ddr3_ecc(6)" )
				)
				( pin "U5D1.DE66"
					( objectStatus "ddr3_ecc(7)" )
				)
				( pin "U5D1.EB53"
					( objectStatus "ddr3_ma(0)" )
				)
				( pin "U5D1.ED57"
					( objectStatus "ddr3_ma(1)" )
				)
				( pin "U5D1.EE58"
					( objectStatus "ddr3_ma(2)" )
				)
				( pin "U5D1.EB57"
					( objectStatus "ddr3_ma(3)" )
				)
				( pin "U5D1.ED59"
					( objectStatus "ddr3_ma(4)" )
				)
				( pin "U5D1.EA58"
					( objectStatus "ddr3_ma(5)" )
				)
				( pin "U5D1.EE60"
					( objectStatus "ddr3_ma(6)" )
				)
				( pin "U5D1.EA60"
					( objectStatus "ddr3_ma(7)" )
				)
				( pin "U5D1.EB59"
					( objectStatus "ddr3_ma(8)" )
				)
				( pin "U5D1.EF61"
					( objectStatus "ddr3_ma(9)" )
				)
				( pin "U5D1.DW54"
					( objectStatus "ddr3_ma(10)" )
				)
				( pin "U5D1.EB61"
					( objectStatus "ddr3_ma(11)" )
				)
				( pin "U5D1.DT63"
					( objectStatus "ddr3_ma(12)" )
				)
				( pin "U5D1.DW48"
					( objectStatus "ddr3_ma(13)" )
				)
				( pin "U5D1.ED51"
					( objectStatus "ddr3_ma(14)" )
				)
				( pin "U5D1.DV49"
					( objectStatus "ddr3_ma(15)" )
				)
				( pin "U5D1.EA52"
					( objectStatus "ddr3_ma(16)" )
				)
				( pin "U5D1.EA46"
					( objectStatus "ddr3_ma(17)" )
				)
				( pin "U5D1.EE50"
					( objectStatus "ddr3_odt(0)" )
				)
				( pin "U5D1.EE48"
					( objectStatus "ddr3_odt(1)" )
				)
				( pin "U5D1.EA50"
					( objectStatus "ddr3_odt(2)" )
				)
				( pin "U5D1.EA48"
					( objectStatus "ddr3_odt(3)" )
				)
				( pin "U5D1.ED53"
					( objectStatus "ddr3_par" )
				)
			)
			( gate "U5D1"
				( objectStatus "@baseboard_fab2_lib.baseboard_fab2(sch_1):page27_i172" )
				( pin "U5D1.DR62"
					( objectStatus "ddr4_act_n" )
				)
				( pin "U5D1.DT61"
					( objectStatus "ddr4_alert_n" )
				)
				( pin "U5D1.DM53"
					( objectStatus "ddr4_ba(0)" )
				)
				( pin "U5D1.DV55"
					( objectStatus "ddr4_ba(1)" )
				)
				( pin "U5D1.DJ62"
					( objectStatus "ddr4_bg(0)" )
				)
				( pin "U5D1.DM61"
					( objectStatus "ddr4_bg(1)" )
				)
				( pin "U5D1.DT47"
					( objectStatus "ddr4_cid(2)" )
				)
				( pin "U5D1.DM63"
					( objectStatus "ddr4_cke(0)" )
				)
				( pin "U5D1.DN64"
					( objectStatus "ddr4_cke(1)" )
				)
				( pin "U5D1.DL64"
					( objectStatus "ddr4_cke(2)" )
				)
				( pin "U5D1.DR64"
					( objectStatus "ddr4_cke(3)" )
				)
				( pin "U5D1.DM55"
					( objectStatus "ddr4_clk_dn(0)" )
				)
				( pin "U5D1.DR54"
					( objectStatus "ddr4_clk_dn(1)" )
				)
				( pin "U5D1.DM57"
					( objectStatus "ddr4_clk_dn(2)" )
				)
				( pin "U5D1.DT57"
					( objectStatus "ddr4_clk_dn(3)" )
				)
				( pin "U5D1.DN54"
					( objectStatus "ddr4_clk_dp(0)" )
				)
				( pin "U5D1.DT53"
					( objectStatus "ddr4_clk_dp(1)" )
				)
				( pin "U5D1.DN56"
					( objectStatus "ddr4_clk_dp(2)" )
				)
				( pin "U5D1.DR56"
					( objectStatus "ddr4_clk_dp(3)" )
				)
				( pin "U5D1.DV51"
					( objectStatus "ddr4_cs_n(0)" )
				)
				( pin "U5D1.DN50"
					( objectStatus "ddr4_cs_n(1)" )
				)
				( pin "U5D1.DR46"
					( objectStatus "ddr4_cs_n(2)" )
				)
				( pin "U5D1.DK47"
					( objectStatus "ddr4_cs_n(3)" )
				)
				( pin "U5D1.DW50"
					( objectStatus "ddr4_cs_n(4)" )
				)
				( pin "U5D1.DM49"
					( objectStatus "ddr4_cs_n(5)" )
				)
				( pin "U5D1.DT45"
					( objectStatus "ddr4_cs_n(6)" )
				)
				( pin "U5D1.DN46"
					( objectStatus "ddr4_cs_n(7)" )
				)
				( pin "U5D1.CM79"
					( objectStatus "ddr4_dq(0)" )
				)
				( pin "U5D1.CK81"
					( objectStatus "ddr4_dq(1)" )
				)
				( pin "U5D1.CT81"
					( objectStatus "ddr4_dq(2)" )
				)
				( pin "U5D1.CR82"
					( objectStatus "ddr4_dq(3)" )
				)
				( pin "U5D1.CK79"
					( objectStatus "ddr4_dq(4)" )
				)
				( pin "U5D1.CJ80"
					( objectStatus "ddr4_dq(5)" )
				)
				( pin "U5D1.CR80"
					( objectStatus "ddr4_dq(6)" )
				)
				( pin "U5D1.CN82"
					( objectStatus "ddr4_dq(7)" )
				)
				( pin "U5D1.DB79"
					( objectStatus "ddr4_dq(8)" )
				)
				( pin "U5D1.CY81"
					( objectStatus "ddr4_dq(9)" )
				)
				( pin "U5D1.DE80"
					( objectStatus "ddr4_dq(10)" )
				)
				( pin "U5D1.DF81"
					( objectStatus "ddr4_dq(11)" )
				)
				( pin "U5D1.CY79"
					( objectStatus "ddr4_dq(12)" )
				)
				( pin "U5D1.CW80"
					( objectStatus "ddr4_dq(13)" )
				)
				( pin "U5D1.DC82"
					( objectStatus "ddr4_dq(14)" )
				)
				( pin "U5D1.DE82"
					( objectStatus "ddr4_dq(15)" )
				)
				( pin "U5D1.DW80"
					( objectStatus "ddr4_dq(16)" )
				)
				( pin "U5D1.EC80"
					( objectStatus "ddr4_dq(17)" )
				)
				( pin "U5D1.DY77"
					( objectStatus "ddr4_dq(18)" )
				)
				( pin "U5D1.EB77"
					( objectStatus "ddr4_dq(19)" )
				)
				( pin "U5D1.DY81"
					( objectStatus "ddr4_dq(20)" )
				)
				( pin "U5D1.EB81"
					( objectStatus "ddr4_dq(21)" )
				)
				( pin "U5D1.DW78"
					( objectStatus "ddr4_dq(22)" )
				)
				( pin "U5D1.EC78"
					( objectStatus "ddr4_dq(23)" )
				)
				( pin "U5D1.ED75"
					( objectStatus "ddr4_dq(24)" )
				)
				( pin "U5D1.EE74"
					( objectStatus "ddr4_dq(25)" )
				)
				( pin "U5D1.EB71"
					( objectStatus "ddr4_dq(26)" )
				)
				( pin "U5D1.ED71"
					( objectStatus "ddr4_dq(27)" )
				)
				( pin "U5D1.EA74"
					( objectStatus "ddr4_dq(28)" )
				)
				( pin "U5D1.EB75"
					( objectStatus "ddr4_dq(29)" )
				)
				( pin "U5D1.EA72"
					( objectStatus "ddr4_dq(30)" )
				)
				( pin "U5D1.EE72"
					( objectStatus "ddr4_dq(31)" )
				)
				( pin "U5D1.DU42"
					( objectStatus "ddr4_dq(32)" )
				)
				( pin "U5D1.DW42"
					( objectStatus "ddr4_dq(33)" )
				)
				( pin "U5D1.DP39"
					( objectStatus "ddr4_dq(34)" )
				)
				( pin "U5D1.DT39"
					( objectStatus "ddr4_dq(35)" )
				)
				( pin "U5D1.DL42"
					( objectStatus "ddr4_dq(36)" )
				)
				( pin "U5D1.DN42"
					( objectStatus "ddr4_dq(37)" )
				)
				( pin "U5D1.DN40"
					( objectStatus "ddr4_dq(38)" )
				)
				( pin "U5D1.DU40"
					( objectStatus "ddr4_dq(39)" )
				)
				( pin "U5D1.EC34"
					( objectStatus "ddr4_dq(40)" )
				)
				( pin "U5D1.ED33"
					( objectStatus "ddr4_dq(41)" )
				)
				( pin "U5D1.EA30"
					( objectStatus "ddr4_dq(42)" )
				)
				( pin "U5D1.EC30"
					( objectStatus "ddr4_dq(43)" )
				)
				( pin "U5D1.DY33"
					( objectStatus "ddr4_dq(44)" )
				)
				( pin "U5D1.EA34"
					( objectStatus "ddr4_dq(45)" )
				)
				( pin "U5D1.DY31"
					( objectStatus "ddr4_dq(46)" )
				)
				( pin "U5D1.ED31"
					( objectStatus "ddr4_dq(47)" )
				)
				( pin "U5D1.EC28"
					( objectStatus "ddr4_dq(48)" )
				)
				( pin "U5D1.ED27"
					( objectStatus "ddr4_dq(49)" )
				)
				( pin "U5D1.EA24"
					( objectStatus "ddr4_dq(50)" )
				)
				( pin "U5D1.EC24"
					( objectStatus "ddr4_dq(51)" )
				)
				( pin "U5D1.DY27"
					( objectStatus "ddr4_dq(52)" )
				)
				( pin "U5D1.EA28"
					( objectStatus "ddr4_dq(53)" )
				)
				( pin "U5D1.DY25"
					( objectStatus "ddr4_dq(54)" )
				)
				( pin "U5D1.ED25"
					( objectStatus "ddr4_dq(55)" )
				)
				( pin "U5D1.DF27"
					( objectStatus "ddr4_dq(56)" )
				)
				( pin "U5D1.DK27"
					( objectStatus "ddr4_dq(57)" )
				)
				( pin "U5D1.DD25"
					( objectStatus "ddr4_dq(58)" )
				)
				( pin "U5D1.DJ24"
					( objectStatus "ddr4_dq(59)" )
				)
				( pin "U5D1.DG28"
					( objectStatus "ddr4_dq(60)" )
				)
				( pin "U5D1.DJ28"
					( objectStatus "ddr4_dq(61)" )
				)
				( pin "U5D1.DF25"
					( objectStatus "ddr4_dq(62)" )
				)
				( pin "U5D1.DK25"
					( objectStatus "ddr4_dq(63)" )
				)
				( pin "U5D1.CL82"
					( objectStatus "ddr4_dqs_dn(0)" )
				)
				( pin "U5D1.DA82"
					( objectStatus "ddr4_dqs_dn(1)" )
				)
				( pin "U5D1.ED79"
					( objectStatus "ddr4_dqs_dn(2)" )
				)
				( pin "U5D1.EF73"
					( objectStatus "ddr4_dqs_dn(3)" )
				)
				( pin "U5D1.DV41"
					( objectStatus "ddr4_dqs_dn(4)" )
				)
				( pin "U5D1.EE32"
					( objectStatus "ddr4_dqs_dn(5)" )
				)
				( pin "U5D1.EE26"
					( objectStatus "ddr4_dqs_dn(6)" )
				)
				( pin "U5D1.DL26"
					( objectStatus "ddr4_dqs_dn(7)" )
				)
				( pin "U5D1.EB67"
					( objectStatus "ddr4_dqs_dn(8)" )
				)
				( pin "U5D1.CN80"
					( objectStatus "ddr4_dqs_dn(9)" )
				)
				( pin "U5D1.DC80"
					( objectStatus "ddr4_dqs_dn(10)" )
				)
				( pin "U5D1.DY79"
					( objectStatus "ddr4_dqs_dn(11)" )
				)
				( pin "U5D1.EB73"
					( objectStatus "ddr4_dqs_dn(12)" )
				)
				( pin "U5D1.DP41"
					( objectStatus "ddr4_dqs_dn(13)" )
				)
				( pin "U5D1.EA32"
					( objectStatus "ddr4_dqs_dn(14)" )
				)
				( pin "U5D1.EA26"
					( objectStatus "ddr4_dqs_dn(15)" )
				)
				( pin "U5D1.DG26"
					( objectStatus "ddr4_dqs_dn(16)" )
				)
				( pin "U5D1.DV67"
					( objectStatus "ddr4_dqs_dn(17)" )
				)
				( pin "U5D1.CM81"
					( objectStatus "ddr4_dqs_dp(0)" )
				)
				( pin "U5D1.DB81"
					( objectStatus "ddr4_dqs_dp(1)" )
				)
				( pin "U5D1.EB79"
					( objectStatus "ddr4_dqs_dp(2)" )
				)
				( pin "U5D1.ED73"
					( objectStatus "ddr4_dqs_dp(3)" )
				)
				( pin "U5D1.DT41"
					( objectStatus "ddr4_dqs_dp(4)" )
				)
				( pin "U5D1.EC32"
					( objectStatus "ddr4_dqs_dp(5)" )
				)
				( pin "U5D1.EC26"
					( objectStatus "ddr4_dqs_dp(6)" )
				)
				( pin "U5D1.DJ26"
					( objectStatus "ddr4_dqs_dp(7)" )
				)
				( pin "U5D1.DY67"
					( objectStatus "ddr4_dqs_dp(8)" )
				)
				( pin "U5D1.CP79"
					( objectStatus "ddr4_dqs_dp(9)" )
				)
				( pin "U5D1.DD79"
					( objectStatus "ddr4_dqs_dp(10)" )
				)
				( pin "U5D1.DV79"
					( objectStatus "ddr4_dqs_dp(11)" )
				)
				( pin "U5D1.DY73"
					( objectStatus "ddr4_dqs_dp(12)" )
				)
				( pin "U5D1.DM41"
					( objectStatus "ddr4_dqs_dp(13)" )
				)
				( pin "U5D1.DW32"
					( objectStatus "ddr4_dqs_dp(14)" )
				)
				( pin "U5D1.DW26"
					( objectStatus "ddr4_dqs_dp(15)" )
				)
				( pin "U5D1.DE26"
					( objectStatus "ddr4_dqs_dp(16)" )
				)
				( pin "U5D1.DT67"
					( objectStatus "ddr4_dqs_dp(17)" )
				)
				( pin "U5D1.DY69"
					( objectStatus "ddr4_ecc(0)" )
				)
				( pin "U5D1.EA68"
					( objectStatus "ddr4_ecc(1)" )
				)
				( pin "U5D1.DV65"
					( objectStatus "ddr4_ecc(2)" )
				)
				( pin "U5D1.DY65"
					( objectStatus "ddr4_ecc(3)" )
				)
				( pin "U5D1.DU68"
					( objectStatus "ddr4_ecc(4)" )
				)
				( pin "U5D1.DV69"
					( objectStatus "ddr4_ecc(5)" )
				)
				( pin "U5D1.DU66"
					( objectStatus "ddr4_ecc(6)" )
				)
				( pin "U5D1.EA66"
					( objectStatus "ddr4_ecc(7)" )
				)
				( pin "U5D1.DW52"
					( objectStatus "ddr4_ma(0)" )
				)
				( pin "U5D1.DW58"
					( objectStatus "ddr4_ma(1)" )
				)
				( pin "U5D1.DV57"
					( objectStatus "ddr4_ma(2)" )
				)
				( pin "U5D1.DR58"
					( objectStatus "ddr4_ma(3)" )
				)
				( pin "U5D1.DT59"
					( objectStatus "ddr4_ma(4)" )
				)
				( pin "U5D1.DN58"
					( objectStatus "ddr4_ma(5)" )
				)
				( pin "U5D1.DM59"
					( objectStatus "ddr4_ma(6)" )
				)
				( pin "U5D1.DK61"
					( objectStatus "ddr4_ma(7)" )
				)
				( pin "U5D1.DJ60"
					( objectStatus "ddr4_ma(8)" )
				)
				( pin "U5D1.DV59"
					( objectStatus "ddr4_ma(9)" )
				)
				( pin "U5D1.DT55"
					( objectStatus "ddr4_ma(10)" )
				)
				( pin "U5D1.DR60"
					( objectStatus "ddr4_ma(11)" )
				)
				( pin "U5D1.DN60"
					( objectStatus "ddr4_ma(12)" )
				)
				( pin "U5D1.DT51"
					( objectStatus "ddr4_ma(13)" )
				)
				( pin "U5D1.DM51"
					( objectStatus "ddr4_ma(14)" )
				)
				( pin "U5D1.DR52"
					( objectStatus "ddr4_ma(15)" )
				)
				( pin "U5D1.DN52"
					( objectStatus "ddr4_ma(16)" )
				)
				( pin "U5D1.DR48"
					( objectStatus "ddr4_ma(17)" )
				)
				( pin "U5D1.DR50"
					( objectStatus "ddr4_odt(0)" )
				)
				( pin "U5D1.DN48"
					( objectStatus "ddr4_odt(1)" )
				)
				( pin "U5D1.DT49"
					( objectStatus "ddr4_odt(2)" )
				)
				( pin "U5D1.DM47"
					( objectStatus "ddr4_odt(3)" )
				)
				( pin "U5D1.DV53"
					( objectStatus "ddr4_par" )
				)
			)
			( gate "U5D1"
				( objectStatus "@baseboard_fab2_lib.baseboard_fab2(sch_1):page28_i172" )
				( pin "U5D1.DC62"
					( objectStatus "ddr5_act_n" )
				)
				( pin "U5D1.DD61"
					( objectStatus "ddr5_alert_n" )
				)
				( pin "U5D1.DJ52"
					( objectStatus "ddr5_ba(0)" )
				)
				( pin "U5D1.DC56"
					( objectStatus "ddr5_ba(1)" )
				)
				( pin "U5D1.DA62"
					( objectStatus "ddr5_bg(0)" )
				)
				( pin "U5D1.DF61"
					( objectStatus "ddr5_bg(1)" )
				)
				( pin "U5D1.DF45"
					( objectStatus "ddr5_cid(2)" )
				)
				( pin "U5D1.DG62"
					( objectStatus "ddr5_cke(0)" )
				)
				( pin "U5D1.DD63"
					( objectStatus "ddr5_cke(1)" )
				)
				( pin "U5D1.DK63"
					( objectStatus "ddr5_cke(2)" )
				)
				( pin "U5D1.DF63"
					( objectStatus "ddr5_cke(3)" )
				)
				( pin "U5D1.DK55"
					( objectStatus "ddr5_clk_dn(0)" )
				)
				( pin "U5D1.DF55"
					( objectStatus "ddr5_clk_dn(1)" )
				)
				( pin "U5D1.DK57"
					( objectStatus "ddr5_clk_dn(2)" )
				)
				( pin "U5D1.DF57"
					( objectStatus "ddr5_clk_dn(3)" )
				)
				( pin "U5D1.DJ54"
					( objectStatus "ddr5_clk_dp(0)" )
				)
				( pin "U5D1.DG54"
					( objectStatus "ddr5_clk_dp(1)" )
				)
				( pin "U5D1.DJ56"
					( objectStatus "ddr5_clk_dp(2)" )
				)
				( pin "U5D1.DG56"
					( objectStatus "ddr5_clk_dp(3)" )
				)
				( pin "U5D1.DK51"
					( objectStatus "ddr5_cs_n(0)" )
				)
				( pin "U5D1.DF49"
					( objectStatus "ddr5_cs_n(1)" )
				)
				( pin "U5D1.DJ46"
					( objectStatus "ddr5_cs_n(2)" )
				)
				( pin "U5D1.DG46"
					( objectStatus "ddr5_cs_n(3)" )
				)
				( pin "U5D1.DF51"
					( objectStatus "ddr5_cs_n(4)" )
				)
				( pin "U5D1.DJ48"
					( objectStatus "ddr5_cs_n(5)" )
				)
				( pin "U5D1.DM45"
					( objectStatus "ddr5_cs_n(6)" )
				)
				( pin "U5D1.DK45"
					( objectStatus "ddr5_cs_n(7)" )
				)
				( pin "U5D1.CR74"
					( objectStatus "ddr5_dq(0)" )
				)
				( pin "U5D1.CN76"
					( objectStatus "ddr5_dq(1)" )
				)
				( pin "U5D1.CW76"
					( objectStatus "ddr5_dq(2)" )
				)
				( pin "U5D1.CV77"
					( objectStatus "ddr5_dq(3)" )
				)
				( pin "U5D1.CN74"
					( objectStatus "ddr5_dq(4)" )
				)
				( pin "U5D1.CM75"
					( objectStatus "ddr5_dq(5)" )
				)
				( pin "U5D1.CV75"
					( objectStatus "ddr5_dq(6)" )
				)
				( pin "U5D1.CT77"
					( objectStatus "ddr5_dq(7)" )
				)
				( pin "U5D1.DE74"
					( objectStatus "ddr5_dq(8)" )
				)
				( pin "U5D1.DC76"
					( objectStatus "ddr5_dq(9)" )
				)
				( pin "U5D1.DH75"
					( objectStatus "ddr5_dq(10)" )
				)
				( pin "U5D1.DJ76"
					( objectStatus "ddr5_dq(11)" )
				)
				( pin "U5D1.DC74"
					( objectStatus "ddr5_dq(12)" )
				)
				( pin "U5D1.DB75"
					( objectStatus "ddr5_dq(13)" )
				)
				( pin "U5D1.DF77"
					( objectStatus "ddr5_dq(14)" )
				)
				( pin "U5D1.DH77"
					( objectStatus "ddr5_dq(15)" )
				)
				( pin "U5D1.DG70"
					( objectStatus "ddr5_dq(16)" )
				)
				( pin "U5D1.DJ72"
					( objectStatus "ddr5_dq(17)" )
				)
				( pin "U5D1.DM69"
					( objectStatus "ddr5_dq(18)" )
				)
				( pin "U5D1.DN70"
					( objectStatus "ddr5_dq(19)" )
				)
				( pin "U5D1.DF71"
					( objectStatus "ddr5_dq(20)" )
				)
				( pin "U5D1.DG72"
					( objectStatus "ddr5_dq(21)" )
				)
				( pin "U5D1.DK69"
					( objectStatus "ddr5_dq(22)" )
				)
				( pin "U5D1.DM71"
					( objectStatus "ddr5_dq(23)" )
				)
				( pin "U5D1.CN66"
					( objectStatus "ddr5_dq(24)" )
				)
				( pin "U5D1.CU66"
					( objectStatus "ddr5_dq(25)" )
				)
				( pin "U5D1.CP63"
					( objectStatus "ddr5_dq(26)" )
				)
				( pin "U5D1.CT63"
					( objectStatus "ddr5_dq(27)" )
				)
				( pin "U5D1.CP67"
					( objectStatus "ddr5_dq(28)" )
				)
				( pin "U5D1.CT67"
					( objectStatus "ddr5_dq(29)" )
				)
				( pin "U5D1.CN64"
					( objectStatus "ddr5_dq(30)" )
				)
				( pin "U5D1.CU64"
					( objectStatus "ddr5_dq(31)" )
				)
				( pin "U5D1.DD41"
					( objectStatus "ddr5_dq(32)" )
				)
				( pin "U5D1.DG42"
					( objectStatus "ddr5_dq(33)" )
				)
				( pin "U5D1.DE38"
					( objectStatus "ddr5_dq(34)" )
				)
				( pin "U5D1.DG38"
					( objectStatus "ddr5_dq(35)" )
				)
				( pin "U5D1.DA42"
					( objectStatus "ddr5_dq(36)" )
				)
				( pin "U5D1.DE42"
					( objectStatus "ddr5_dq(37)" )
				)
				( pin "U5D1.DD39"
					( objectStatus "ddr5_dq(38)" )
				)
				( pin "U5D1.DH39"
					( objectStatus "ddr5_dq(39)" )
				)
				( pin "U5D1.DF33"
					( objectStatus "ddr5_dq(40)" )
				)
				( pin "U5D1.DK33"
					( objectStatus "ddr5_dq(41)" )
				)
				( pin "U5D1.DG30"
					( objectStatus "ddr5_dq(42)" )
				)
				( pin "U5D1.DJ30"
					( objectStatus "ddr5_dq(43)" )
				)
				( pin "U5D1.DG34"
					( objectStatus "ddr5_dq(44)" )
				)
				( pin "U5D1.DJ34"
					( objectStatus "ddr5_dq(45)" )
				)
				( pin "U5D1.DF31"
					( objectStatus "ddr5_dq(46)" )
				)
				( pin "U5D1.DK31"
					( objectStatus "ddr5_dq(47)" )
				)
				( pin "U5D1.CW36"
					( objectStatus "ddr5_dq(48)" )
				)
				( pin "U5D1.DC36"
					( objectStatus "ddr5_dq(49)" )
				)
				( pin "U5D1.CY33"
					( objectStatus "ddr5_dq(50)" )
				)
				( pin "U5D1.DB33"
					( objectStatus "ddr5_dq(51)" )
				)
				( pin "U5D1.CY37"
					( objectStatus "ddr5_dq(52)" )
				)
				( pin "U5D1.DB37"
					( objectStatus "ddr5_dq(53)" )
				)
				( pin "U5D1.CW34"
					( objectStatus "ddr5_dq(54)" )
				)
				( pin "U5D1.DC34"
					( objectStatus "ddr5_dq(55)" )
				)
				( pin "U5D1.CW30"
					( objectStatus "ddr5_dq(56)" )
				)
				( pin "U5D1.DC30"
					( objectStatus "ddr5_dq(57)" )
				)
				( pin "U5D1.CY27"
					( objectStatus "ddr5_dq(58)" )
				)
				( pin "U5D1.DB27"
					( objectStatus "ddr5_dq(59)" )
				)
				( pin "U5D1.CY31"
					( objectStatus "ddr5_dq(60)" )
				)
				( pin "U5D1.DB31"
					( objectStatus "ddr5_dq(61)" )
				)
				( pin "U5D1.CW28"
					( objectStatus "ddr5_dq(62)" )
				)
				( pin "U5D1.DC28"
					( objectStatus "ddr5_dq(63)" )
				)
				( pin "U5D1.CP77"
					( objectStatus "ddr5_dqs_dn(0)" )
				)
				( pin "U5D1.DD77"
					( objectStatus "ddr5_dqs_dn(1)" )
				)
				( pin "U5D1.DL72"
					( objectStatus "ddr5_dqs_dn(2)" )
				)
				( pin "U5D1.CV65"
					( objectStatus "ddr5_dqs_dn(3)" )
				)
				( pin "U5D1.DG40"
					( objectStatus "ddr5_dqs_dn(4)" )
				)
				( pin "U5D1.DL32"
					( objectStatus "ddr5_dqs_dn(5)" )
				)
				( pin "U5D1.DD35"
					( objectStatus "ddr5_dqs_dn(6)" )
				)
				( pin "U5D1.DD29"
					( objectStatus "ddr5_dqs_dn(7)" )
				)
				( pin "U5D1.CN70"
					( objectStatus "ddr5_dqs_dn(8)" )
				)
				( pin "U5D1.CT75"
					( objectStatus "ddr5_dqs_dn(9)" )
				)
				( pin "U5D1.DF75"
					( objectStatus "ddr5_dqs_dn(10)" )
				)
				( pin "U5D1.DJ70"
					( objectStatus "ddr5_dqs_dn(11)" )
				)
				( pin "U5D1.CP65"
					( objectStatus "ddr5_dqs_dn(12)" )
				)
				( pin "U5D1.DE40"
					( objectStatus "ddr5_dqs_dn(13)" )
				)
				( pin "U5D1.DG32"
					( objectStatus "ddr5_dqs_dn(14)" )
				)
				( pin "U5D1.CY35"
					( objectStatus "ddr5_dqs_dn(15)" )
				)
				( pin "U5D1.CY29"
					( objectStatus "ddr5_dqs_dn(16)" )
				)
				( pin "U5D1.CJ70"
					( objectStatus "ddr5_dqs_dn(17)" )
				)
				( pin "U5D1.CR76"
					( objectStatus "ddr5_dqs_dp(0)" )
				)
				( pin "U5D1.DE76"
					( objectStatus "ddr5_dqs_dp(1)" )
				)
				( pin "U5D1.DK71"
					( objectStatus "ddr5_dqs_dp(2)" )
				)
				( pin "U5D1.CT65"
					( objectStatus "ddr5_dqs_dp(3)" )
				)
				( pin "U5D1.DJ40"
					( objectStatus "ddr5_dqs_dp(4)" )
				)
				( pin "U5D1.DJ32"
					( objectStatus "ddr5_dqs_dp(5)" )
				)
				( pin "U5D1.DB35"
					( objectStatus "ddr5_dqs_dp(6)" )
				)
				( pin "U5D1.DB29"
					( objectStatus "ddr5_dqs_dp(7)" )
				)
				( pin "U5D1.CL70"
					( objectStatus "ddr5_dqs_dp(8)" )
				)
				( pin "U5D1.CU74"
					( objectStatus "ddr5_dqs_dp(9)" )
				)
				( pin "U5D1.DG74"
					( objectStatus "ddr5_dqs_dp(10)" )
				)
				( pin "U5D1.DH69"
					( objectStatus "ddr5_dqs_dp(11)" )
				)
				( pin "U5D1.CM65"
					( objectStatus "ddr5_dqs_dp(12)" )
				)
				( pin "U5D1.DC40"
					( objectStatus "ddr5_dqs_dp(13)" )
				)
				( pin "U5D1.DE32"
					( objectStatus "ddr5_dqs_dp(14)" )
				)
				( pin "U5D1.CV35"
					( objectStatus "ddr5_dqs_dp(15)" )
				)
				( pin "U5D1.CV29"
					( objectStatus "ddr5_dqs_dp(16)" )
				)
				( pin "U5D1.CG70"
					( objectStatus "ddr5_dqs_dp(17)" )
				)
				( pin "U5D1.CH71"
					( objectStatus "ddr5_ecc(0)" )
				)
				( pin "U5D1.CM71"
					( objectStatus "ddr5_ecc(1)" )
				)
				( pin "U5D1.CJ68"
					( objectStatus "ddr5_ecc(2)" )
				)
				( pin "U5D1.CL68"
					( objectStatus "ddr5_ecc(3)" )
				)
				( pin "U5D1.CJ72"
					( objectStatus "ddr5_ecc(4)" )
				)
				( pin "U5D1.CL72"
					( objectStatus "ddr5_ecc(5)" )
				)
				( pin "U5D1.CH69"
					( objectStatus "ddr5_ecc(6)" )
				)
				( pin "U5D1.CM69"
					( objectStatus "ddr5_ecc(7)" )
				)
				( pin "U5D1.DF53"
					( objectStatus "ddr5_ma(0)" )
				)
				( pin "U5D1.DC58"
					( objectStatus "ddr5_ma(1)" )
				)
				( pin "U5D1.DD57"
					( objectStatus "ddr5_ma(2)" )
				)
				( pin "U5D1.DG58"
					( objectStatus "ddr5_ma(3)" )
				)
				( pin "U5D1.DJ58"
					( objectStatus "ddr5_ma(4)" )
				)
				( pin "U5D1.DF59"
					( objectStatus "ddr5_ma(5)" )
				)
				( pin "U5D1.DK59"
					( objectStatus "ddr5_ma(6)" )
				)
				( pin "U5D1.DC60"
					( objectStatus "ddr5_ma(7)" )
				)
				( pin "U5D1.DD59"
					( objectStatus "ddr5_ma(8)" )
				)
				( pin "U5D1.DA58"
					( objectStatus "ddr5_ma(9)" )
				)
				( pin "U5D1.DD55"
					( objectStatus "ddr5_ma(10)" )
				)
				( pin "U5D1.DA60"
					( objectStatus "ddr5_ma(11)" )
				)
				( pin "U5D1.DG60"
					( objectStatus "ddr5_ma(12)" )
				)
				( pin "U5D1.DD53"
					( objectStatus "ddr5_ma(13)" )
				)
				( pin "U5D1.DJ50"
					( objectStatus "ddr5_ma(14)" )
				)
				( pin "U5D1.DC54"
					( objectStatus "ddr5_ma(15)" )
				)
				( pin "U5D1.DG52"
					( objectStatus "ddr5_ma(16)" )
				)
				( pin "U5D1.DE46"
					( objectStatus "ddr5_ma(17)" )
				)
				( pin "U5D1.DG50"
					( objectStatus "ddr5_odt(0)" )
				)
				( pin "U5D1.DG48"
					( objectStatus "ddr5_odt(1)" )
				)
				( pin "U5D1.DK49"
					( objectStatus "ddr5_odt(2)" )
				)
				( pin "U5D1.DF47"
					( objectStatus "ddr5_odt(3)" )
				)
				( pin "U5D1.DK53"
					( objectStatus "ddr5_par" )
				)
			)
			( gate "U5D1"
				( objectStatus "@baseboard_fab2_lib.baseboard_fab2(sch_1):page29_i61" )
				( pin "U5D1.BN22"
					( objectStatus "cd_hfi0_i2cclk" )
				)
				( pin "U5D1.BP23"
					( objectStatus "cd_hfi0_i2cdat" )
				)
				( pin "U5D1.BP19"
					( objectStatus "cd_hfi0_int_n" )
				)
				( pin "U5D1.BK21"
					( objectStatus "cd_hfi0_led_n" )
				)
				( pin "U5D1.BR20"
					( objectStatus "cd_hfi0_modprst_n" )
				)
				( pin "U5D1.BN24"
					( objectStatus "cd_hfi0_reset_n" )
				)
				( pin "U5D1.BJ22"
					( objectStatus "cd_hfi1_i2cclk" )
				)
				( pin "U5D1.BH23"
					( objectStatus "cd_hfi1_i2cdat" )
				)
				( pin "U5D1.BM21"
					( objectStatus "cd_hfi1_int_n" )
				)
				( pin "U5D1.BM23"
					( objectStatus "cd_hfi1_led_n" )
				)
				( pin "U5D1.BT19"
					( objectStatus "cd_hfi1_modprst_n" )
				)
				( pin "U5D1.BK23"
					( objectStatus "cd_hfi1_reset_n" )
				)
				( pin "U5D1.BE16"
					( objectStatus "cd_hfi_refclk_dn" )
				)
				( pin "U5D1.BG16"
					( objectStatus "cd_hfi_refclk_dp" )
				)
				( pin "U5D1.BU24"
					( objectStatus "cd_pe_refclk_dn" )
				)
				( pin "U5D1.BW24"
					( objectStatus "cd_pe_refclk_dp" )
				)
				( pin "U5D1.CF25"
					( objectStatus "cd_por_n" )
				)
				( pin "U5D1.CB23"
					( objectStatus "cd_tclk" )
				)
				( pin "U5D1.BY21"
					( objectStatus "cd_tdi" )
				)
				( pin "U5D1.CC22"
					( objectStatus "cd_tdo" )
				)
				( pin "U5D1.CE24"
					( objectStatus "cd_tms" )
				)
				( pin "U5D1.CD23"
					( objectStatus "cd_trst_n" )
				)
				( pin "U5D1.CK9"
					( objectStatus "dmi_rx_dn(0)" )
				)
				( pin "U5D1.CM11"
					( objectStatus "dmi_rx_dn(1)" )
				)
				( pin "U5D1.CR12"
					( objectStatus "dmi_rx_dn(2)" )
				)
				( pin "U5D1.CT11"
					( objectStatus "dmi_rx_dn(3)" )
				)
				( pin "U5D1.CL10"
					( objectStatus "dmi_rx_dp(0)" )
				)
				( pin "U5D1.CN10"
					( objectStatus "dmi_rx_dp(1)" )
				)
				( pin "U5D1.CP11"
					( objectStatus "dmi_rx_dp(2)" )
				)
				( pin "U5D1.CV11"
					( objectStatus "dmi_rx_dp(3)" )
				)
				( pin "U5D1.CG4"
					( objectStatus "dmi_tx_dn(0)" )
				)
				( pin "U5D1.CJ4"
					( objectStatus "dmi_tx_dn(1)" )
				)
				( pin "U5D1.CN4"
					( objectStatus "dmi_tx_dn(2)" )
				)
				( pin "U5D1.CP5"
					( objectStatus "dmi_tx_dn(3)" )
				)
				( pin "U5D1.CH5"
					( objectStatus "dmi_tx_dp(0)" )
				)
				( pin "U5D1.CL4"
					( objectStatus "dmi_tx_dp(1)" )
				)
				( pin "U5D1.CM3"
					( objectStatus "dmi_tx_dp(2)" )
				)
				( pin "U5D1.CR4"
					( objectStatus "dmi_tx_dp(3)" )
				)
				( pin "U5D1.BA76"
					( objectStatus "rsvd(172)" )
				)
				( pin "U5D1.BA66"
					( objectStatus "rsvd(173)" )
				)
				( pin "U5D1.BA64"
					( objectStatus "rsvd(174)" )
				)
				( pin "U5D1.BA22"
					( objectStatus "rsvd(175)" )
				)
				( pin "U5D1.BA18"
					( objectStatus "rsvd(176)" )
				)
				( pin "U5D1.BA16"
					( objectStatus "rsvd(177)" )
				)
				( pin "U5D1.BA14"
					( objectStatus "rsvd(178)" )
				)
				( pin "U5D1.AY77"
					( objectStatus "rsvd(179)" )
				)
				( pin "U5D1.AY75"
					( objectStatus "rsvd(180)" )
				)
				( pin "U5D1.AY67"
					( objectStatus "rsvd(181)" )
				)
				( pin "U5D1.AY65"
					( objectStatus "rsvd(182)" )
				)
				( pin "U5D1.AW76"
					( objectStatus "rsvd(183)" )
				)
				( pin "U5D1.AW64"
					( objectStatus "rsvd(184)" )
				)
				( pin "U5D1.AV77"
					( objectStatus "rsvd(186)" )
				)
				( pin "U5D1.AT25"
					( objectStatus "rsvd(187)" )
				)
				( pin "U5D1.AT23"
					( objectStatus "rsvd(188)" )
				)
				( pin "U5D1.AT13"
					( objectStatus "rsvd(189)" )
				)
				( pin "U5D1.AR62"
					( objectStatus "rsvd(190)" )
				)
				( pin "U5D1.AR26"
					( objectStatus "rsvd(191)" )
				)
				( pin "U5D1.AR22"
					( objectStatus "rsvd(192)" )
				)
				( pin "U5D1.AR20"
					( objectStatus "rsvd(193)" )
				)
			)
			( gate "U5D1"
				( objectStatus "@baseboard_fab2_lib.baseboard_fab2(sch_1):page30_i84" )
				( pin "U5D1.CW8"
					( objectStatus "pe1_rx_dn(0)" )
				)
				( pin "U5D1.DA8"
					( objectStatus "pe1_rx_dn(1)" )
				)
				( pin "U5D1.DC8"
					( objectStatus "pe1_rx_dn(2)" )
				)
				( pin "U5D1.DC10"
					( objectStatus "pe1_rx_dn(3)" )
				)
				( pin "U5D1.DE10"
					( objectStatus "pe1_rx_dn(4)" )
				)
				( pin "U5D1.DH9"
					( objectStatus "pe1_rx_dn(5)" )
				)
				( pin "U5D1.DK9"
					( objectStatus "pe1_rx_dn(6)" )
				)
				( pin "U5D1.DM9"
					( objectStatus "pe1_rx_dn(7)" )
				)
				( pin "U5D1.DM11"
					( objectStatus "pe1_rx_dn(8)" )
				)
				( pin "U5D1.DP11"
					( objectStatus "pe1_rx_dn(9)" )
				)
				( pin "U5D1.DT11"
					( objectStatus "pe1_rx_dn(10)" )
				)
				( pin "U5D1.DT13"
					( objectStatus "pe1_rx_dn(11)" )
				)
				( pin "U5D1.DV13"
					( objectStatus "pe1_rx_dn(12)" )
				)
				( pin "U5D1.DW14"
					( objectStatus "pe1_rx_dn(13)" )
				)
				( pin "U5D1.DY15"
					( objectStatus "pe1_rx_dn(14)" )
				)
				( pin "U5D1.DU16"
					( objectStatus "pe1_rx_dn(15)" )
				)
				( pin "U5D1.CU8"
					( objectStatus "pe1_rx_dp(0)" )
				)
				( pin "U5D1.CY7"
					( objectStatus "pe1_rx_dp(1)" )
				)
				( pin "U5D1.DB9"
					( objectStatus "pe1_rx_dp(2)" )
				)
				( pin "U5D1.DA10"
					( objectStatus "pe1_rx_dp(3)" )
				)
				( pin "U5D1.DD9"
					( objectStatus "pe1_rx_dp(4)" )
				)
				( pin "U5D1.DF9"
					( objectStatus "pe1_rx_dp(5)" )
				)
				( pin "U5D1.DJ8"
					( objectStatus "pe1_rx_dp(6)" )
				)
				( pin "U5D1.DL10"
					( objectStatus "pe1_rx_dp(7)" )
				)
				( pin "U5D1.DK11"
					( objectStatus "pe1_rx_dp(8)" )
				)
				( pin "U5D1.DN10"
					( objectStatus "pe1_rx_dp(9)" )
				)
				( pin "U5D1.DR12"
					( objectStatus "pe1_rx_dp(10)" )
				)
				( pin "U5D1.DP13"
					( objectStatus "pe1_rx_dp(11)" )
				)
				( pin "U5D1.DU12"
					( objectStatus "pe1_rx_dp(12)" )
				)
				( pin "U5D1.DY13"
					( objectStatus "pe1_rx_dp(13)" )
				)
				( pin "U5D1.DV15"
					( objectStatus "pe1_rx_dp(14)" )
				)
				( pin "U5D1.DT15"
					( objectStatus "pe1_rx_dp(15)" )
				)
				( pin "U5D1.DA2"
					( objectStatus "pe1_tx_dn(0)" )
				)
				( pin "U5D1.DC2"
					( objectStatus "pe1_tx_dn(1)" )
				)
				( pin "U5D1.DE2"
					( objectStatus "pe1_tx_dn(2)" )
				)
				( pin "U5D1.DE4"
					( objectStatus "pe1_tx_dn(3)" )
				)
				( pin "U5D1.DG4"
					( objectStatus "pe1_tx_dn(4)" )
				)
				( pin "U5D1.DK3"
					( objectStatus "pe1_tx_dn(5)" )
				)
				( pin "U5D1.DM3"
					( objectStatus "pe1_tx_dn(6)" )
				)
				( pin "U5D1.DN4"
					( objectStatus "pe1_tx_dn(7)" )
				)
				( pin "U5D1.DT5"
					( objectStatus "pe1_tx_dn(8)" )
				)
				( pin "U5D1.DV3"
					( objectStatus "pe1_tx_dn(9)" )
				)
				( pin "U5D1.DW4"
					( objectStatus "pe1_tx_dn(10)" )
				)
				( pin "U5D1.DU6"
					( objectStatus "pe1_tx_dn(11)" )
				)
				( pin "U5D1.DV7"
					( objectStatus "pe1_tx_dn(12)" )
				)
				( pin "U5D1.DY7"
					( objectStatus "pe1_tx_dn(13)" )
				)
				( pin "U5D1.EA8"
					( objectStatus "pe1_tx_dn(14)" )
				)
				( pin "U5D1.ED9"
					( objectStatus "pe1_tx_dn(15)" )
				)
				( pin "U5D1.CW2"
					( objectStatus "pe1_tx_dp(0)" )
				)
				( pin "U5D1.DB1"
					( objectStatus "pe1_tx_dp(1)" )
				)
				( pin "U5D1.DD3"
					( objectStatus "pe1_tx_dp(2)" )
				)
				( pin "U5D1.DC4"
					( objectStatus "pe1_tx_dp(3)" )
				)
				( pin "U5D1.DF3"
					( objectStatus "pe1_tx_dp(4)" )
				)
				( pin "U5D1.DH3"
					( objectStatus "pe1_tx_dp(5)" )
				)
				( pin "U5D1.DL2"
					( objectStatus "pe1_tx_dp(6)" )
				)
				( pin "U5D1.DP3"
					( objectStatus "pe1_tx_dp(7)" )
				)
				( pin "U5D1.DR4"
					( objectStatus "pe1_tx_dp(8)" )
				)
				( pin "U5D1.DU2"
					( objectStatus "pe1_tx_dp(9)" )
				)
				( pin "U5D1.DU4"
					( objectStatus "pe1_tx_dp(10)" )
				)
				( pin "U5D1.DV5"
					( objectStatus "pe1_tx_dp(11)" )
				)
				( pin "U5D1.DT7"
					( objectStatus "pe1_tx_dp(12)" )
				)
				( pin "U5D1.DW6"
					( objectStatus "pe1_tx_dp(13)" )
				)
				( pin "U5D1.EB7"
					( objectStatus "pe1_tx_dp(14)" )
				)
				( pin "U5D1.EC8"
					( objectStatus "pe1_tx_dp(15)" )
				)
			)
			( gate "U5D1"
				( objectStatus "@baseboard_fab2_lib.baseboard_fab2(sch_1):page31_i106" )
				( pin "U5D1.CT9"
					( objectStatus "pe2_rx_dn(0)" )
				)
				( pin "U5D1.CP9"
					( objectStatus "pe2_rx_dn(1)" )
				)
				( pin "U5D1.CP7"
					( objectStatus "pe2_rx_dn(2)" )
				)
				( pin "U5D1.CM7"
					( objectStatus "pe2_rx_dn(3)" )
				)
				( pin "U5D1.CK7"
					( objectStatus "pe2_rx_dn(4)" )
				)
				( pin "U5D1.CG8"
					( objectStatus "pe2_rx_dn(5)" )
				)
				( pin "U5D1.CE6"
					( objectStatus "pe2_rx_dn(6)" )
				)
				( pin "U5D1.CE8"
					( objectStatus "pe2_rx_dn(7)" )
				)
				( pin "U5D1.BY9"
					( objectStatus "pe2_rx_dn(8)" )
				)
				( pin "U5D1.BY7"
					( objectStatus "pe2_rx_dn(9)" )
				)
				( pin "U5D1.BV7"
					( objectStatus "pe2_rx_dn(10)" )
				)
				( pin "U5D1.BT7"
					( objectStatus "pe2_rx_dn(11)" )
				)
				( pin "U5D1.BR8"
					( objectStatus "pe2_rx_dn(12)" )
				)
				( pin "U5D1.BN8"
					( objectStatus "pe2_rx_dn(13)" )
				)
				( pin "U5D1.BL8"
					( objectStatus "pe2_rx_dn(14)" )
				)
				( pin "U5D1.BK9"
					( objectStatus "pe2_rx_dn(15)" )
				)
				( pin "U5D1.CR8"
					( objectStatus "pe2_rx_dp(0)" )
				)
				( pin "U5D1.CM9"
					( objectStatus "pe2_rx_dp(1)" )
				)
				( pin "U5D1.CN8"
					( objectStatus "pe2_rx_dp(2)" )
				)
				( pin "U5D1.CL6"
					( objectStatus "pe2_rx_dp(3)" )
				)
				( pin "U5D1.CH7"
					( objectStatus "pe2_rx_dp(4)" )
				)
				( pin "U5D1.CF7"
					( objectStatus "pe2_rx_dp(5)" )
				)
				( pin "U5D1.CD7"
					( objectStatus "pe2_rx_dp(6)" )
				)
				( pin "U5D1.CC8"
					( objectStatus "pe2_rx_dp(7)" )
				)
				( pin "U5D1.BV9"
					( objectStatus "pe2_rx_dp(8)" )
				)
				( pin "U5D1.BW8"
					( objectStatus "pe2_rx_dp(9)" )
				)
				( pin "U5D1.BU6"
					( objectStatus "pe2_rx_dp(10)" )
				)
				( pin "U5D1.BP7"
					( objectStatus "pe2_rx_dp(11)" )
				)
				( pin "U5D1.BP9"
					( objectStatus "pe2_rx_dp(12)" )
				)
				( pin "U5D1.BM7"
					( objectStatus "pe2_rx_dp(13)" )
				)
				( pin "U5D1.BJ8"
					( objectStatus "pe2_rx_dp(14)" )
				)
				( pin "U5D1.BJ10"
					( objectStatus "pe2_rx_dp(15)" )
				)
				( pin "U5D1.CY3"
					( objectStatus "pe2_tx_dn(0)" )
				)
				( pin "U5D1.CV3"
					( objectStatus "pe2_tx_dn(1)" )
				)
				( pin "U5D1.CT1"
					( objectStatus "pe2_tx_dn(2)" )
				)
				( pin "U5D1.CT3"
					( objectStatus "pe2_tx_dn(3)" )
				)
				( pin "U5D1.CM1"
					( objectStatus "pe2_tx_dn(4)" )
				)
				( pin "U5D1.CL2"
					( objectStatus "pe2_tx_dn(5)" )
				)
				( pin "U5D1.CG2"
					( objectStatus "pe2_tx_dn(6)" )
				)
				( pin "U5D1.CF3"
					( objectStatus "pe2_tx_dn(7)" )
				)
				( pin "U5D1.CC2"
					( objectStatus "pe2_tx_dn(8)" )
				)
				( pin "U5D1.CB3"
					( objectStatus "pe2_tx_dn(9)" )
				)
				( pin "U5D1.CA4"
					( objectStatus "pe2_tx_dn(10)" )
				)
				( pin "U5D1.BW4"
					( objectStatus "pe2_tx_dn(11)" )
				)
				( pin "U5D1.BU4"
					( objectStatus "pe2_tx_dn(12)" )
				)
				( pin "U5D1.BP5"
					( objectStatus "pe2_tx_dn(13)" )
				)
				( pin "U5D1.BL4"
					( objectStatus "pe2_tx_dn(14)" )
				)
				( pin "U5D1.BM5"
					( objectStatus "pe2_tx_dn(15)" )
				)
				( pin "U5D1.CW4"
					( objectStatus "pe2_tx_dp(0)" )
				)
				( pin "U5D1.CU2"
					( objectStatus "pe2_tx_dp(1)" )
				)
				( pin "U5D1.CR2"
					( objectStatus "pe2_tx_dp(2)" )
				)
				( pin "U5D1.CP3"
					( objectStatus "pe2_tx_dp(3)" )
				)
				( pin "U5D1.CK1"
					( objectStatus "pe2_tx_dp(4)" )
				)
				( pin "U5D1.CK3"
					( objectStatus "pe2_tx_dp(5)" )
				)
				( pin "U5D1.CE2"
					( objectStatus "pe2_tx_dp(6)" )
				)
				( pin "U5D1.CE4"
					( objectStatus "pe2_tx_dp(7)" )
				)
				( pin "U5D1.CD3"
					( objectStatus "pe2_tx_dp(8)" )
				)
				( pin "U5D1.BY3"
					( objectStatus "pe2_tx_dp(9)" )
				)
				( pin "U5D1.BY5"
					( objectStatus "pe2_tx_dp(10)" )
				)
				( pin "U5D1.BV3"
					( objectStatus "pe2_tx_dp(11)" )
				)
				( pin "U5D1.BR4"
					( objectStatus "pe2_tx_dp(12)" )
				)
				( pin "U5D1.BN4"
					( objectStatus "pe2_tx_dp(13)" )
				)
				( pin "U5D1.BM3"
					( objectStatus "pe2_tx_dp(14)" )
				)
				( pin "U5D1.BK5"
					( objectStatus "pe2_tx_dp(15)" )
				)
			)
			( gate "U5D1"
				( objectStatus "@baseboard_fab2_lib.baseboard_fab2(sch_1):page32_i89" )
				( pin "U5D1.EA18"
					( objectStatus "pe3_rx_dn(0)" )
				)
				( pin "U5D1.DW18"
					( objectStatus "pe3_rx_dn(1)" )
				)
				( pin "U5D1.DW16"
					( objectStatus "pe3_rx_dn(2)" )
				)
				( pin "U5D1.DT19"
					( objectStatus "pe3_rx_dn(3)" )
				)
				( pin "U5D1.DR16"
					( objectStatus "pe3_rx_dn(4)" )
				)
				( pin "U5D1.DR14"
					( objectStatus "pe3_rx_dn(5)" )
				)
				( pin "U5D1.DN14"
					( objectStatus "pe3_rx_dn(6)" )
				)
				( pin "U5D1.DL14"
					( objectStatus "pe3_rx_dn(7)" )
				)
				( pin "U5D1.DL12"
					( objectStatus "pe3_rx_dn(8)" )
				)
				( pin "U5D1.DJ12"
					( objectStatus "pe3_rx_dn(9)" )
				)
				( pin "U5D1.DG12"
					( objectStatus "pe3_rx_dn(10)" )
				)
				( pin "U5D1.DG10"
					( objectStatus "pe3_rx_dn(11)" )
				)
				( pin "U5D1.DD13"
					( objectStatus "pe3_rx_dn(12)" )
				)
				( pin "U5D1.DB11"
					( objectStatus "pe3_rx_dn(13)" )
				)
				( pin "U5D1.CY11"
					( objectStatus "pe3_rx_dn(14)" )
				)
				( pin "U5D1.CV9"
					( objectStatus "pe3_rx_dn(15)" )
				)
				( pin "U5D1.DY17"
					( objectStatus "pe3_rx_dp(0)" )
				)
				( pin "U5D1.DU18"
					( objectStatus "pe3_rx_dp(1)" )
				)
				( pin "U5D1.DV17"
					( objectStatus "pe3_rx_dp(2)" )
				)
				( pin "U5D1.DR18"
					( objectStatus "pe3_rx_dp(3)" )
				)
				( pin "U5D1.DN16"
					( objectStatus "pe3_rx_dp(4)" )
				)
				( pin "U5D1.DP15"
					( objectStatus "pe3_rx_dp(5)" )
				)
				( pin "U5D1.DM13"
					( objectStatus "pe3_rx_dp(6)" )
				)
				( pin "U5D1.DJ14"
					( objectStatus "pe3_rx_dp(7)" )
				)
				( pin "U5D1.DK13"
					( objectStatus "pe3_rx_dp(8)" )
				)
				( pin "U5D1.DH11"
					( objectStatus "pe3_rx_dp(9)" )
				)
				( pin "U5D1.DE12"
					( objectStatus "pe3_rx_dp(10)" )
				)
				( pin "U5D1.DF11"
					( objectStatus "pe3_rx_dp(11)" )
				)
				( pin "U5D1.DC12"
					( objectStatus "pe3_rx_dp(12)" )
				)
				( pin "U5D1.DA12"
					( objectStatus "pe3_rx_dp(13)" )
				)
				( pin "U5D1.CW10"
					( objectStatus "pe3_rx_dp(14)" )
				)
				( pin "U5D1.CU10"
					( objectStatus "pe3_rx_dp(15)" )
				)
				( pin "U5D1.EE14"
					( objectStatus "pe3_tx_dn(0)" )
				)
				( pin "U5D1.EE12"
					( objectStatus "pe3_tx_dn(1)" )
				)
				( pin "U5D1.EC12"
					( objectStatus "pe3_tx_dn(2)" )
				)
				( pin "U5D1.DY11"
					( objectStatus "pe3_tx_dn(3)" )
				)
				( pin "U5D1.EB9"
					( objectStatus "pe3_tx_dn(4)" )
				)
				( pin "U5D1.DW10"
					( objectStatus "pe3_tx_dn(5)" )
				)
				( pin "U5D1.DU8"
					( objectStatus "pe3_tx_dn(6)" )
				)
				( pin "U5D1.DR8"
					( objectStatus "pe3_tx_dn(7)" )
				)
				( pin "U5D1.DM7"
					( objectStatus "pe3_tx_dn(8)" )
				)
				( pin "U5D1.DP5"
					( objectStatus "pe3_tx_dn(9)" )
				)
				( pin "U5D1.DL6"
					( objectStatus "pe3_tx_dn(10)" )
				)
				( pin "U5D1.DJ4"
					( objectStatus "pe3_tx_dn(11)" )
				)
				( pin "U5D1.DJ6"
					( objectStatus "pe3_tx_dn(12)" )
				)
				( pin "U5D1.DD5"
					( objectStatus "pe3_tx_dn(13)" )
				)
				( pin "U5D1.DB5"
					( objectStatus "pe3_tx_dn(14)" )
				)
				( pin "U5D1.CY5"
					( objectStatus "pe3_tx_dn(15)" )
				)
				( pin "U5D1.EC14"
					( objectStatus "pe3_tx_dp(0)" )
				)
				( pin "U5D1.ED13"
					( objectStatus "pe3_tx_dp(1)" )
				)
				( pin "U5D1.EB11"
					( objectStatus "pe3_tx_dp(2)" )
				)
				( pin "U5D1.EA10"
					( objectStatus "pe3_tx_dp(3)" )
				)
				( pin "U5D1.DY9"
					( objectStatus "pe3_tx_dp(4)" )
				)
				( pin "U5D1.DV9"
					( objectStatus "pe3_tx_dp(5)" )
				)
				( pin "U5D1.DT9"
					( objectStatus "pe3_tx_dp(6)" )
				)
				( pin "U5D1.DP7"
					( objectStatus "pe3_tx_dp(7)" )
				)
				( pin "U5D1.DN6"
					( objectStatus "pe3_tx_dp(8)" )
				)
				( pin "U5D1.DM5"
					( objectStatus "pe3_tx_dp(9)" )
				)
				( pin "U5D1.DK5"
					( objectStatus "pe3_tx_dp(10)" )
				)
				( pin "U5D1.DH5"
					( objectStatus "pe3_tx_dp(11)" )
				)
				( pin "U5D1.DG6"
					( objectStatus "pe3_tx_dp(12)" )
				)
				( pin "U5D1.DC6"
					( objectStatus "pe3_tx_dp(13)" )
				)
				( pin "U5D1.DA4"
					( objectStatus "pe3_tx_dp(14)" )
				)
				( pin "U5D1.CV5"
					( objectStatus "pe3_tx_dp(15)" )
				)
			)
			( gate "U5D1"
				( objectStatus "@baseboard_fab2_lib.baseboard_fab2(sch_1):page33_i86" )
				( pin "U5D1.AC10"
					( objectStatus "upi0_rx_dn(0)" )
				)
				( pin "U5D1.AA8"
					( objectStatus "upi0_rx_dn(1)" )
				)
				( pin "U5D1.AB7"
					( objectStatus "upi0_rx_dn(2)" )
				)
				( pin "U5D1.AD5"
					( objectStatus "upi0_rx_dn(3)" )
				)
				( pin "U5D1.AE6"
					( objectStatus "upi0_rx_dn(4)" )
				)
				( pin "U5D1.AG8"
					( objectStatus "upi0_rx_dn(5)" )
				)
				( pin "U5D1.AJ6"
					( objectStatus "upi0_rx_dn(6)" )
				)
				( pin "U5D1.AL6"
					( objectStatus "upi0_rx_dn(7)" )
				)
				( pin "U5D1.AK7"
					( objectStatus "upi0_rx_dn(8)" )
				)
				( pin "U5D1.AM9"
					( objectStatus "upi0_rx_dn(9)" )
				)
				( pin "U5D1.AP7"
					( objectStatus "upi0_rx_dn(10)" )
				)
				( pin "U5D1.AR8"
					( objectStatus "upi0_rx_dn(11)" )
				)
				( pin "U5D1.AU10"
					( objectStatus "upi0_rx_dn(12)" )
				)
				( pin "U5D1.BA8"
					( objectStatus "upi0_rx_dn(13)" )
				)
				( pin "U5D1.BC6"
					( objectStatus "upi0_rx_dn(14)" )
				)
				( pin "U5D1.BD7"
					( objectStatus "upi0_rx_dn(15)" )
				)
				( pin "U5D1.AW8"
					( objectStatus "upi0_rx_dn(16)" )
				)
				( pin "U5D1.AY9"
					( objectStatus "upi0_rx_dn(17)" )
				)
				( pin "U5D1.BD9"
					( objectStatus "upi0_rx_dn(18)" )
				)
				( pin "U5D1.BB11"
					( objectStatus "upi0_rx_dn(19)" )
				)
				( pin "U5D1.AB9"
					( objectStatus "upi0_rx_dp(0)" )
				)
				( pin "U5D1.AC8"
					( objectStatus "upi0_rx_dp(1)" )
				)
				( pin "U5D1.AA6"
					( objectStatus "upi0_rx_dp(2)" )
				)
				( pin "U5D1.AC6"
					( objectStatus "upi0_rx_dp(3)" )
				)
				( pin "U5D1.AG6"
					( objectStatus "upi0_rx_dp(4)" )
				)
				( pin "U5D1.AF7"
					( objectStatus "upi0_rx_dp(5)" )
				)
				( pin "U5D1.AH7"
					( objectStatus "upi0_rx_dp(6)" )
				)
				( pin "U5D1.AK5"
					( objectStatus "upi0_rx_dp(7)" )
				)
				( pin "U5D1.AM7"
					( objectStatus "upi0_rx_dp(8)" )
				)
				( pin "U5D1.AL8"
					( objectStatus "upi0_rx_dp(9)" )
				)
				( pin "U5D1.AN8"
					( objectStatus "upi0_rx_dp(10)" )
				)
				( pin "U5D1.AU8"
					( objectStatus "upi0_rx_dp(11)" )
				)
				( pin "U5D1.AT9"
					( objectStatus "upi0_rx_dp(12)" )
				)
				( pin "U5D1.AY7"
					( objectStatus "upi0_rx_dp(13)" )
				)
				( pin "U5D1.BB7"
					( objectStatus "upi0_rx_dp(14)" )
				)
				( pin "U5D1.BF7"
					( objectStatus "upi0_rx_dp(15)" )
				)
				( pin "U5D1.AV9"
					( objectStatus "upi0_rx_dp(16)" )
				)
				( pin "U5D1.BB9"
					( objectStatus "upi0_rx_dp(17)" )
				)
				( pin "U5D1.BC10"
					( objectStatus "upi0_rx_dp(18)" )
				)
				( pin "U5D1.BA10"
					( objectStatus "upi0_rx_dp(19)" )
				)
				( pin "U5D1.N2"
					( objectStatus "upi0_tx_dn(0)" )
				)
				( pin "U5D1.P1"
					( objectStatus "upi0_tx_dn(1)" )
				)
				( pin "U5D1.V3"
					( objectStatus "upi0_tx_dn(2)" )
				)
				( pin "U5D1.Y1"
					( objectStatus "upi0_tx_dn(3)" )
				)
				( pin "U5D1.AB3"
					( objectStatus "upi0_tx_dn(4)" )
				)
				( pin "U5D1.AC2"
					( objectStatus "upi0_tx_dn(5)" )
				)
				( pin "U5D1.AG4"
					( objectStatus "upi0_tx_dn(6)" )
				)
				( pin "U5D1.AE2"
					( objectStatus "upi0_tx_dn(7)" )
				)
				( pin "U5D1.AH3"
					( objectStatus "upi0_tx_dn(8)" )
				)
				( pin "U5D1.AL2"
					( objectStatus "upi0_tx_dn(9)" )
				)
				( pin "U5D1.AM3"
					( objectStatus "upi0_tx_dn(10)" )
				)
				( pin "U5D1.AN4"
					( objectStatus "upi0_tx_dn(11)" )
				)
				( pin "U5D1.AT1"
					( objectStatus "upi0_tx_dn(12)" )
				)
				( pin "U5D1.AT3"
					( objectStatus "upi0_tx_dn(13)" )
				)
				( pin "U5D1.AU4"
					( objectStatus "upi0_tx_dn(14)" )
				)
				( pin "U5D1.AV5"
					( objectStatus "upi0_tx_dn(15)" )
				)
				( pin "U5D1.BA4"
					( objectStatus "upi0_tx_dn(16)" )
				)
				( pin "U5D1.BB3"
					( objectStatus "upi0_tx_dn(17)" )
				)
				( pin "U5D1.BF3"
					( objectStatus "upi0_tx_dn(18)" )
				)
				( pin "U5D1.BG4"
					( objectStatus "upi0_tx_dn(19)" )
				)
				( pin "U5D1.M1"
					( objectStatus "upi0_tx_dp(0)" )
				)
				( pin "U5D1.T1"
					( objectStatus "upi0_tx_dp(1)" )
				)
				( pin "U5D1.Y3"
					( objectStatus "upi0_tx_dp(2)" )
				)
				( pin "U5D1.W2"
					( objectStatus "upi0_tx_dp(3)" )
				)
				( pin "U5D1.AA2"
					( objectStatus "upi0_tx_dp(4)" )
				)
				( pin "U5D1.AD1"
					( objectStatus "upi0_tx_dp(5)" )
				)
				( pin "U5D1.AF3"
					( objectStatus "upi0_tx_dp(6)" )
				)
				( pin "U5D1.AG2"
					( objectStatus "upi0_tx_dp(7)" )
				)
				( pin "U5D1.AJ2"
					( objectStatus "upi0_tx_dp(8)" )
				)
				( pin "U5D1.AK1"
					( objectStatus "upi0_tx_dp(9)" )
				)
				( pin "U5D1.AK3"
					( objectStatus "upi0_tx_dp(10)" )
				)
				( pin "U5D1.AP3"
					( objectStatus "upi0_tx_dp(11)" )
				)
				( pin "U5D1.AP1"
					( objectStatus "upi0_tx_dp(12)" )
				)
				( pin "U5D1.AR2"
					( objectStatus "upi0_tx_dp(13)" )
				)
				( pin "U5D1.AR4"
					( objectStatus "upi0_tx_dp(14)" )
				)
				( pin "U5D1.AW4"
					( objectStatus "upi0_tx_dp(15)" )
				)
				( pin "U5D1.AY3"
					( objectStatus "upi0_tx_dp(16)" )
				)
				( pin "U5D1.BC2"
					( objectStatus "upi0_tx_dp(17)" )
				)
				( pin "U5D1.BD3"
					( objectStatus "upi0_tx_dp(18)" )
				)
				( pin "U5D1.BH3"
					( objectStatus "upi0_tx_dp(19)" )
				)
			)
			( gate "U5D1"
				( objectStatus "@baseboard_fab2_lib.baseboard_fab2(sch_1):page34_i86" )
				( pin "U5D1.T5"
					( objectStatus "upi1_rx_dn(0)" )
				)
				( pin "U5D1.P7"
					( objectStatus "upi1_rx_dn(1)" )
				)
				( pin "U5D1.V7"
					( objectStatus "upi1_rx_dn(2)" )
				)
				( pin "U5D1.T9"
					( objectStatus "upi1_rx_dn(3)" )
				)
				( pin "U5D1.P9"
					( objectStatus "upi1_rx_dn(4)" )
				)
				( pin "U5D1.R10"
					( objectStatus "upi1_rx_dn(5)" )
				)
				( pin "U5D1.U12"
					( objectStatus "upi1_rx_dn(6)" )
				)
				( pin "U5D1.L12"
					( objectStatus "upi1_rx_dn(7)" )
				)
				( pin "U5D1.N14"
					( objectStatus "upi1_rx_dn(8)" )
				)
				( pin "U5D1.R12"
					( objectStatus "upi1_rx_dn(9)" )
				)
				( pin "U5D1.R16"
					( objectStatus "upi1_rx_dn(10)" )
				)
				( pin "U5D1.P17"
					( objectStatus "upi1_rx_dn(11)" )
				)
				( pin "U5D1.U16"
					( objectStatus "upi1_rx_dn(12)" )
				)
				( pin "U5D1.W18"
					( objectStatus "upi1_rx_dn(13)" )
				)
				( pin "U5D1.R20"
					( objectStatus "upi1_rx_dn(14)" )
				)
				( pin "U5D1.U18"
					( objectStatus "upi1_rx_dn(15)" )
				)
				( pin "U5D1.P21"
					( objectStatus "upi1_rx_dn(16)" )
				)
				( pin "U5D1.V19"
					( objectStatus "upi1_rx_dn(17)" )
				)
				( pin "U5D1.Y21"
					( objectStatus "upi1_rx_dn(18)" )
				)
				( pin "U5D1.AB19"
					( objectStatus "upi1_rx_dn(19)" )
				)
				( pin "U5D1.R6"
					( objectStatus "upi1_rx_dp(0)" )
				)
				( pin "U5D1.T7"
					( objectStatus "upi1_rx_dp(1)" )
				)
				( pin "U5D1.U8"
					( objectStatus "upi1_rx_dp(2)" )
				)
				( pin "U5D1.R8"
					( objectStatus "upi1_rx_dp(3)" )
				)
				( pin "U5D1.N10"
					( objectStatus "upi1_rx_dp(4)" )
				)
				( pin "U5D1.U10"
					( objectStatus "upi1_rx_dp(5)" )
				)
				( pin "U5D1.T11"
					( objectStatus "upi1_rx_dp(6)" )
				)
				( pin "U5D1.N12"
					( objectStatus "upi1_rx_dp(7)" )
				)
				( pin "U5D1.M13"
					( objectStatus "upi1_rx_dp(8)" )
				)
				( pin "U5D1.P13"
					( objectStatus "upi1_rx_dp(9)" )
				)
				( pin "U5D1.T15"
					( objectStatus "upi1_rx_dp(10)" )
				)
				( pin "U5D1.N16"
					( objectStatus "upi1_rx_dp(11)" )
				)
				( pin "U5D1.W16"
					( objectStatus "upi1_rx_dp(12)" )
				)
				( pin "U5D1.V17"
					( objectStatus "upi1_rx_dp(13)" )
				)
				( pin "U5D1.P19"
					( objectStatus "upi1_rx_dp(14)" )
				)
				( pin "U5D1.T19"
					( objectStatus "upi1_rx_dp(15)" )
				)
				( pin "U5D1.T21"
					( objectStatus "upi1_rx_dp(16)" )
				)
				( pin "U5D1.Y19"
					( objectStatus "upi1_rx_dp(17)" )
				)
				( pin "U5D1.W20"
					( objectStatus "upi1_rx_dp(18)" )
				)
				( pin "U5D1.AA20"
					( objectStatus "upi1_rx_dp(19)" )
				)
				( pin "U5D1.M3"
					( objectStatus "upi1_tx_dn(0)" )
				)
				( pin "U5D1.L4"
					( objectStatus "upi1_tx_dn(1)" )
				)
				( pin "U5D1.K5"
					( objectStatus "upi1_tx_dn(2)" )
				)
				( pin "U5D1.J6"
					( objectStatus "upi1_tx_dn(3)" )
				)
				( pin "U5D1.G6"
					( objectStatus "upi1_tx_dn(4)" )
				)
				( pin "U5D1.H7"
					( objectStatus "upi1_tx_dn(5)" )
				)
				( pin "U5D1.K9"
					( objectStatus "upi1_tx_dn(6)" )
				)
				( pin "U5D1.D9"
					( objectStatus "upi1_tx_dn(7)" )
				)
				( pin "U5D1.F11"
					( objectStatus "upi1_tx_dn(8)" )
				)
				( pin "U5D1.G10"
					( objectStatus "upi1_tx_dn(9)" )
				)
				( pin "U5D1.E12"
					( objectStatus "upi1_tx_dn(10)" )
				)
				( pin "U5D1.G14"
					( objectStatus "upi1_tx_dn(11)" )
				)
				( pin "U5D1.D15"
					( objectStatus "upi1_tx_dn(12)" )
				)
				( pin "U5D1.F15"
					( objectStatus "upi1_tx_dn(13)" )
				)
				( pin "U5D1.H17"
					( objectStatus "upi1_tx_dn(14)" )
				)
				( pin "U5D1.K19"
					( objectStatus "upi1_tx_dn(15)" )
				)
				( pin "U5D1.G18"
					( objectStatus "upi1_tx_dn(16)" )
				)
				( pin "U5D1.J20"
					( objectStatus "upi1_tx_dn(17)" )
				)
				( pin "U5D1.F21"
					( objectStatus "upi1_tx_dn(18)" )
				)
				( pin "U5D1.H21"
					( objectStatus "upi1_tx_dn(19)" )
				)
				( pin "U5D1.P3"
					( objectStatus "upi1_tx_dp(0)" )
				)
				( pin "U5D1.K3"
					( objectStatus "upi1_tx_dp(1)" )
				)
				( pin "U5D1.M5"
					( objectStatus "upi1_tx_dp(2)" )
				)
				( pin "U5D1.H5"
					( objectStatus "upi1_tx_dp(3)" )
				)
				( pin "U5D1.F7"
					( objectStatus "upi1_tx_dp(4)" )
				)
				( pin "U5D1.K7"
					( objectStatus "upi1_tx_dp(5)" )
				)
				( pin "U5D1.J8"
					( objectStatus "upi1_tx_dp(6)" )
				)
				( pin "U5D1.F9"
					( objectStatus "upi1_tx_dp(7)" )
				)
				( pin "U5D1.E10"
					( objectStatus "upi1_tx_dp(8)" )
				)
				( pin "U5D1.H9"
					( objectStatus "upi1_tx_dp(9)" )
				)
				( pin "U5D1.G12"
					( objectStatus "upi1_tx_dp(10)" )
				)
				( pin "U5D1.F13"
					( objectStatus "upi1_tx_dp(11)" )
				)
				( pin "U5D1.E14"
					( objectStatus "upi1_tx_dp(12)" )
				)
				( pin "U5D1.H15"
					( objectStatus "upi1_tx_dp(13)" )
				)
				( pin "U5D1.G16"
					( objectStatus "upi1_tx_dp(14)" )
				)
				( pin "U5D1.L18"
					( objectStatus "upi1_tx_dp(15)" )
				)
				( pin "U5D1.J18"
					( objectStatus "upi1_tx_dp(16)" )
				)
				( pin "U5D1.H19"
					( objectStatus "upi1_tx_dp(17)" )
				)
				( pin "U5D1.G20"
					( objectStatus "upi1_tx_dp(18)" )
				)
				( pin "U5D1.K21"
					( objectStatus "upi1_tx_dp(19)" )
				)
			)
			( gate "U5D1"
				( objectStatus "@baseboard_fab2_lib.baseboard_fab2(sch_1):page35_i3" )
				( pin "U5D1.DF23"
					( objectStatus "upi2_rx_dn(0)" )
				)
				( pin "U5D1.DE22"
					( objectStatus "upi2_rx_dn(1)" )
				)
				( pin "U5D1.DC22"
					( objectStatus "upi2_rx_dn(2)" )
				)
				( pin "U5D1.DB21"
					( objectStatus "upi2_rx_dn(3)" )
				)
				( pin "U5D1.DD19"
					( objectStatus "upi2_rx_dn(4)" )
				)
				( pin "U5D1.DA20"
					( objectStatus "upi2_rx_dn(5)" )
				)
				( pin "U5D1.CW20"
					( objectStatus "upi2_rx_dn(6)" )
				)
				( pin "U5D1.CV19"
					( objectStatus "upi2_rx_dn(7)" )
				)
				( pin "U5D1.CT21"
					( objectStatus "upi2_rx_dn(8)" )
				)
				( pin "U5D1.CR18"
					( objectStatus "upi2_rx_dn(9)" )
				)
				( pin "U5D1.CN20"
					( objectStatus "upi2_rx_dn(10)" )
				)
				( pin "U5D1.CP21"
					( objectStatus "upi2_rx_dn(11)" )
				)
				( pin "U5D1.CL16"
					( objectStatus "upi2_rx_dn(12)" )
				)
				( pin "U5D1.CJ18"
					( objectStatus "upi2_rx_dn(13)" )
				)
				( pin "U5D1.CH17"
					( objectStatus "upi2_rx_dn(14)" )
				)
				( pin "U5D1.CE16"
					( objectStatus "upi2_rx_dn(15)" )
				)
				( pin "U5D1.CD15"
					( objectStatus "upi2_rx_dn(16)" )
				)
				( pin "U5D1.CF17"
					( objectStatus "upi2_rx_dn(17)" )
				)
				( pin "U5D1.CB15"
					( objectStatus "upi2_rx_dn(18)" )
				)
				( pin "U5D1.BY17"
					( objectStatus "upi2_rx_dn(19)" )
				)
				( pin "U5D1.DG22"
					( objectStatus "upi2_rx_dp(0)" )
				)
				( pin "U5D1.DD21"
					( objectStatus "upi2_rx_dp(1)" )
				)
				( pin "U5D1.DA22"
					( objectStatus "upi2_rx_dp(2)" )
				)
				( pin "U5D1.DC20"
					( objectStatus "upi2_rx_dp(3)" )
				)
				( pin "U5D1.DB19"
					( objectStatus "upi2_rx_dp(4)" )
				)
				( pin "U5D1.CY19"
					( objectStatus "upi2_rx_dp(5)" )
				)
				( pin "U5D1.CU20"
					( objectStatus "upi2_rx_dp(6)" )
				)
				( pin "U5D1.CW18"
					( objectStatus "upi2_rx_dp(7)" )
				)
				( pin "U5D1.CR20"
					( objectStatus "upi2_rx_dp(8)" )
				)
				( pin "U5D1.CN18"
					( objectStatus "upi2_rx_dp(9)" )
				)
				( pin "U5D1.CP19"
					( objectStatus "upi2_rx_dp(10)" )
				)
				( pin "U5D1.CM21"
					( objectStatus "upi2_rx_dp(11)" )
				)
				( pin "U5D1.CJ16"
					( objectStatus "upi2_rx_dp(12)" )
				)
				( pin "U5D1.CK17"
					( objectStatus "upi2_rx_dp(13)" )
				)
				( pin "U5D1.CG16"
					( objectStatus "upi2_rx_dp(14)" )
				)
				( pin "U5D1.CF15"
					( objectStatus "upi2_rx_dp(15)" )
				)
				( pin "U5D1.CC14"
					( objectStatus "upi2_rx_dp(16)" )
				)
				( pin "U5D1.CD17"
					( objectStatus "upi2_rx_dp(17)" )
				)
				( pin "U5D1.BY15"
					( objectStatus "upi2_rx_dp(18)" )
				)
				( pin "U5D1.CA16"
					( objectStatus "upi2_rx_dp(19)" )
				)
				( pin "U5D1.DT21"
					( objectStatus "upi2_tx_dn(0)" )
				)
				( pin "U5D1.DM21"
					( objectStatus "upi2_tx_dn(1)" )
				)
				( pin "U5D1.DL20"
					( objectStatus "upi2_tx_dn(2)" )
				)
				( pin "U5D1.DG20"
					( objectStatus "upi2_tx_dn(3)" )
				)
				( pin "U5D1.DH19"
					( objectStatus "upi2_tx_dn(4)" )
				)
				( pin "U5D1.DK17"
					( objectStatus "upi2_tx_dn(5)" )
				)
				( pin "U5D1.DG18"
					( objectStatus "upi2_tx_dn(6)" )
				)
				( pin "U5D1.DD17"
					( objectStatus "upi2_tx_dn(7)" )
				)
				( pin "U5D1.DF15"
					( objectStatus "upi2_tx_dn(8)" )
				)
				( pin "U5D1.DC16"
					( objectStatus "upi2_tx_dn(9)" )
				)
				( pin "U5D1.DA16"
					( objectStatus "upi2_tx_dn(10)" )
				)
				( pin "U5D1.CW14"
					( objectStatus "upi2_tx_dn(11)" )
				)
				( pin "U5D1.CU14"
					( objectStatus "upi2_tx_dn(12)" )
				)
				( pin "U5D1.CM13"
					( objectStatus "upi2_tx_dn(13)" )
				)
				( pin "U5D1.CJ14"
					( objectStatus "upi2_tx_dn(14)" )
				)
				( pin "U5D1.CF13"
					( objectStatus "upi2_tx_dn(15)" )
				)
				( pin "U5D1.CH11"
					( objectStatus "upi2_tx_dn(16)" )
				)
				( pin "U5D1.CE12"
					( objectStatus "upi2_tx_dn(17)" )
				)
				( pin "U5D1.CC10"
					( objectStatus "upi2_tx_dn(18)" )
				)
				( pin "U5D1.CC12"
					( objectStatus "upi2_tx_dn(19)" )
				)
				( pin "U5D1.DP21"
					( objectStatus "upi2_tx_dp(0)" )
				)
				( pin "U5D1.DN20"
					( objectStatus "upi2_tx_dp(1)" )
				)
				( pin "U5D1.DK19"
					( objectStatus "upi2_tx_dp(2)" )
				)
				( pin "U5D1.DJ20"
					( objectStatus "upi2_tx_dp(3)" )
				)
				( pin "U5D1.DJ18"
					( objectStatus "upi2_tx_dp(4)" )
				)
				( pin "U5D1.DH17"
					( objectStatus "upi2_tx_dp(5)" )
				)
				( pin "U5D1.DF17"
					( objectStatus "upi2_tx_dp(6)" )
				)
				( pin "U5D1.DE16"
					( objectStatus "upi2_tx_dp(7)" )
				)
				( pin "U5D1.DD15"
					( objectStatus "upi2_tx_dp(8)" )
				)
				( pin "U5D1.DB15"
					( objectStatus "upi2_tx_dp(9)" )
				)
				( pin "U5D1.CW16"
					( objectStatus "upi2_tx_dp(10)" )
				)
				( pin "U5D1.CV13"
					( objectStatus "upi2_tx_dp(11)" )
				)
				( pin "U5D1.CR14"
					( objectStatus "upi2_tx_dp(12)" )
				)
				( pin "U5D1.CK13"
					( objectStatus "upi2_tx_dp(13)" )
				)
				( pin "U5D1.CH13"
					( objectStatus "upi2_tx_dp(14)" )
				)
				( pin "U5D1.CG12"
					( objectStatus "upi2_tx_dp(15)" )
				)
				( pin "U5D1.CF11"
					( objectStatus "upi2_tx_dp(16)" )
				)
				( pin "U5D1.CD11"
					( objectStatus "upi2_tx_dp(17)" )
				)
				( pin "U5D1.CB11"
					( objectStatus "upi2_tx_dp(18)" )
				)
				( pin "U5D1.CA12"
					( objectStatus "upi2_tx_dp(19)" )
				)
			)
			( gate "U5D1"
				( objectStatus "@baseboard_fab2_lib.baseboard_fab2(sch_1):page36_i15" )
				( pin "U5D1.CH23"
					( objectStatus "rsvd(92)" )
				)
				( pin "U5D1.CH21"
					( objectStatus "rsvd(93)" )
				)
				( pin "U5D1.CG82"
					( objectStatus "rsvd(94)" )
				)
				( pin "U5D1.CG78"
					( objectStatus "rsvd(95)" )
				)
				( pin "U5D1.CG26"
					( objectStatus "rsvd(96)" )
				)
				( pin "U5D1.CG24"
					( objectStatus "rsvd(97)" )
				)
				( pin "U5D1.CG20"
					( objectStatus "rsvd(98)" )
				)
				( pin "U5D1.CG10"
					( objectStatus "rsvd(99)" )
				)
				( pin "U5D1.CF81"
					( objectStatus "rsvd(100)" )
				)
				( pin "U5D1.CF79"
					( objectStatus "rsvd(101)" )
				)
				( pin "U5D1.CF23"
					( objectStatus "rsvd(102)" )
				)
				( pin "U5D1.CF21"
					( objectStatus "rsvd(103)" )
				)
				( pin "U5D1.CF19"
					( objectStatus "rsvd(104)" )
				)
				( pin "U5D1.CE80"
					( objectStatus "rsvd(105)" )
				)
				( pin "U5D1.CE78"
					( objectStatus "rsvd(106)" )
				)
				( pin "U5D1.CE22"
					( objectStatus "rsvd(107)" )
				)
				( pin "U5D1.CD25"
					( objectStatus "rsvd(108)" )
				)
				( pin "U5D1.CD21"
					( objectStatus "rsvd(109)" )
				)
				( pin "U5D1.CD19"
					( objectStatus "rsvd(110)" )
				)
				( pin "U5D1.CC6"
					( objectStatus "rsvd(111)" )
				)
				( pin "U5D1.CC20"
					( objectStatus "rsvd(112)" )
				)
				( pin "U5D1.CB5"
					( objectStatus "rsvd(113)" )
				)
				( pin "U5D1.CB25"
					( objectStatus "rsvd(114)" )
				)
				( pin "U5D1.CB21"
					( objectStatus "rsvd(115)" )
				)
				( pin "U5D1.CB19"
					( objectStatus "rsvd(116)" )
				)
				( pin "U5D1.CA24"
					( objectStatus "rsvd(117)" )
				)
				( pin "U5D1.CA22"
					( objectStatus "rsvd(118)" )
				)
				( pin "U5D1.BY25"
					( objectStatus "rsvd(119)" )
				)
				( pin "U5D1.BY19"
					( objectStatus "rsvd(120)" )
				)
				( pin "U5D1.BW22"
					( objectStatus "rsvd(121)" )
				)
				( pin "U5D1.BW20"
					( objectStatus "rsvd(122)" )
				)
				( pin "U5D1.BW10"
					( objectStatus "rsvd(123)" )
				)
				( pin "U5D1.BV23"
					( objectStatus "rsvd(124)" )
				)
				( pin "U5D1.BV21"
					( objectStatus "rsvd(125)" )
				)
				( pin "U5D1.BV19"
					( objectStatus "rsvd(126)" )
				)
				( pin "U5D1.BU22"
					( objectStatus "rsvd(127)" )
				)
				( pin "U5D1.BU20"
					( objectStatus "rsvd(128)" )
				)
				( pin "U5D1.BU18"
					( objectStatus "rsvd(129)" )
				)
				( pin "U5D1.BR24"
					( objectStatus "rsvd(130)" )
				)
				( pin "U5D1.BR22"
					( objectStatus "rsvd(131)" )
				)
				( pin "U5D1.BP21"
					( objectStatus "rsvd(132)" )
				)
				( pin "U5D1.BP17"
					( objectStatus "rsvd(133)" )
				)
				( pin "U5D1.BN18"
					( objectStatus "rsvd(134)" )
				)
				( pin "U5D1.BM19"
					( objectStatus "rsvd(135)" )
				)
				( pin "U5D1.BM17"
					( objectStatus "rsvd(136)" )
				)
				( pin "U5D1.BL20"
					( objectStatus "rsvd(137)" )
				)
				( pin "U5D1.BL18"
					( objectStatus "rsvd(138)" )
				)
				( pin "U5D1.BK17"
					( objectStatus "rsvd(139)" )
				)
				( pin "U5D1.BJ20"
					( objectStatus "rsvd(140)" )
				)
				( pin "U5D1.BJ18"
					( objectStatus "rsvd(141)" )
				)
				( pin "U5D1.BJ16"
					( objectStatus "rsvd(142)" )
				)
				( pin "U5D1.BH19"
					( objectStatus "rsvd(143)" )
				)
				( pin "U5D1.BG20"
					( objectStatus "rsvd(144)" )
				)
				( pin "U5D1.BG18"
					( objectStatus "rsvd(145)" )
				)
				( pin "U5D1.BF21"
					( objectStatus "rsvd(146)" )
				)
				( pin "U5D1.BE22"
					( objectStatus "rsvd(147)" )
				)
				( pin "U5D1.BE20"
					( objectStatus "rsvd(148)" )
				)
				( pin "U5D1.BE18"
					( objectStatus "rsvd(149)" )
				)
				( pin "U5D1.BD69"
					( objectStatus "rsvd(150)" )
				)
				( pin "U5D1.BD67"
					( objectStatus "rsvd(151)" )
				)
				( pin "U5D1.BD65"
					( objectStatus "rsvd(152)" )
				)
				( pin "U5D1.BD25"
					( objectStatus "rsvd(153)" )
				)
				( pin "U5D1.BD19"
					( objectStatus "rsvd(154)" )
				)
				( pin "U5D1.BD17"
					( objectStatus "rsvd(155)" )
				)
				( pin "U5D1.BC68"
					( objectStatus "rsvd(156)" )
				)
				( pin "U5D1.BC66"
					( objectStatus "rsvd(157)" )
				)
				( pin "U5D1.BC64"
					( objectStatus "rsvd(158)" )
				)
				( pin "U5D1.BC22"
					( objectStatus "rsvd(159)" )
				)
				( pin "U5D1.BC20"
					( objectStatus "rsvd(160)" )
				)
				( pin "U5D1.BC18"
					( objectStatus "rsvd(161)" )
				)
				( pin "U5D1.BC14"
					( objectStatus "rsvd(162)" )
				)
				( pin "U5D1.BB67"
					( objectStatus "rsvd(163)" )
				)
				( pin "U5D1.BB65"
					( objectStatus "rsvd(164)" )
				)
				( pin "U5D1.BB25"
					( objectStatus "rsvd(165)" )
				)
				( pin "U5D1.BB21"
					( objectStatus "rsvd(166)" )
				)
				( pin "U5D1.BB17"
					( objectStatus "rsvd(167)" )
				)
				( pin "U5D1.BB15"
					( objectStatus "rsvd(168)" )
				)
				( pin "U5D1.BB13"
					( objectStatus "rsvd(169)" )
				)
				( pin "U5D1.BA82"
					( objectStatus "rsvd(170)" )
				)
				( pin "U5D1.BA78"
					( objectStatus "rsvd(171)" )
				)
				( pin "U5D1.AY83"
					( objectStatus "rsvd(255)" )
				)
			)
			( gate "U5D1"
				( objectStatus "@baseboard_fab2_lib.baseboard_fab2(sch_1):page36_i16" )
				( pin "U5D1.CL24"
					( objectStatus "rsvd(81)" )
				)
				( pin "U5D1.CK77"
					( objectStatus "rsvd(82)" )
				)
				( pin "U5D1.CK25"
					( objectStatus "rsvd(83)" )
				)
				( pin "U5D1.CK23"
					( objectStatus "rsvd(84)" )
				)
				( pin "U5D1.CK19"
					( objectStatus "rsvd(85)" )
				)
				( pin "U5D1.CJ26"
					( objectStatus "rsvd(86)" )
				)
				( pin "U5D1.CJ24"
					( objectStatus "rsvd(87)" )
				)
				( pin "U5D1.CJ22"
					( objectStatus "rsvd(88)" )
				)
				( pin "U5D1.CJ20"
					( objectStatus "rsvd(89)" )
				)
				( pin "U5D1.CH77"
					( objectStatus "rsvd(90)" )
				)
				( pin "U5D1.CH25"
					( objectStatus "rsvd(91)" )
				)
				( pin "U5D1.AR16"
					( objectStatus "test_6" )
				)
				( pin "U5D1.AU18"
					( objectStatus "test_7" )
				)
				( pin "U5D1.AW16"
					( objectStatus "test_8" )
				)
				( pin "U5D1.AW20"
					( objectStatus "test_9" )
				)
				( pin "U5D1.AW22"
					( objectStatus "test_10" )
				)
			)
			( gate "R5D5"
				( objectStatus "@baseboard_fab2_lib.baseboard_fab2(sch_1):page37_i303" )
				( pin "R5D5.1"
					( objectStatus "a" )
				)
				( pin "R5D5.2"
					( objectStatus "b" )
				)
			)
			( gate "R5P1"
				( objectStatus "@baseboard_fab2_lib.baseboard_fab2(sch_1):page37_i309" )
				( pin "R5P1.1"
					( objectStatus "a" )
				)
				( pin "R5P1.2"
					( objectStatus "b" )
				)
			)
			( gate "U5D1"
				( objectStatus "@baseboard_fab2_lib.baseboard_fab2(sch_1):page37_i310" )
				( pin "U5D1.BN78"
					( objectStatus "vccin(130)" )
				)
				( pin "U5D1.BN76"
					( objectStatus "vccin(131)" )
				)
				( pin "U5D1.BN74"
					( objectStatus "vccin(132)" )
				)
				( pin "U5D1.BN72"
					( objectStatus "vccin(133)" )
				)
				( pin "U5D1.BN70"
					( objectStatus "vccin(134)" )
				)
				( pin "U5D1.BN68"
					( objectStatus "vccin(135)" )
				)
				( pin "U5D1.BN66"
					( objectStatus "vccin(136)" )
				)
				( pin "U5D1.BN64"
					( objectStatus "vccin(137)" )
				)
				( pin "U5D1.BN62"
					( objectStatus "vccin(138)" )
				)
				( pin "U5D1.BN60"
					( objectStatus "vccin(139)" )
				)
				( pin "U5D1.BM83"
					( objectStatus "vccin(140)" )
				)
				( pin "U5D1.BM81"
					( objectStatus "vccin(141)" )
				)
				( pin "U5D1.BM79"
					( objectStatus "vccin(142)" )
				)
				( pin "U5D1.BM77"
					( objectStatus "vccin(143)" )
				)
				( pin "U5D1.BM75"
					( objectStatus "vccin(144)" )
				)
				( pin "U5D1.BM73"
					( objectStatus "vccin(145)" )
				)
				( pin "U5D1.BM71"
					( objectStatus "vccin(146)" )
				)
				( pin "U5D1.BM69"
					( objectStatus "vccin(147)" )
				)
				( pin "U5D1.BM67"
					( objectStatus "vccin(148)" )
				)
				( pin "U5D1.BM65"
					( objectStatus "vccin(149)" )
				)
				( pin "U5D1.BM63"
					( objectStatus "vccin(150)" )
				)
				( pin "U5D1.BM61"
					( objectStatus "vccin(151)" )
				)
				( pin "U5D1.BL84"
					( objectStatus "vccin(152)" )
				)
				( pin "U5D1.BL62"
					( objectStatus "vccin(153)" )
				)
				( pin "U5D1.BL60"
					( objectStatus "vccin(154)" )
				)
				( pin "U5D1.BK83"
					( objectStatus "vccin(155)" )
				)
				( pin "U5D1.BK81"
					( objectStatus "vccin(156)" )
				)
				( pin "U5D1.BK79"
					( objectStatus "vccin(157)" )
				)
				( pin "U5D1.BK77"
					( objectStatus "vccin(158)" )
				)
				( pin "U5D1.BK75"
					( objectStatus "vccin(159)" )
				)
				( pin "U5D1.BK73"
					( objectStatus "vccin(160)" )
				)
				( pin "U5D1.BK71"
					( objectStatus "vccin(161)" )
				)
				( pin "U5D1.BK69"
					( objectStatus "vccin(162)" )
				)
				( pin "U5D1.BK67"
					( objectStatus "vccin(163)" )
				)
				( pin "U5D1.BK65"
					( objectStatus "vccin(164)" )
				)
				( pin "U5D1.BK63"
					( objectStatus "vccin(165)" )
				)
				( pin "U5D1.BK61"
					( objectStatus "vccin(166)" )
				)
				( pin "U5D1.BJ84"
					( objectStatus "vccin(167)" )
				)
				( pin "U5D1.BJ82"
					( objectStatus "vccin(168)" )
				)
				( pin "U5D1.BJ80"
					( objectStatus "vccin(169)" )
				)
				( pin "U5D1.BJ78"
					( objectStatus "vccin(170)" )
				)
				( pin "U5D1.BJ76"
					( objectStatus "vccin(171)" )
				)
				( pin "U5D1.BJ74"
					( objectStatus "vccin(172)" )
				)
				( pin "U5D1.BJ72"
					( objectStatus "vccin(173)" )
				)
				( pin "U5D1.BJ70"
					( objectStatus "vccin(174)" )
				)
				( pin "U5D1.BJ68"
					( objectStatus "vccin(175)" )
				)
				( pin "U5D1.BJ66"
					( objectStatus "vccin(176)" )
				)
				( pin "U5D1.BJ64"
					( objectStatus "vccin(177)" )
				)
				( pin "U5D1.BJ62"
					( objectStatus "vccin(178)" )
				)
				( pin "U5D1.BJ60"
					( objectStatus "vccin(179)" )
				)
				( pin "U5D1.BH83"
					( objectStatus "vccin(180)" )
				)
				( pin "U5D1.BH81"
					( objectStatus "vccin(181)" )
				)
				( pin "U5D1.BH79"
					( objectStatus "vccin(182)" )
				)
				( pin "U5D1.BH77"
					( objectStatus "vccin(183)" )
				)
				( pin "U5D1.BH75"
					( objectStatus "vccin(184)" )
				)
				( pin "U5D1.BH73"
					( objectStatus "vccin(185)" )
				)
				( pin "U5D1.BH71"
					( objectStatus "vccin(186)" )
				)
				( pin "U5D1.BH69"
					( objectStatus "vccin(187)" )
				)
				( pin "U5D1.BH67"
					( objectStatus "vccin(188)" )
				)
				( pin "U5D1.BH65"
					( objectStatus "vccin(189)" )
				)
				( pin "U5D1.BH63"
					( objectStatus "vccin(190)" )
				)
				( pin "U5D1.BH61"
					( objectStatus "vccin(191)" )
				)
				( pin "U5D1.BG84"
					( objectStatus "vccin(192)" )
				)
				( pin "U5D1.BG70"
					( objectStatus "vccin(193)" )
				)
				( pin "U5D1.BG68"
					( objectStatus "vccin(194)" )
				)
				( pin "U5D1.BG66"
					( objectStatus "vccin(195)" )
				)
				( pin "U5D1.BG64"
					( objectStatus "vccin(196)" )
				)
				( pin "U5D1.BG62"
					( objectStatus "vccin(197)" )
				)
				( pin "U5D1.BG60"
					( objectStatus "vccin(198)" )
				)
				( pin "U5D1.BF85"
					( objectStatus "vccin(199)" )
				)
				( pin "U5D1.BF83"
					( objectStatus "vccin(200)" )
				)
				( pin "U5D1.BF81"
					( objectStatus "vccin(201)" )
				)
				( pin "U5D1.BF79"
					( objectStatus "vccin(202)" )
				)
				( pin "U5D1.BF77"
					( objectStatus "vccin(203)" )
				)
				( pin "U5D1.BF75"
					( objectStatus "vccin(204)" )
				)
				( pin "U5D1.BF73"
					( objectStatus "vccin(205)" )
				)
				( pin "U5D1.BF61"
					( objectStatus "vccin(206)" )
				)
				( pin "U5D1.BE84"
					( objectStatus "vccin(207)" )
				)
				( pin "U5D1.BE82"
					( objectStatus "vccin(208)" )
				)
				( pin "U5D1.BE80"
					( objectStatus "vccin(209)" )
				)
				( pin "U5D1.BE78"
					( objectStatus "vccin(210)" )
				)
				( pin "U5D1.BE76"
					( objectStatus "vccin(211)" )
				)
				( pin "U5D1.BE74"
					( objectStatus "vccin(212)" )
				)
				( pin "U5D1.BE72"
					( objectStatus "vccin(213)" )
				)
				( pin "U5D1.BE62"
					( objectStatus "vccin(214)" )
				)
				( pin "U5D1.BE60"
					( objectStatus "vccin(215)" )
				)
				( pin "U5D1.BD85"
					( objectStatus "vccin(216)" )
				)
				( pin "U5D1.BD83"
					( objectStatus "vccin(217)" )
				)
				( pin "U5D1.BD81"
					( objectStatus "vccin(218)" )
				)
				( pin "U5D1.BD79"
					( objectStatus "vccin(219)" )
				)
				( pin "U5D1.BD77"
					( objectStatus "vccin(220)" )
				)
				( pin "U5D1.BD75"
					( objectStatus "vccin(221)" )
				)
				( pin "U5D1.BD73"
					( objectStatus "vccin(222)" )
				)
				( pin "U5D1.BD61"
					( objectStatus "vccin(223)" )
				)
				( pin "U5D1.BC84"
					( objectStatus "vccin(224)" )
				)
				( pin "U5D1.BC62"
					( objectStatus "vccin(225)" )
				)
				( pin "U5D1.BC60"
					( objectStatus "vccin(226)" )
				)
				( pin "U5D1.BB85"
					( objectStatus "vccin(227)" )
				)
				( pin "U5D1.BB61"
					( objectStatus "vccin(228)" )
				)
				( pin "U5D1.BA60"
					( objectStatus "vccin(229)" )
				)
				( pin "U5D1.AY61"
					( objectStatus "vccin(230)" )
				)
				( pin "U5D1.AW60"
					( objectStatus "vccin(231)" )
				)
				( pin "U5D1.AV61"
					( objectStatus "vccin(232)" )
				)
				( pin "U5D1.AV59"
					( objectStatus "vccin(233)" )
				)
				( pin "U5D1.AU60"
					( objectStatus "vccin(234)" )
				)
				( pin "U5D1.AU58"
					( objectStatus "vccin(235)" )
				)
				( pin "U5D1.AT59"
					( objectStatus "vccin(236)" )
				)
				( pin "U5D1.AT57"
					( objectStatus "vccin(237)" )
				)
				( pin "U5D1.AR58"
					( objectStatus "vccin(238)" )
				)
				( pin "U5D1.AR56"
					( objectStatus "vccin(239)" )
				)
				( pin "U5D1.AP57"
					( objectStatus "vccin(240)" )
				)
				( pin "U5D1.AP55"
					( objectStatus "vccin(241)" )
				)
				( pin "U5D1.AN56"
					( objectStatus "vccin(242)" )
				)
				( pin "U5D1.AN54"
					( objectStatus "vccin(243)" )
				)
				( pin "U5D1.AN32"
					( objectStatus "vccin(244)" )
				)
				( pin "U5D1.AM55"
					( objectStatus "vccin(245)" )
				)
				( pin "U5D1.AM53"
					( objectStatus "vccin(246)" )
				)
				( pin "U5D1.AM33"
					( objectStatus "vccin(247)" )
				)
				( pin "U5D1.AL54"
					( objectStatus "vccin(248)" )
				)
				( pin "U5D1.AL52"
					( objectStatus "vccin(249)" )
				)
				( pin "U5D1.AL50"
					( objectStatus "vccin(250)" )
				)
				( pin "U5D1.AL48"
					( objectStatus "vccin(251)" )
				)
				( pin "U5D1.AL46"
					( objectStatus "vccin(252)" )
				)
				( pin "U5D1.AL34"
					( objectStatus "vccin(253)" )
				)
				( pin "U5D1.AK53"
					( objectStatus "vccin(254)" )
				)
				( pin "U5D1.AK51"
					( objectStatus "vccin(255)" )
				)
				( pin "U5D1.AK49"
					( objectStatus "vccin(256)" )
				)
				( pin "U5D1.AK47"
					( objectStatus "vccin(257)" )
				)
				( pin "U5D1.AK45"
					( objectStatus "vccin(258)" )
				)
				( pin "U5D1.AK35"
					( objectStatus "vccin(259)" )
				)
				( pin "U5D1.AJ36"
					( objectStatus "vccin(260)" )
				)
				( pin "U5D1.AH41"
					( objectStatus "vccin(261)" )
				)
				( pin "U5D1.AH39"
					( objectStatus "vccin(262)" )
				)
				( pin "U5D1.AH37"
					( objectStatus "vccin(263)" )
				)
				( pin "U5D1.AG42"
					( objectStatus "vccin(264)" )
				)
				( pin "U5D1.AG40"
					( objectStatus "vccin(265)" )
				)
				( pin "U5D1.AG38"
					( objectStatus "vccin(266)" )
				)
				( pin "U5D1.AF43"
					( objectStatus "vccin(267)" )
				)
			)
			( gate "U5D1"
				( objectStatus "@baseboard_fab2_lib.baseboard_fab2(sch_1):page37_i311" )
				( pin "U5D1.CY49"
					( objectStatus "vccin(0)" )
				)
				( pin "U5D1.CY47"
					( objectStatus "vccin(1)" )
				)
				( pin "U5D1.CW50"
					( objectStatus "vccin(2)" )
				)
				( pin "U5D1.CW48"
					( objectStatus "vccin(3)" )
				)
				( pin "U5D1.CW46"
					( objectStatus "vccin(4)" )
				)
				( pin "U5D1.CV51"
					( objectStatus "vccin(5)" )
				)
				( pin "U5D1.CU54"
					( objectStatus "vccin(6)" )
				)
				( pin "U5D1.CU52"
					( objectStatus "vccin(7)" )
				)
				( pin "U5D1.CU42"
					( objectStatus "vccin(8)" )
				)
				( pin "U5D1.CU40"
					( objectStatus "vccin(9)" )
				)
				( pin "U5D1.CU38"
					( objectStatus "vccin(10)" )
				)
				( pin "U5D1.CT55"
					( objectStatus "vccin(11)" )
				)
				( pin "U5D1.CT53"
					( objectStatus "vccin(12)" )
				)
				( pin "U5D1.CT41"
					( objectStatus "vccin(13)" )
				)
				( pin "U5D1.CT39"
					( objectStatus "vccin(14)" )
				)
				( pin "U5D1.CT37"
					( objectStatus "vccin(15)" )
				)
				( pin "U5D1.CR56"
					( objectStatus "vccin(16)" )
				)
				( pin "U5D1.CR54"
					( objectStatus "vccin(17)" )
				)
				( pin "U5D1.CR34"
					( objectStatus "vccin(18)" )
				)
				( pin "U5D1.CP57"
					( objectStatus "vccin(19)" )
				)
				( pin "U5D1.CP55"
					( objectStatus "vccin(20)" )
				)
				( pin "U5D1.CP33"
					( objectStatus "vccin(21)" )
				)
				( pin "U5D1.CN58"
					( objectStatus "vccin(22)" )
				)
				( pin "U5D1.CN56"
					( objectStatus "vccin(23)" )
				)
				( pin "U5D1.CM59"
					( objectStatus "vccin(24)" )
				)
				( pin "U5D1.CM57"
					( objectStatus "vccin(25)" )
				)
				( pin "U5D1.CL60"
					( objectStatus "vccin(26)" )
				)
				( pin "U5D1.CL58"
					( objectStatus "vccin(27)" )
				)
				( pin "U5D1.CK61"
					( objectStatus "vccin(28)" )
				)
				( pin "U5D1.CK59"
					( objectStatus "vccin(29)" )
				)
				( pin "U5D1.CJ60"
					( objectStatus "vccin(30)" )
				)
				( pin "U5D1.CH85"
					( objectStatus "vccin(31)" )
				)
				( pin "U5D1.CH61"
					( objectStatus "vccin(32)" )
				)
				( pin "U5D1.CG84"
					( objectStatus "vccin(33)" )
				)
				( pin "U5D1.CG60"
					( objectStatus "vccin(34)" )
				)
				( pin "U5D1.CF85"
					( objectStatus "vccin(35)" )
				)
				( pin "U5D1.CF61"
					( objectStatus "vccin(36)" )
				)
				( pin "U5D1.CE84"
					( objectStatus "vccin(37)" )
				)
				( pin "U5D1.CE60"
					( objectStatus "vccin(38)" )
				)
				( pin "U5D1.CD85"
					( objectStatus "vccin(39)" )
				)
				( pin "U5D1.CD83"
					( objectStatus "vccin(40)" )
				)
				( pin "U5D1.CD61"
					( objectStatus "vccin(41)" )
				)
				( pin "U5D1.CC84"
					( objectStatus "vccin(42)" )
				)
				( pin "U5D1.CC62"
					( objectStatus "vccin(43)" )
				)
				( pin "U5D1.CC60"
					( objectStatus "vccin(44)" )
				)
				( pin "U5D1.CB83"
					( objectStatus "vccin(45)" )
				)
				( pin "U5D1.CB81"
					( objectStatus "vccin(46)" )
				)
				( pin "U5D1.CB79"
					( objectStatus "vccin(47)" )
				)
				( pin "U5D1.CB77"
					( objectStatus "vccin(48)" )
				)
				( pin "U5D1.CB75"
					( objectStatus "vccin(49)" )
				)
				( pin "U5D1.CB73"
					( objectStatus "vccin(50)" )
				)
				( pin "U5D1.CB61"
					( objectStatus "vccin(51)" )
				)
				( pin "U5D1.CA84"
					( objectStatus "vccin(52)" )
				)
				( pin "U5D1.CA82"
					( objectStatus "vccin(53)" )
				)
				( pin "U5D1.CA80"
					( objectStatus "vccin(54)" )
				)
				( pin "U5D1.CA78"
					( objectStatus "vccin(55)" )
				)
				( pin "U5D1.CA76"
					( objectStatus "vccin(56)" )
				)
				( pin "U5D1.CA74"
					( objectStatus "vccin(57)" )
				)
				( pin "U5D1.CA72"
					( objectStatus "vccin(58)" )
				)
				( pin "U5D1.CA62"
					( objectStatus "vccin(59)" )
				)
				( pin "U5D1.CA60"
					( objectStatus "vccin(60)" )
				)
				( pin "U5D1.BY83"
					( objectStatus "vccin(61)" )
				)
				( pin "U5D1.BY81"
					( objectStatus "vccin(62)" )
				)
				( pin "U5D1.BY79"
					( objectStatus "vccin(63)" )
				)
				( pin "U5D1.BY77"
					( objectStatus "vccin(64)" )
				)
				( pin "U5D1.BY75"
					( objectStatus "vccin(65)" )
				)
				( pin "U5D1.BY73"
					( objectStatus "vccin(66)" )
				)
				( pin "U5D1.BY61"
					( objectStatus "vccin(67)" )
				)
				( pin "U5D1.BW84"
					( objectStatus "vccin(68)" )
				)
				( pin "U5D1.BW70"
					( objectStatus "vccin(69)" )
				)
				( pin "U5D1.BW68"
					( objectStatus "vccin(70)" )
				)
				( pin "U5D1.BW66"
					( objectStatus "vccin(71)" )
				)
				( pin "U5D1.BW64"
					( objectStatus "vccin(72)" )
				)
				( pin "U5D1.BW62"
					( objectStatus "vccin(73)" )
				)
				( pin "U5D1.BW60"
					( objectStatus "vccin(74)" )
				)
				( pin "U5D1.BV83"
					( objectStatus "vccin(75)" )
				)
				( pin "U5D1.BV81"
					( objectStatus "vccin(76)" )
				)
				( pin "U5D1.BV79"
					( objectStatus "vccin(77)" )
				)
				( pin "U5D1.BV77"
					( objectStatus "vccin(78)" )
				)
				( pin "U5D1.BV75"
					( objectStatus "vccin(79)" )
				)
				( pin "U5D1.BV73"
					( objectStatus "vccin(80)" )
				)
				( pin "U5D1.BV71"
					( objectStatus "vccin(81)" )
				)
				( pin "U5D1.BV69"
					( objectStatus "vccin(82)" )
				)
				( pin "U5D1.BV67"
					( objectStatus "vccin(83)" )
				)
				( pin "U5D1.BV65"
					( objectStatus "vccin(84)" )
				)
				( pin "U5D1.BV63"
					( objectStatus "vccin(85)" )
				)
				( pin "U5D1.BV61"
					( objectStatus "vccin(86)" )
				)
				( pin "U5D1.BU84"
					( objectStatus "vccin(87)" )
				)
				( pin "U5D1.BU82"
					( objectStatus "vccin(88)" )
				)
				( pin "U5D1.BU80"
					( objectStatus "vccin(89)" )
				)
				( pin "U5D1.BU78"
					( objectStatus "vccin(90)" )
				)
				( pin "U5D1.BU76"
					( objectStatus "vccin(91)" )
				)
				( pin "U5D1.BU74"
					( objectStatus "vccin(92)" )
				)
				( pin "U5D1.BU72"
					( objectStatus "vccin(93)" )
				)
				( pin "U5D1.BU70"
					( objectStatus "vccin(94)" )
				)
				( pin "U5D1.BU68"
					( objectStatus "vccin(95)" )
				)
				( pin "U5D1.BU66"
					( objectStatus "vccin(96)" )
				)
				( pin "U5D1.BU64"
					( objectStatus "vccin(97)" )
				)
				( pin "U5D1.BU62"
					( objectStatus "vccin(98)" )
				)
				( pin "U5D1.BU60"
					( objectStatus "vccin(99)" )
				)
				( pin "U5D1.BT83"
					( objectStatus "vccin(100)" )
				)
				( pin "U5D1.BT81"
					( objectStatus "vccin(101)" )
				)
				( pin "U5D1.BT79"
					( objectStatus "vccin(102)" )
				)
				( pin "U5D1.BT77"
					( objectStatus "vccin(103)" )
				)
				( pin "U5D1.BT75"
					( objectStatus "vccin(104)" )
				)
				( pin "U5D1.BT73"
					( objectStatus "vccin(105)" )
				)
				( pin "U5D1.BT71"
					( objectStatus "vccin(106)" )
				)
				( pin "U5D1.BT69"
					( objectStatus "vccin(107)" )
				)
				( pin "U5D1.BT67"
					( objectStatus "vccin(108)" )
				)
				( pin "U5D1.BT65"
					( objectStatus "vccin(109)" )
				)
				( pin "U5D1.BT63"
					( objectStatus "vccin(110)" )
				)
				( pin "U5D1.BT61"
					( objectStatus "vccin(111)" )
				)
				( pin "U5D1.BR84"
					( objectStatus "vccin(112)" )
				)
				( pin "U5D1.BR62"
					( objectStatus "vccin(113)" )
				)
				( pin "U5D1.BR60"
					( objectStatus "vccin(114)" )
				)
				( pin "U5D1.BP83"
					( objectStatus "vccin(115)" )
				)
				( pin "U5D1.BP81"
					( objectStatus "vccin(116)" )
				)
				( pin "U5D1.BP79"
					( objectStatus "vccin(117)" )
				)
				( pin "U5D1.BP77"
					( objectStatus "vccin(118)" )
				)
				( pin "U5D1.BP75"
					( objectStatus "vccin(119)" )
				)
				( pin "U5D1.BP73"
					( objectStatus "vccin(120)" )
				)
				( pin "U5D1.BP71"
					( objectStatus "vccin(121)" )
				)
				( pin "U5D1.BP69"
					( objectStatus "vccin(122)" )
				)
				( pin "U5D1.BP67"
					( objectStatus "vccin(123)" )
				)
				( pin "U5D1.BP65"
					( objectStatus "vccin(124)" )
				)
				( pin "U5D1.BP63"
					( objectStatus "vccin(125)" )
				)
				( pin "U5D1.BP61"
					( objectStatus "vccin(126)" )
				)
				( pin "U5D1.BN84"
					( objectStatus "vccin(127)" )
				)
				( pin "U5D1.BN82"
					( objectStatus "vccin(128)" )
				)
				( pin "U5D1.BN80"
					( objectStatus "vccin(129)" )
				)
				( pin "U5D1.BA86"
					( objectStatus "vccin_sense" )
				)
				( pin "U5D1.AW86"
					( objectStatus "vccinpmax(0)" )
				)
				( pin "U5D1.AV85"
					( objectStatus "vccinpmax(1)" )
				)
				( pin "U5D1.AD41"
					( objectStatus "vsensepmax" )
				)
				( pin "U5D1.AY85"
					( objectStatus "vss_vccin_sense" )
				)
			)
			( gate "R14"
				( objectStatus "@baseboard_fab2_lib.baseboard_fab2(sch_1):page37_i312" )
				( pin "R14.1"
					( objectStatus "a" )
				)
				( pin "R14.2"
					( objectStatus "b" )
				)
			)
			( gate "C6D1"
				( objectStatus "@baseboard_fab2_lib.baseboard_fab2(sch_1):page38_i19" )
				( pin "C6D1.1"
					( objectStatus "a" )
				)
				( pin "C6D1.2"
					( objectStatus "b" )
				)
			)
			( gate "U5D1"
				( objectStatus "@baseboard_fab2_lib.baseboard_fab2(sch_1):page38_i33" )
				( pin "U5D1.B49"
					( objectStatus "vccd012(0)" )
				)
				( pin "U5D1.B53"
					( objectStatus "vccd012(1)" )
				)
				( pin "U5D1.B59"
					( objectStatus "vccd012(2)" )
				)
				( pin "U5D1.E46"
					( objectStatus "vccd012(3)" )
				)
				( pin "U5D1.E48"
					( objectStatus "vccd012(4)" )
				)
				( pin "U5D1.E50"
					( objectStatus "vccd012(5)" )
				)
				( pin "U5D1.E52"
					( objectStatus "vccd012(6)" )
				)
				( pin "U5D1.E54"
					( objectStatus "vccd012(7)" )
				)
				( pin "U5D1.E56"
					( objectStatus "vccd012(8)" )
				)
				( pin "U5D1.E58"
					( objectStatus "vccd012(9)" )
				)
				( pin "U5D1.E60"
					( objectStatus "vccd012(10)" )
				)
				( pin "U5D1.E62"
					( objectStatus "vccd012(11)" )
				)
				( pin "U5D1.E64"
					( objectStatus "vccd012(12)" )
				)
				( pin "U5D1.L46"
					( objectStatus "vccd012(13)" )
				)
				( pin "U5D1.L48"
					( objectStatus "vccd012(14)" )
				)
				( pin "U5D1.L50"
					( objectStatus "vccd012(15)" )
				)
				( pin "U5D1.L52"
					( objectStatus "vccd012(16)" )
				)
				( pin "U5D1.L54"
					( objectStatus "vccd012(17)" )
				)
				( pin "U5D1.L56"
					( objectStatus "vccd012(18)" )
				)
				( pin "U5D1.L58"
					( objectStatus "vccd012(19)" )
				)
				( pin "U5D1.L60"
					( objectStatus "vccd012(20)" )
				)
				( pin "U5D1.L62"
					( objectStatus "vccd012(21)" )
				)
				( pin "U5D1.N64"
					( objectStatus "vccd012(22)" )
				)
				( pin "U5D1.U46"
					( objectStatus "vccd012(23)" )
				)
				( pin "U5D1.U48"
					( objectStatus "vccd012(24)" )
				)
				( pin "U5D1.U50"
					( objectStatus "vccd012(25)" )
				)
				( pin "U5D1.U52"
					( objectStatus "vccd012(26)" )
				)
				( pin "U5D1.U54"
					( objectStatus "vccd012(27)" )
				)
				( pin "U5D1.U56"
					( objectStatus "vccd012(28)" )
				)
				( pin "U5D1.U58"
					( objectStatus "vccd012(29)" )
				)
				( pin "U5D1.U60"
					( objectStatus "vccd012(30)" )
				)
				( pin "U5D1.U62"
					( objectStatus "vccd012(31)" )
				)
				( pin "U5D1.W64"
					( objectStatus "vccd012(32)" )
				)
				( pin "U5D1.Y45"
					( objectStatus "vccd012(33)" )
				)
				( pin "U5D1.Y47"
					( objectStatus "vccd012(34)" )
				)
				( pin "U5D1.Y49"
					( objectStatus "vccd012(35)" )
				)
				( pin "U5D1.Y51"
					( objectStatus "vccd012(36)" )
				)
				( pin "U5D1.Y53"
					( objectStatus "vccd012(37)" )
				)
				( pin "U5D1.Y55"
					( objectStatus "vccd012(38)" )
				)
				( pin "U5D1.Y57"
					( objectStatus "vccd012(39)" )
				)
				( pin "U5D1.Y59"
					( objectStatus "vccd012(40)" )
				)
				( pin "U5D1.Y61"
					( objectStatus "vccd012(41)" )
				)
				( pin "U5D1.Y63"
					( objectStatus "vccd012(42)" )
				)
				( pin "U5D1.AD45"
					( objectStatus "vccd012(43)" )
				)
				( pin "U5D1.AF55"
					( objectStatus "vccd012(44)" )
				)
				( pin "U5D1.AF57"
					( objectStatus "vccd012(45)" )
				)
				( pin "U5D1.AF59"
					( objectStatus "vccd012(46)" )
				)
				( pin "U5D1.AF61"
					( objectStatus "vccd012(47)" )
				)
				( pin "U5D1.AF63"
					( objectStatus "vccd012(48)" )
				)
				( pin "U5D1.D45"
					( objectStatus "vccd012(49)" )
				)
				( pin "U5D1.C46"
					( objectStatus "vccd012(50)" )
				)
				( pin "U5D1.B47"
					( objectStatus "vccd012(51)" )
				)
				( pin "U5D1.EF59"
					( objectStatus "vccd345(0)" )
				)
				( pin "U5D1.EF53"
					( objectStatus "vccd345(1)" )
				)
				( pin "U5D1.EF49"
					( objectStatus "vccd345(2)" )
				)
				( pin "U5D1.EC62"
					( objectStatus "vccd345(3)" )
				)
				( pin "U5D1.EC60"
					( objectStatus "vccd345(4)" )
				)
				( pin "U5D1.EC58"
					( objectStatus "vccd345(5)" )
				)
				( pin "U5D1.EC56"
					( objectStatus "vccd345(6)" )
				)
				( pin "U5D1.EC54"
					( objectStatus "vccd345(7)" )
				)
				( pin "U5D1.EC52"
					( objectStatus "vccd345(8)" )
				)
				( pin "U5D1.EC50"
					( objectStatus "vccd345(9)" )
				)
				( pin "U5D1.EC48"
					( objectStatus "vccd345(10)" )
				)
				( pin "U5D1.EC46"
					( objectStatus "vccd345(11)" )
				)
				( pin "U5D1.DU64"
					( objectStatus "vccd345(12)" )
				)
				( pin "U5D1.DU62"
					( objectStatus "vccd345(13)" )
				)
				( pin "U5D1.DU60"
					( objectStatus "vccd345(14)" )
				)
				( pin "U5D1.DU58"
					( objectStatus "vccd345(15)" )
				)
				( pin "U5D1.DU56"
					( objectStatus "vccd345(16)" )
				)
				( pin "U5D1.DU54"
					( objectStatus "vccd345(17)" )
				)
				( pin "U5D1.DU52"
					( objectStatus "vccd345(18)" )
				)
				( pin "U5D1.DU50"
					( objectStatus "vccd345(19)" )
				)
				( pin "U5D1.DU48"
					( objectStatus "vccd345(20)" )
				)
				( pin "U5D1.DU46"
					( objectStatus "vccd345(21)" )
				)
				( pin "U5D1.DL62"
					( objectStatus "vccd345(22)" )
				)
				( pin "U5D1.DL60"
					( objectStatus "vccd345(23)" )
				)
				( pin "U5D1.DL58"
					( objectStatus "vccd345(24)" )
				)
				( pin "U5D1.DL56"
					( objectStatus "vccd345(25)" )
				)
				( pin "U5D1.DL54"
					( objectStatus "vccd345(26)" )
				)
				( pin "U5D1.DL52"
					( objectStatus "vccd345(27)" )
				)
				( pin "U5D1.DL50"
					( objectStatus "vccd345(28)" )
				)
				( pin "U5D1.DL48"
					( objectStatus "vccd345(29)" )
				)
				( pin "U5D1.DL46"
					( objectStatus "vccd345(30)" )
				)
				( pin "U5D1.DJ64"
					( objectStatus "vccd345(31)" )
				)
				( pin "U5D1.DH63"
					( objectStatus "vccd345(32)" )
				)
				( pin "U5D1.DH61"
					( objectStatus "vccd345(33)" )
				)
				( pin "U5D1.DH59"
					( objectStatus "vccd345(34)" )
				)
				( pin "U5D1.DH57"
					( objectStatus "vccd345(35)" )
				)
				( pin "U5D1.DH55"
					( objectStatus "vccd345(36)" )
				)
				( pin "U5D1.DH53"
					( objectStatus "vccd345(37)" )
				)
				( pin "U5D1.DH51"
					( objectStatus "vccd345(38)" )
				)
				( pin "U5D1.DH49"
					( objectStatus "vccd345(39)" )
				)
				( pin "U5D1.DH47"
					( objectStatus "vccd345(40)" )
				)
				( pin "U5D1.DH45"
					( objectStatus "vccd345(41)" )
				)
				( pin "U5D1.DD45"
					( objectStatus "vccd345(42)" )
				)
				( pin "U5D1.DB63"
					( objectStatus "vccd345(43)" )
				)
				( pin "U5D1.DB61"
					( objectStatus "vccd345(44)" )
				)
				( pin "U5D1.DB59"
					( objectStatus "vccd345(45)" )
				)
				( pin "U5D1.DB57"
					( objectStatus "vccd345(46)" )
				)
				( pin "U5D1.DB55"
					( objectStatus "vccd345(47)" )
				)
				( pin "U5D1.DB53"
					( objectStatus "vccd345(48)" )
				)
				( pin "U5D1.EF45"
					( objectStatus "vccd345(49)" )
				)
				( pin "U5D1.EE44"
					( objectStatus "vccd345(50)" )
				)
			)
			( gate "U5D1"
				( objectStatus "@baseboard_fab2_lib.baseboard_fab2(sch_1):page38_i34" )
				( pin "U5D1.BL14"
					( objectStatus "cd_vcc_core(0)" )
				)
				( pin "U5D1.BK15"
					( objectStatus "cd_vcc_core(1)" )
				)
				( pin "U5D1.BK13"
					( objectStatus "cd_vcc_core(2)" )
				)
				( pin "U5D1.BJ14"
					( objectStatus "cd_vcc_core(3)" )
				)
				( pin "U5D1.BJ12"
					( objectStatus "cd_vcc_core(4)" )
				)
				( pin "U5D1.BH13"
					( objectStatus "cd_vcc_core(5)" )
				)
				( pin "U5D1.BG14"
					( objectStatus "cd_vcc_core(6)" )
				)
				( pin "U5D1.BG12"
					( objectStatus "cd_vcc_core(7)" )
				)
				( pin "U5D1.BF13"
					( objectStatus "cd_vcc_core(8)" )
				)
				( pin "U5D1.BF11"
					( objectStatus "cd_vcc_core(9)" )
				)
				( pin "U5D1.BE14"
					( objectStatus "cd_vcc_core(10)" )
				)
				( pin "U5D1.BE12"
					( objectStatus "cd_vcc_core(11)" )
				)
				( pin "U5D1.BD13"
					( objectStatus "cd_vcc_core(12)" )
				)
				( pin "U5D1.BT27"
					( objectStatus "cd_vccin(0)" )
				)
				( pin "U5D1.BU26"
					( objectStatus "cd_vccin(1)" )
				)
				( pin "U5D1.BV27"
					( objectStatus "cd_vccin(2)" )
				)
				( pin "U5D1.BY27"
					( objectStatus "cd_vccin(3)" )
				)
				( pin "U5D1.BV15"
					( objectStatus "cd_vccp(0)" )
				)
				( pin "U5D1.BV13"
					( objectStatus "cd_vccp(1)" )
				)
				( pin "U5D1.BV11"
					( objectStatus "cd_vccp(2)" )
				)
				( pin "U5D1.BU14"
					( objectStatus "cd_vccp(3)" )
				)
				( pin "U5D1.BU12"
					( objectStatus "cd_vccp(4)" )
				)
				( pin "U5D1.BT15"
					( objectStatus "cd_vccp(5)" )
				)
				( pin "U5D1.BT13"
					( objectStatus "cd_vccp(6)" )
				)
				( pin "U5D1.BT11"
					( objectStatus "cd_vccp(7)" )
				)
				( pin "U5D1.BR14"
					( objectStatus "cd_vccp(8)" )
				)
				( pin "U5D1.BR12"
					( objectStatus "cd_vccp(9)" )
				)
				( pin "U5D1.BP15"
					( objectStatus "cd_vccp(10)" )
				)
				( pin "U5D1.BP13"
					( objectStatus "cd_vccp(11)" )
				)
				( pin "U5D1.BP11"
					( objectStatus "cd_vccp(12)" )
				)
				( pin "U5D1.BN14"
					( objectStatus "cd_vccp(13)" )
				)
				( pin "U5D1.BN12"
					( objectStatus "cd_vccp(14)" )
				)
				( pin "U5D1.BM11"
					( objectStatus "cd_vccp(15)" )
				)
				( pin "U5D1.B11"
					( objectStatus "cd_vpp(0)" )
				)
				( pin "U5D1.A12"
					( objectStatus "cd_vpp(1)" )
				)
				( pin "U5D1.A10"
					( objectStatus "cd_vpp(2)" )
				)
				( pin "U5D1.A8"
					( objectStatus "cd_vpp(3)" )
				)
				( pin "U5D1.CY55"
					( objectStatus "vcc33" )
				)
				( pin "U5D1.CM15"
					( objectStatus "vccio(20)" )
				)
				( pin "U5D1.CL12"
					( objectStatus "vccio(21)" )
				)
				( pin "U5D1.CK5"
					( objectStatus "vccio(22)" )
				)
				( pin "U5D1.CV7"
					( objectStatus "vccio(23)" )
				)
				( pin "U5D1.CH9"
					( objectStatus "vccio(24)" )
				)
				( pin "U5D1.D7"
					( objectStatus "vccio(25)" )
				)
				( pin "U5D1.CE18"
					( objectStatus "vccio(26)" )
				)
				( pin "U5D1.CD9"
					( objectStatus "vccio(27)" )
				)
				( pin "U5D1.CB17"
					( objectStatus "vccio(28)" )
				)
				( pin "U5D1.CB13"
					( objectStatus "vccio(29)" )
				)
				( pin "U5D1.BP25"
					( objectStatus "vccio(30)" )
				)
				( pin "U5D1.BJ24"
					( objectStatus "vccio(31)" )
				)
				( pin "U5D1.BF23"
					( objectStatus "vccio(32)" )
				)
				( pin "U5D1.DA14"
					( objectStatus "vccio(33)" )
				)
				( pin "U5D1.BB5"
					( objectStatus "vccio(34)" )
				)
				( pin "U5D1.BA24"
					( objectStatus "vccio(35)" )
				)
				( pin "U5D1.AY11"
					( objectStatus "vccio(36)" )
				)
				( pin "U5D1.AW6"
					( objectStatus "vccio(37)" )
				)
				( pin "U5D1.AT11"
					( objectStatus "vccio(38)" )
				)
				( pin "U5D1.DD7"
					( objectStatus "vccio(39)" )
				)
				( pin "U5D1.AN10"
					( objectStatus "vccio(40)" )
				)
				( pin "U5D1.DF13"
					( objectStatus "vccio(41)" )
				)
				( pin "U5D1.AH9"
					( objectStatus "vccio(42)" )
				)
				( pin "U5D1.AC4"
					( objectStatus "vccio(43)" )
				)
				( pin "U5D1.AC20"
					( objectStatus "vccio(44)" )
				)
				( pin "U5D1.AA10"
					( objectStatus "vccio(45)" )
				)
				( pin "U5D1.W6"
					( objectStatus "vccio(46)" )
				)
				( pin "U5D1.W4"
					( objectStatus "vccio(47)" )
				)
				( pin "U5D1.DF21"
					( objectStatus "vccio(48)" )
				)
				( pin "U5D1.U14"
					( objectStatus "vccio(49)" )
				)
				( pin "U5D1.T3"
					( objectStatus "vccio(50)" )
				)
				( pin "U5D1.P5"
					( objectStatus "vccio(51)" )
				)
				( pin "U5D1.M21"
					( objectStatus "vccio(52)" )
				)
				( pin "U5D1.M11"
					( objectStatus "vccio(53)" )
				)
				( pin "U5D1.DG8"
					( objectStatus "vccio(54)" )
				)
				( pin "U5D1.DH7"
					( objectStatus "vccio(55)" )
				)
				( pin "U5D1.L16"
					( objectStatus "vccio(56)" )
				)
				( pin "U5D1.L14"
					( objectStatus "vccio(57)" )
				)
				( pin "U5D1.J10"
					( objectStatus "vccio(58)" )
				)
				( pin "U5D1.H13"
					( objectStatus "vccio(59)" )
				)
				( pin "U5D1.DJ16"
					( objectStatus "vccio(60)" )
				)
				( pin "U5D1.DM17"
					( objectStatus "vccio(61)" )
				)
				( pin "U5D1.DN8"
					( objectStatus "vccio(62)" )
				)
				( pin "U5D1.DP19"
					( objectStatus "vccio(63)" )
				)
				( pin "U5D1.DR10"
					( objectStatus "vccio(64)" )
				)
				( pin "U5D1.DR2"
					( objectStatus "vccio(65)" )
				)
				( pin "U5D1.DU20"
					( objectStatus "vccio(66)" )
				)
				( pin "U5D1.EA12"
					( objectStatus "vccio(67)" )
				)
				( pin "U5D1.EB15"
					( objectStatus "vccio(68)" )
				)
				( pin "U5D1.J2"
					( objectStatus "vccio(69)" )
				)
				( pin "U5D1.K15"
					( objectStatus "vccio(70)" )
				)
				( pin "U5D1.M7"
					( objectStatus "vccio(71)" )
				)
				( pin "U5D1.M9"
					( objectStatus "vccio(72)" )
				)
				( pin "U5D1.N18"
					( objectStatus "vccio(73)" )
				)
				( pin "U5D1.W10"
					( objectStatus "vccio(74)" )
				)
				( pin "U5D1.BC26"
					( objectStatus "vccio(75)" )
				)
				( pin "U5D1.BB27"
					( objectStatus "vccio(76)" )
				)
				( pin "U5D1.BA26"
					( objectStatus "vccio(77)" )
				)
				( pin "U5D1.AY27"
					( objectStatus "vccio(78)" )
				)
				( pin "U5D1.AW26"
					( objectStatus "vccio(79)" )
				)
				( pin "U5D1.AV27"
					( objectStatus "vccio(80)" )
				)
				( pin "U5D1.CF27"
					( objectStatus "vccio(81)" )
				)
				( pin "U5D1.CD27"
					( objectStatus "vccio(82)" )
				)
				( pin "U5D1.CC26"
					( objectStatus "vccio(83)" )
				)
				( pin "U5D1.CJ28"
					( objectStatus "vccio(84)" )
				)
				( pin "U5D1.CH27"
					( objectStatus "vccio(85)" )
				)
				( pin "U5D1.BM27"
					( objectStatus "vccio(86)" )
				)
				( pin "U5D1.BL26"
					( objectStatus "vccio(87)" )
				)
				( pin "U5D1.BK27"
					( objectStatus "vccio(88)" )
				)
				( pin "U5D1.BK25"
					( objectStatus "vccio(89)" )
				)
				( pin "U5D1.BJ26"
					( objectStatus "vccio(90)" )
				)
				( pin "U5D1.BH27"
					( objectStatus "vccio(91)" )
				)
				( pin "U5D1.BH25"
					( objectStatus "vccio(92)" )
				)
				( pin "U5D1.BG26"
					( objectStatus "vccio(93)" )
				)
				( pin "U5D1.BF27"
					( objectStatus "vccio(94)" )
				)
				( pin "U5D1.AE36"
					( objectStatus "vccio(95)" )
				)
				( pin "U5D1.AD37"
					( objectStatus "vccio(96)" )
				)
				( pin "U5D1.AC36"
					( objectStatus "vccio(97)" )
				)
				( pin "U5D1.AF35"
					( objectStatus "vccio(98)" )
				)
				( pin "U5D1.AD35"
					( objectStatus "vccio(99)" )
				)
				( pin "U5D1.AE34"
					( objectStatus "vccio(100)" )
				)
				( pin "U5D1.AG34"
					( objectStatus "vccio(101)" )
				)
				( pin "U5D1.AM29"
					( objectStatus "vccio(102)" )
				)
				( pin "U5D1.AL28"
					( objectStatus "vccio(103)" )
				)
				( pin "U5D1.AR28"
					( objectStatus "vccio(104)" )
				)
				( pin "U5D1.CJ66"
					( objectStatus "vccsa(0)" )
				)
				( pin "U5D1.CJ64"
					( objectStatus "vccsa(1)" )
				)
				( pin "U5D1.CH75"
					( objectStatus "vccsa(2)" )
				)
				( pin "U5D1.CH65"
					( objectStatus "vccsa(3)" )
				)
				( pin "U5D1.CG74"
					( objectStatus "vccsa(4)" )
				)
				( pin "U5D1.CG66"
					( objectStatus "vccsa(5)" )
				)
				( pin "U5D1.CG64"
					( objectStatus "vccsa(6)" )
				)
				( pin "U5D1.CF75"
					( objectStatus "vccsa(7)" )
				)
				( pin "U5D1.CF73"
					( objectStatus "vccsa(8)" )
				)
				( pin "U5D1.CF67"
					( objectStatus "vccsa(9)" )
				)
				( pin "U5D1.CF65"
					( objectStatus "vccsa(10)" )
				)
				( pin "U5D1.CE74"
					( objectStatus "vccsa(11)" )
				)
				( pin "U5D1.CE72"
					( objectStatus "vccsa(12)" )
				)
				( pin "U5D1.CE68"
					( objectStatus "vccsa(13)" )
				)
				( pin "U5D1.CE66"
					( objectStatus "vccsa(14)" )
				)
				( pin "U5D1.CE64"
					( objectStatus "vccsa(15)" )
				)
				( pin "U5D1.CD71"
					( objectStatus "vccsa(16)" )
				)
				( pin "U5D1.CD69"
					( objectStatus "vccsa(17)" )
				)
				( pin "U5D1.CD67"
					( objectStatus "vccsa(18)" )
				)
				( pin "U5D1.CD65"
					( objectStatus "vccsa(19)" )
				)
				( pin "U5D1.CC70"
					( objectStatus "vccsa(20)" )
				)
				( pin "U5D1.CC68"
					( objectStatus "vccsa(21)" )
				)
				( pin "U5D1.CC66"
					( objectStatus "vccsa(22)" )
				)
				( pin "U5D1.CB69"
					( objectStatus "vccsa(23)" )
				)
				( pin "U5D1.CB67"
					( objectStatus "vccsa(24)" )
				)
				( pin "U5D1.CB65"
					( objectStatus "vccsa(25)" )
				)
			)
			( gate "U5D1"
				( objectStatus "@baseboard_fab2_lib.baseboard_fab2(sch_1):page39_i127" )
				( pin "U5D1.BN16"
					( objectStatus "cd_vcc_core_sense" )
				)
				( pin "U5D1.BU16"
					( objectStatus "cd_vccp_sense(0)" )
				)
				( pin "U5D1.BT17"
					( objectStatus "cd_vccp_sense(1)" )
				)
				( pin "U5D1.BL16"
					( objectStatus "cd_vss_vcc_core_sense" )
				)
				( pin "U5D1.EF83"
					( objectStatus "rsvd(0)" )
				)
				( pin "U5D1.EF81"
					( objectStatus "rsvd(1)" )
				)
				( pin "U5D1.EF77"
					( objectStatus "rsvd(2)" )
				)
				( pin "U5D1.EF47"
					( objectStatus "rsvd(3)" )
				)
				( pin "U5D1.EE84"
					( objectStatus "rsvd(4)" )
				)
				( pin "U5D1.EE82"
					( objectStatus "rsvd(5)" )
				)
				( pin "U5D1.EE6"
					( objectStatus "rsvd(6)" )
				)
				( pin "U5D1.EE46"
					( objectStatus "rsvd(7)" )
				)
				( pin "U5D1.EE16"
					( objectStatus "rsvd(8)" )
				)
				( pin "U5D1.ED83"
					( objectStatus "rsvd(9)" )
				)
				( pin "U5D1.ED5"
					( objectStatus "rsvd(10)" )
				)
				( pin "U5D1.ED45"
					( objectStatus "rsvd(11)" )
				)
				( pin "U5D1.EC84"
					( objectStatus "rsvd(12)" )
				)
				( pin "U5D1.EC44"
					( objectStatus "rsvd(13)" )
				)
				( pin "U5D1.EC4"
					( objectStatus "rsvd(14)" )
				)
				( pin "U5D1.EC16"
					( objectStatus "rsvd(15)" )
				)
				( pin "U5D1.EB85"
					( objectStatus "rsvd(16)" )
				)
				( pin "U5D1.EB5"
					( objectStatus "rsvd(17)" )
				)
				( pin "U5D1.EB3"
					( objectStatus "rsvd(18)" )
				)
				( pin "U5D1.EA44"
					( objectStatus "rsvd(19)" )
				)
				( pin "U5D1.EA4"
					( objectStatus "rsvd(20)" )
				)
				( pin "U5D1.DY3"
					( objectStatus "rsvd(21)" )
				)
				( pin "U5D1.DW46"
					( objectStatus "rsvd(22)" )
				)
				( pin "U5D1.DW44"
					( objectStatus "rsvd(23)" )
				)
				( pin "U5D1.DV71"
					( objectStatus "rsvd(24)" )
				)
				( pin "U5D1.DV61"
					( objectStatus "rsvd(25)" )
				)
				( pin "U5D1.DU44"
					( objectStatus "rsvd(26)" )
				)
				( pin "U5D1.DT71"
					( objectStatus "rsvd(27)" )
				)
				( pin "U5D1.DR44"
					( objectStatus "rsvd(28)" )
				)
				( pin "U5D1.DP65"
					( objectStatus "rsvd(29)" )
				)
				( pin "U5D1.DP17"
					( objectStatus "rsvd(30)" )
				)
				( pin "U5D1.DN66"
					( objectStatus "rsvd(31)" )
				)
				( pin "U5D1.DN62"
					( objectStatus "rsvd(32)" )
				)
				( pin "U5D1.DM67"
					( objectStatus "rsvd(33)" )
				)
				( pin "U5D1.DL66"
					( objectStatus "rsvd(34)" )
				)
				( pin "U5D1.DL38"
					( objectStatus "rsvd(35)" )
				)
				( pin "U5D1.DK67"
					( objectStatus "rsvd(36)" )
				)
				( pin "U5D1.DK65"
					( objectStatus "rsvd(37)" )
				)
				( pin "U5D1.DK37"
					( objectStatus "rsvd(38)" )
				)
				( pin "U5D1.DK15"
					( objectStatus "rsvd(39)" )
				)
				( pin "U5D1.DJ66"
					( objectStatus "rsvd(40)" )
				)
				( pin "U5D1.DJ36"
					( objectStatus "rsvd(41)" )
				)
				( pin "U5D1.DH65"
					( objectStatus "rsvd(42)" )
				)
				( pin "U5D1.DG64"
					( objectStatus "rsvd(43)" )
				)
				( pin "U5D1.DG36"
					( objectStatus "rsvd(44)" )
				)
				( pin "U5D1.DD51"
					( objectStatus "rsvd(45)" )
				)
				( pin "U5D1.DC52"
					( objectStatus "rsvd(46)" )
				)
				( pin "U5D1.DC46"
					( objectStatus "rsvd(47)" )
				)
				( pin "U5D1.DA56"
					( objectStatus "rsvd(48)" )
				)
				( pin "U5D1.DA54"
					( objectStatus "rsvd(49)" )
				)
				( pin "U5D1.DA52"
					( objectStatus "rsvd(50)" )
				)
				( pin "U5D1.DA40"
					( objectStatus "rsvd(51)" )
				)
				( pin "U5D1.DA24"
					( objectStatus "rsvd(52)" )
				)
				( pin "U5D1.CY73"
					( objectStatus "rsvd(53)" )
				)
				( pin "U5D1.CY63"
					( objectStatus "rsvd(54)" )
				)
				( pin "U5D1.CY57"
					( objectStatus "rsvd(55)" )
				)
				( pin "U5D1.CY53"
					( objectStatus "rsvd(56)" )
				)
				( pin "U5D1.CY39"
					( objectStatus "rsvd(57)" )
				)
				( pin "U5D1.CY25"
					( objectStatus "rsvd(58)" )
				)
				( pin "U5D1.CY23"
					( objectStatus "rsvd(59)" )
				)
				( pin "U5D1.CW62"
					( objectStatus "rsvd(60)" )
				)
				( pin "U5D1.CW60"
					( objectStatus "rsvd(61)" )
				)
				( pin "U5D1.CW24"
					( objectStatus "rsvd(62)" )
				)
				( pin "U5D1.CW22"
					( objectStatus "rsvd(63)" )
				)
				( pin "U5D1.CV69"
					( objectStatus "rsvd(64)" )
				)
				( pin "U5D1.CV23"
					( objectStatus "rsvd(65)" )
				)
				( pin "U5D1.CU60"
					( objectStatus "rsvd(66)" )
				)
				( pin "U5D1.CU6"
					( objectStatus "rsvd(67)" )
				)
				( pin "U5D1.CU24"
					( objectStatus "rsvd(68)" )
				)
				( pin "U5D1.CT69"
					( objectStatus "rsvd(69)" )
				)
				( pin "U5D1.CT5"
					( objectStatus "rsvd(70)" )
				)
				( pin "U5D1.CT23"
					( objectStatus "rsvd(71)" )
				)
				( pin "U5D1.CR60"
					( objectStatus "rsvd(72)" )
				)
				( pin "U5D1.CP31"
					( objectStatus "rsvd(73)" )
				)
				( pin "U5D1.CP23"
					( objectStatus "rsvd(74)" )
				)
				( pin "U5D1.CN28"
					( objectStatus "rsvd(75)" )
				)
				( pin "U5D1.CN24"
					( objectStatus "rsvd(76)" )
				)
				( pin "U5D1.CN22"
					( objectStatus "rsvd(77)" )
				)
				( pin "U5D1.CM25"
					( objectStatus "rsvd(78)" )
				)
				( pin "U5D1.CM23"
					( objectStatus "rsvd(79)" )
				)
				( pin "U5D1.CL26"
					( objectStatus "rsvd(80)" )
				)
				( pin "U5D1.EE10"
					( objectStatus "vccio(0)" )
				)
				( pin "U5D1.AE10"
					( objectStatus "vccio(1)" )
				)
				( pin "U5D1.AF5"
					( objectStatus "vccio(2)" )
				)
				( pin "U5D1.DV11"
					( objectStatus "vccio(3)" )
				)
				( pin "U5D1.AM5"
					( objectStatus "vccio(4)" )
				)
				( pin "U5D1.AT5"
					( objectStatus "vccio(5)" )
				)
				( pin "U5D1.AT7"
					( objectStatus "vccio(6)" )
				)
				( pin "U5D1.BE24"
					( objectStatus "vccio(7)" )
				)
				( pin "U5D1.DK21"
					( objectStatus "vccio(8)" )
				)
				( pin "U5D1.CF5"
					( objectStatus "vccio(9)" )
				)
				( pin "U5D1.CG14"
					( objectStatus "vccio(10)" )
				)
				( pin "U5D1.CL20"
					( objectStatus "vccio(11)" )
				)
				( pin "U5D1.CP13"
					( objectStatus "vccio(12)" )
				)
				( pin "U5D1.DE14"
					( objectStatus "vccio(13)" )
				)
				( pin "U5D1.DC18"
					( objectStatus "vccio(14)" )
				)
				( pin "U5D1.CY17"
					( objectStatus "vccio(15)" )
				)
				( pin "U5D1.CU18"
					( objectStatus "vccio(16)" )
				)
				( pin "U5D1.CV21"
					( objectStatus "vccio(17)" )
				)
				( pin "U5D1.CU12"
					( objectStatus "vccio(18)" )
				)
				( pin "U5D1.CN6"
					( objectStatus "vccio(19)" )
				)
				( pin "U5D1.BH5"
					( objectStatus "vccio_sense" )
				)
				( pin "U5D1.CE76"
					( objectStatus "vccsa_sense" )
				)
				( pin "U5D1.BF5"
					( objectStatus "vss_vccio_sense" )
				)
				( pin "U5D1.CG76"
					( objectStatus "vss_vccsa_sense" )
				)
			)
			( gate "U5D1"
				( objectStatus "@baseboard_fab2_lib.baseboard_fab2(sch_1):page40_i20" )
				( pin "U5D1.J74"
					( objectStatus "vss(1094)" )
				)
				( pin "U5D1.J72"
					( objectStatus "vss(1095)" )
				)
				( pin "U5D1.J40"
					( objectStatus "vss(1096)" )
				)
				( pin "U5D1.J38"
					( objectStatus "vss(1097)" )
				)
				( pin "U5D1.J34"
					( objectStatus "vss(1098)" )
				)
				( pin "U5D1.J32"
					( objectStatus "vss(1099)" )
				)
				( pin "U5D1.J28"
					( objectStatus "vss(1100)" )
				)
				( pin "U5D1.J26"
					( objectStatus "vss(1101)" )
				)
				( pin "U5D1.J22"
					( objectStatus "vss(1102)" )
				)
				( pin "U5D1.J14"
					( objectStatus "vss(1103)" )
				)
				( pin "U5D1.J12"
					( objectStatus "vss(1104)" )
				)
				( pin "U5D1.J4"
					( objectStatus "vss(1105)" )
				)
				( pin "U5D1.DN44"
					( objectStatus "vss(1106)" )
				)
				( pin "U5D1.H75"
					( objectStatus "vss(1107)" )
				)
				( pin "U5D1.H71"
					( objectStatus "vss(1108)" )
				)
				( pin "U5D1.H65"
					( objectStatus "vss(1109)" )
				)
				( pin "U5D1.H41"
					( objectStatus "vss(1110)" )
				)
				( pin "U5D1.H39"
					( objectStatus "vss(1111)" )
				)
				( pin "U5D1.H37"
					( objectStatus "vss(1112)" )
				)
				( pin "U5D1.H35"
					( objectStatus "vss(1113)" )
				)
				( pin "U5D1.H33"
					( objectStatus "vss(1114)" )
				)
				( pin "U5D1.H31"
					( objectStatus "vss(1115)" )
				)
				( pin "U5D1.H29"
					( objectStatus "vss(1116)" )
				)
				( pin "U5D1.H27"
					( objectStatus "vss(1117)" )
				)
				( pin "U5D1.H25"
					( objectStatus "vss(1118)" )
				)
				( pin "U5D1.H11"
					( objectStatus "vss(1119)" )
				)
				( pin "U5D1.H3"
					( objectStatus "vss(1120)" )
				)
				( pin "U5D1.G82"
					( objectStatus "vss(1121)" )
				)
				( pin "U5D1.G80"
					( objectStatus "vss(1122)" )
				)
				( pin "U5D1.G78"
					( objectStatus "vss(1123)" )
				)
				( pin "U5D1.G76"
					( objectStatus "vss(1124)" )
				)
				( pin "U5D1.G70"
					( objectStatus "vss(1125)" )
				)
				( pin "U5D1.G66"
					( objectStatus "vss(1126)" )
				)
				( pin "U5D1.G42"
					( objectStatus "vss(1127)" )
				)
				( pin "U5D1.G38"
					( objectStatus "vss(1128)" )
				)
				( pin "U5D1.G36"
					( objectStatus "vss(1129)" )
				)
				( pin "U5D1.G32"
					( objectStatus "vss(1130)" )
				)
				( pin "U5D1.G30"
					( objectStatus "vss(1131)" )
				)
				( pin "U5D1.G26"
					( objectStatus "vss(1132)" )
				)
				( pin "U5D1.G24"
					( objectStatus "vss(1133)" )
				)
				( pin "U5D1.G22"
					( objectStatus "vss(1134)" )
				)
				( pin "U5D1.G8"
					( objectStatus "vss(1135)" )
				)
				( pin "U5D1.G4"
					( objectStatus "vss(1136)" )
				)
				( pin "U5D1.F69"
					( objectStatus "vss(1137)" )
				)
				( pin "U5D1.F67"
					( objectStatus "vss(1138)" )
				)
				( pin "U5D1.F43"
					( objectStatus "vss(1139)" )
				)
				( pin "U5D1.F37"
					( objectStatus "vss(1140)" )
				)
				( pin "U5D1.F31"
					( objectStatus "vss(1141)" )
				)
				( pin "U5D1.F25"
					( objectStatus "vss(1142)" )
				)
				( pin "U5D1.F19"
					( objectStatus "vss(1143)" )
				)
				( pin "U5D1.F17"
					( objectStatus "vss(1144)" )
				)
				( pin "U5D1.F5"
					( objectStatus "vss(1145)" )
				)
				( pin "U5D1.E76"
					( objectStatus "vss(1146)" )
				)
				( pin "U5D1.E74"
					( objectStatus "vss(1147)" )
				)
				( pin "U5D1.E72"
					( objectStatus "vss(1148)" )
				)
				( pin "U5D1.E22"
					( objectStatus "vss(1149)" )
				)
				( pin "U5D1.E20"
					( objectStatus "vss(1150)" )
				)
				( pin "U5D1.E18"
					( objectStatus "vss(1151)" )
				)
				( pin "U5D1.E16"
					( objectStatus "vss(1152)" )
				)
				( pin "U5D1.E8"
					( objectStatus "vss(1153)" )
				)
				( pin "U5D1.E6"
					( objectStatus "vss(1154)" )
				)
				( pin "U5D1.D77"
					( objectStatus "vss(1155)" )
				)
				( pin "U5D1.D43"
					( objectStatus "vss(1156)" )
				)
				( pin "U5D1.D41"
					( objectStatus "vss(1157)" )
				)
				( pin "U5D1.D39"
					( objectStatus "vss(1158)" )
				)
				( pin "U5D1.D37"
					( objectStatus "vss(1159)" )
				)
				( pin "U5D1.D35"
					( objectStatus "vss(1160)" )
				)
				( pin "U5D1.D33"
					( objectStatus "vss(1161)" )
				)
				( pin "U5D1.D31"
					( objectStatus "vss(1162)" )
				)
				( pin "U5D1.D29"
					( objectStatus "vss(1163)" )
				)
				( pin "U5D1.D27"
					( objectStatus "vss(1164)" )
				)
				( pin "U5D1.D25"
					( objectStatus "vss(1165)" )
				)
				( pin "U5D1.D13"
					( objectStatus "vss(1166)" )
				)
				( pin "U5D1.D11"
					( objectStatus "vss(1167)" )
				)
				( pin "U5D1.CM27"
					( objectStatus "vss(1168)" )
				)
				( pin "U5D1.C78"
					( objectStatus "vss(1169)" )
				)
				( pin "U5D1.C76"
					( objectStatus "vss(1170)" )
				)
				( pin "U5D1.C16"
					( objectStatus "vss(1171)" )
				)
				( pin "U5D1.C14"
					( objectStatus "vss(1172)" )
				)
				( pin "U5D1.C12"
					( objectStatus "vss(1173)" )
				)
				( pin "U5D1.C10"
					( objectStatus "vss(1174)" )
				)
				( pin "U5D1.C8"
					( objectStatus "vss(1175)" )
				)
				( pin "U5D1.B75"
					( objectStatus "vss(1176)" )
				)
				( pin "U5D1.B71"
					( objectStatus "vss(1177)" )
				)
				( pin "U5D1.B37"
					( objectStatus "vss(1178)" )
				)
				( pin "U5D1.B31"
					( objectStatus "vss(1179)" )
				)
				( pin "U5D1.B25"
					( objectStatus "vss(1180)" )
				)
				( pin "U5D1.A38"
					( objectStatus "vss(1181)" )
				)
				( pin "U5D1.A36"
					( objectStatus "vss(1182)" )
				)
				( pin "U5D1.A32"
					( objectStatus "vss(1183)" )
				)
				( pin "U5D1.A30"
					( objectStatus "vss(1184)" )
				)
				( pin "U5D1.A26"
					( objectStatus "vss(1185)" )
				)
				( pin "U5D1.AC58"
					( objectStatus "vss(1186)" )
				)
				( pin "U5D1.AC60"
					( objectStatus "vss(1187)" )
				)
				( pin "U5D1.AC62"
					( objectStatus "vss(1188)" )
				)
				( pin "U5D1.AJ4"
					( objectStatus "vss(1189)" )
				)
				( pin "U5D1.AR6"
					( objectStatus "vss(1190)" )
				)
				( pin "U5D1.CG6"
					( objectStatus "vss(1191)" )
				)
				( pin "U5D1.CW6"
					( objectStatus "vss(1192)" )
				)
				( pin "U5D1.DE48"
					( objectStatus "vss(1193)" )
				)
				( pin "U5D1.DE50"
					( objectStatus "vss(1194)" )
				)
				( pin "U5D1.DE52"
					( objectStatus "vss(1195)" )
				)
				( pin "U5D1.DE54"
					( objectStatus "vss(1196)" )
				)
				( pin "U5D1.DE56"
					( objectStatus "vss(1197)" )
				)
				( pin "U5D1.DE58"
					( objectStatus "vss(1198)" )
				)
				( pin "U5D1.DE60"
					( objectStatus "vss(1199)" )
				)
				( pin "U5D1.DE62"
					( objectStatus "vss(1200)" )
				)
				( pin "U5D1.DL8"
					( objectStatus "vss(1201)" )
				)
				( pin "U5D1.DN18"
					( objectStatus "vss(1202)" )
				)
				( pin "U5D1.DP45"
					( objectStatus "vss(1203)" )
				)
				( pin "U5D1.DP47"
					( objectStatus "vss(1204)" )
				)
				( pin "U5D1.DP49"
					( objectStatus "vss(1205)" )
				)
				( pin "U5D1.DP51"
					( objectStatus "vss(1206)" )
				)
				( pin "U5D1.DP53"
					( objectStatus "vss(1207)" )
				)
				( pin "U5D1.DP55"
					( objectStatus "vss(1208)" )
				)
				( pin "U5D1.DP57"
					( objectStatus "vss(1209)" )
				)
				( pin "U5D1.DP59"
					( objectStatus "vss(1210)" )
				)
				( pin "U5D1.DP61"
					( objectStatus "vss(1211)" )
				)
				( pin "U5D1.DP63"
					( objectStatus "vss(1212)" )
				)
				( pin "U5D1.DP9"
					( objectStatus "vss(1213)" )
				)
				( pin "U5D1.DV19"
					( objectStatus "vss(1214)" )
				)
				( pin "U5D1.DY45"
					( objectStatus "vss(1215)" )
				)
				( pin "U5D1.DY47"
					( objectStatus "vss(1216)" )
				)
				( pin "U5D1.DY49"
					( objectStatus "vss(1217)" )
				)
				( pin "U5D1.DY51"
					( objectStatus "vss(1218)" )
				)
				( pin "U5D1.DY53"
					( objectStatus "vss(1219)" )
				)
				( pin "U5D1.DY55"
					( objectStatus "vss(1220)" )
				)
				( pin "U5D1.DY57"
					( objectStatus "vss(1221)" )
				)
				( pin "U5D1.DY59"
					( objectStatus "vss(1222)" )
				)
				( pin "U5D1.DY61"
					( objectStatus "vss(1223)" )
				)
				( pin "U5D1.DY63"
					( objectStatus "vss(1224)" )
				)
				( pin "U5D1.EA14"
					( objectStatus "vss(1225)" )
				)
				( pin "U5D1.L8"
					( objectStatus "vss(1226)" )
				)
				( pin "U5D1.V11"
					( objectStatus "vss(1227)" )
				)
				( pin "U5D1.E66"
					( objectStatus "vss(1228)" )
				)
				( pin "U5D1.ED69"
					( objectStatus "vss(1229)" )
				)
				( pin "U5D1.EE80"
					( objectStatus "vss(1230)" )
				)
				( pin "U5D1.EE8"
					( objectStatus "vss(1231)" )
				)
				( pin "U5D1.EE40"
					( objectStatus "vss(1232)" )
				)
				( pin "U5D1.ED81"
					( objectStatus "vss(1233)" )
				)
				( pin "U5D1.ED7"
					( objectStatus "vss(1234)" )
				)
				( pin "U5D1.ED41"
					( objectStatus "vss(1235)" )
				)
				( pin "U5D1.EC82"
					( objectStatus "vss(1236)" )
				)
				( pin "U5D1.EC6"
					( objectStatus "vss(1237)" )
				)
				( pin "U5D1.EC42"
					( objectStatus "vss(1238)" )
				)
				( pin "U5D1.DW2"
					( objectStatus "vss(1239)" )
				)
				( pin "U5D1.EB83"
					( objectStatus "vss(1240)" )
				)
				( pin "U5D1.EA84"
					( objectStatus "vss(1241)" )
				)
				( pin "U5D1.DY85"
					( objectStatus "vss(1242)" )
				)
				( pin "U5D1.J86"
					( objectStatus "vss(1243)" )
				)
				( pin "U5D1.E82"
					( objectStatus "vss(1244)" )
				)
				( pin "U5D1.D81"
					( objectStatus "vss(1245)" )
				)
				( pin "U5D1.D3"
					( objectStatus "vss(1246)" )
				)
				( pin "U5D1.C80"
					( objectStatus "vss(1247)" )
				)
				( pin "U5D1.C4"
					( objectStatus "vss(1248)" )
				)
				( pin "U5D1.B79"
					( objectStatus "vss(1249)" )
				)
				( pin "U5D1.B5"
					( objectStatus "vss(1250)" )
				)
				( pin "U5D1.B43"
					( objectStatus "vss(1251)" )
				)
				( pin "U5D1.A42"
					( objectStatus "vss(1252)" )
				)
				( pin "U5D1.B9"
					( objectStatus "vss(1253)" )
				)
			)
			( gate "U5D1"
				( objectStatus "@baseboard_fab2_lib.baseboard_fab2(sch_1):page40_i21" )
				( pin "U5D1.AA16"
					( objectStatus "vss(934)" )
				)
				( pin "U5D1.AA4"
					( objectStatus "vss(935)" )
				)
				( pin "U5D1.Y85"
					( objectStatus "vss(936)" )
				)
				( pin "U5D1.Y83"
					( objectStatus "vss(937)" )
				)
				( pin "U5D1.Y81"
					( objectStatus "vss(938)" )
				)
				( pin "U5D1.Y79"
					( objectStatus "vss(939)" )
				)
				( pin "U5D1.Y73"
					( objectStatus "vss(940)" )
				)
				( pin "U5D1.Y71"
					( objectStatus "vss(941)" )
				)
				( pin "U5D1.Y9"
					( objectStatus "vss(942)" )
				)
				( pin "U5D1.Y7"
					( objectStatus "vss(943)" )
				)
				( pin "U5D1.Y67"
					( objectStatus "vss(944)" )
				)
				( pin "U5D1.Y5"
					( objectStatus "vss(945)" )
				)
				( pin "U5D1.Y17"
					( objectStatus "vss(946)" )
				)
				( pin "U5D1.Y15"
					( objectStatus "vss(947)" )
				)
				( pin "U5D1.W82"
					( objectStatus "vss(948)" )
				)
				( pin "U5D1.W78"
					( objectStatus "vss(949)" )
				)
				( pin "U5D1.W74"
					( objectStatus "vss(950)" )
				)
				( pin "U5D1.W68"
					( objectStatus "vss(951)" )
				)
				( pin "U5D1.W42"
					( objectStatus "vss(952)" )
				)
				( pin "U5D1.W40"
					( objectStatus "vss(953)" )
				)
				( pin "U5D1.W38"
					( objectStatus "vss(954)" )
				)
				( pin "U5D1.W36"
					( objectStatus "vss(955)" )
				)
				( pin "U5D1.W34"
					( objectStatus "vss(956)" )
				)
				( pin "U5D1.W32"
					( objectStatus "vss(957)" )
				)
				( pin "U5D1.W30"
					( objectStatus "vss(958)" )
				)
				( pin "U5D1.W28"
					( objectStatus "vss(959)" )
				)
				( pin "U5D1.W26"
					( objectStatus "vss(960)" )
				)
				( pin "U5D1.W24"
					( objectStatus "vss(961)" )
				)
				( pin "U5D1.W22"
					( objectStatus "vss(962)" )
				)
				( pin "U5D1.W12"
					( objectStatus "vss(963)" )
				)
				( pin "U5D1.AC56"
					( objectStatus "vss(964)" )
				)
				( pin "U5D1.W8"
					( objectStatus "vss(965)" )
				)
				( pin "U5D1.V83"
					( objectStatus "vss(966)" )
				)
				( pin "U5D1.V77"
					( objectStatus "vss(967)" )
				)
				( pin "U5D1.V75"
					( objectStatus "vss(968)" )
				)
				( pin "U5D1.V73"
					( objectStatus "vss(969)" )
				)
				( pin "U5D1.V43"
					( objectStatus "vss(970)" )
				)
				( pin "U5D1.V23"
					( objectStatus "vss(971)" )
				)
				( pin "U5D1.V21"
					( objectStatus "vss(972)" )
				)
				( pin "U5D1.V15"
					( objectStatus "vss(973)" )
				)
				( pin "U5D1.V13"
					( objectStatus "vss(974)" )
				)
				( pin "U5D1.V9"
					( objectStatus "vss(975)" )
				)
				( pin "U5D1.V5"
					( objectStatus "vss(976)" )
				)
				( pin "U5D1.V1"
					( objectStatus "vss(977)" )
				)
				( pin "U5D1.U86"
					( objectStatus "vss(978)" )
				)
				( pin "U5D1.U80"
					( objectStatus "vss(979)" )
				)
				( pin "U5D1.U78"
					( objectStatus "vss(980)" )
				)
				( pin "U5D1.U76"
					( objectStatus "vss(981)" )
				)
				( pin "U5D1.U74"
					( objectStatus "vss(982)" )
				)
				( pin "U5D1.U70"
					( objectStatus "vss(983)" )
				)
				( pin "U5D1.U68"
					( objectStatus "vss(984)" )
				)
				( pin "U5D1.U42"
					( objectStatus "vss(985)" )
				)
				( pin "U5D1.U36"
					( objectStatus "vss(986)" )
				)
				( pin "U5D1.U30"
					( objectStatus "vss(987)" )
				)
				( pin "U5D1.U24"
					( objectStatus "vss(988)" )
				)
				( pin "U5D1.U22"
					( objectStatus "vss(989)" )
				)
				( pin "U5D1.U20"
					( objectStatus "vss(990)" )
				)
				( pin "U5D1.U6"
					( objectStatus "vss(991)" )
				)
				( pin "U5D1.U4"
					( objectStatus "vss(992)" )
				)
				( pin "U5D1.U2"
					( objectStatus "vss(993)" )
				)
				( pin "U5D1.T85"
					( objectStatus "vss(994)" )
				)
				( pin "U5D1.T83"
					( objectStatus "vss(995)" )
				)
				( pin "U5D1.T77"
					( objectStatus "vss(996)" )
				)
				( pin "U5D1.T73"
					( objectStatus "vss(997)" )
				)
				( pin "U5D1.T65"
					( objectStatus "vss(998)" )
				)
				( pin "U5D1.T41"
					( objectStatus "vss(999)" )
				)
				( pin "U5D1.T37"
					( objectStatus "vss(1000)" )
				)
				( pin "U5D1.T35"
					( objectStatus "vss(1001)" )
				)
				( pin "U5D1.T31"
					( objectStatus "vss(1002)" )
				)
				( pin "U5D1.T29"
					( objectStatus "vss(1003)" )
				)
				( pin "U5D1.T25"
					( objectStatus "vss(1004)" )
				)
				( pin "U5D1.T17"
					( objectStatus "vss(1005)" )
				)
				( pin "U5D1.T13"
					( objectStatus "vss(1006)" )
				)
				( pin "U5D1.R86"
					( objectStatus "vss(1007)" )
				)
				( pin "U5D1.R78"
					( objectStatus "vss(1008)" )
				)
				( pin "U5D1.R72"
					( objectStatus "vss(1009)" )
				)
				( pin "U5D1.R68"
					( objectStatus "vss(1010)" )
				)
				( pin "U5D1.R40"
					( objectStatus "vss(1011)" )
				)
				( pin "U5D1.R38"
					( objectStatus "vss(1012)" )
				)
				( pin "U5D1.R34"
					( objectStatus "vss(1013)" )
				)
				( pin "U5D1.R32"
					( objectStatus "vss(1014)" )
				)
				( pin "U5D1.R28"
					( objectStatus "vss(1015)" )
				)
				( pin "U5D1.R26"
					( objectStatus "vss(1016)" )
				)
				( pin "U5D1.R22"
					( objectStatus "vss(1017)" )
				)
				( pin "U5D1.R4"
					( objectStatus "vss(1018)" )
				)
				( pin "U5D1.R2"
					( objectStatus "vss(1019)" )
				)
				( pin "U5D1.R18"
					( objectStatus "vss(1020)" )
				)
				( pin "U5D1.R14"
					( objectStatus "vss(1021)" )
				)
				( pin "U5D1.P83"
					( objectStatus "vss(1022)" )
				)
				( pin "U5D1.P81"
					( objectStatus "vss(1023)" )
				)
				( pin "U5D1.P71"
					( objectStatus "vss(1024)" )
				)
				( pin "U5D1.P69"
					( objectStatus "vss(1025)" )
				)
				( pin "U5D1.P67"
					( objectStatus "vss(1026)" )
				)
				( pin "U5D1.P39"
					( objectStatus "vss(1027)" )
				)
				( pin "U5D1.P33"
					( objectStatus "vss(1028)" )
				)
				( pin "U5D1.P27"
					( objectStatus "vss(1029)" )
				)
				( pin "U5D1.P15"
					( objectStatus "vss(1030)" )
				)
				( pin "U5D1.P11"
					( objectStatus "vss(1031)" )
				)
				( pin "U5D1.N8"
					( objectStatus "vss(1032)" )
				)
				( pin "U5D1.N4"
					( objectStatus "vss(1033)" )
				)
				( pin "U5D1.N78"
					( objectStatus "vss(1034)" )
				)
				( pin "U5D1.N76"
					( objectStatus "vss(1035)" )
				)
				( pin "U5D1.N74"
					( objectStatus "vss(1036)" )
				)
				( pin "U5D1.N72"
					( objectStatus "vss(1037)" )
				)
				( pin "U5D1.N70"
					( objectStatus "vss(1038)" )
				)
				( pin "U5D1.N66"
					( objectStatus "vss(1039)" )
				)
				( pin "U5D1.N6"
					( objectStatus "vss(1040)" )
				)
				( pin "U5D1.N22"
					( objectStatus "vss(1041)" )
				)
				( pin "U5D1.N20"
					( objectStatus "vss(1042)" )
				)
				( pin "U5D1.DM19"
					( objectStatus "vss(1043)" )
				)
				( pin "U5D1.M85"
					( objectStatus "vss(1044)" )
				)
				( pin "U5D1.M83"
					( objectStatus "vss(1045)" )
				)
				( pin "U5D1.M79"
					( objectStatus "vss(1046)" )
				)
				( pin "U5D1.M71"
					( objectStatus "vss(1047)" )
				)
				( pin "U5D1.M65"
					( objectStatus "vss(1048)" )
				)
				( pin "U5D1.M43"
					( objectStatus "vss(1049)" )
				)
				( pin "U5D1.M41"
					( objectStatus "vss(1050)" )
				)
				( pin "U5D1.M39"
					( objectStatus "vss(1051)" )
				)
				( pin "U5D1.M37"
					( objectStatus "vss(1052)" )
				)
				( pin "U5D1.M35"
					( objectStatus "vss(1053)" )
				)
				( pin "U5D1.M33"
					( objectStatus "vss(1054)" )
				)
				( pin "U5D1.M31"
					( objectStatus "vss(1055)" )
				)
				( pin "U5D1.M29"
					( objectStatus "vss(1056)" )
				)
				( pin "U5D1.M27"
					( objectStatus "vss(1057)" )
				)
				( pin "U5D1.M25"
					( objectStatus "vss(1058)" )
				)
				( pin "U5D1.M23"
					( objectStatus "vss(1059)" )
				)
				( pin "U5D1.M19"
					( objectStatus "vss(1060)" )
				)
				( pin "U5D1.M17"
					( objectStatus "vss(1061)" )
				)
				( pin "U5D1.M15"
					( objectStatus "vss(1062)" )
				)
				( pin "U5D1.CT7"
					( objectStatus "vss(1063)" )
				)
				( pin "U5D1.BT9"
					( objectStatus "vss(1064)" )
				)
				( pin "U5D1.L82"
					( objectStatus "vss(1065)" )
				)
				( pin "U5D1.L80"
					( objectStatus "vss(1066)" )
				)
				( pin "U5D1.L78"
					( objectStatus "vss(1067)" )
				)
				( pin "U5D1.L72"
					( objectStatus "vss(1068)" )
				)
				( pin "U5D1.L22"
					( objectStatus "vss(1069)" )
				)
				( pin "U5D1.L20"
					( objectStatus "vss(1070)" )
				)
				( pin "U5D1.L6"
					( objectStatus "vss(1071)" )
				)
				( pin "U5D1.L2"
					( objectStatus "vss(1072)" )
				)
				( pin "U5D1.L10"
					( objectStatus "vss(1073)" )
				)
				( pin "U5D1.K85"
					( objectStatus "vss(1074)" )
				)
				( pin "U5D1.K83"
					( objectStatus "vss(1075)" )
				)
				( pin "U5D1.K81"
					( objectStatus "vss(1076)" )
				)
				( pin "U5D1.K77"
					( objectStatus "vss(1077)" )
				)
				( pin "U5D1.K73"
					( objectStatus "vss(1078)" )
				)
				( pin "U5D1.K71"
					( objectStatus "vss(1079)" )
				)
				( pin "U5D1.K69"
					( objectStatus "vss(1080)" )
				)
				( pin "U5D1.K67"
					( objectStatus "vss(1081)" )
				)
				( pin "U5D1.K65"
					( objectStatus "vss(1082)" )
				)
				( pin "U5D1.K39"
					( objectStatus "vss(1083)" )
				)
				( pin "U5D1.K33"
					( objectStatus "vss(1084)" )
				)
				( pin "U5D1.K27"
					( objectStatus "vss(1085)" )
				)
				( pin "U5D1.DB7"
					( objectStatus "vss(1086)" )
				)
				( pin "U5D1.K17"
					( objectStatus "vss(1087)" )
				)
				( pin "U5D1.K13"
					( objectStatus "vss(1088)" )
				)
				( pin "U5D1.K11"
					( objectStatus "vss(1089)" )
				)
				( pin "U5D1.K1"
					( objectStatus "vss(1090)" )
				)
				( pin "U5D1.J84"
					( objectStatus "vss(1091)" )
				)
				( pin "U5D1.J82"
					( objectStatus "vss(1092)" )
				)
				( pin "U5D1.J76"
					( objectStatus "vss(1093)" )
				)
			)
			( gate "U5D1"
				( objectStatus "@baseboard_fab2_lib.baseboard_fab2(sch_1):page40_i22" )
				( pin "U5D1.AL68"
					( objectStatus "vss(774)" )
				)
				( pin "U5D1.AL64"
					( objectStatus "vss(775)" )
				)
				( pin "U5D1.AL56"
					( objectStatus "vss(776)" )
				)
				( pin "U5D1.AL32"
					( objectStatus "vss(777)" )
				)
				( pin "U5D1.AL30"
					( objectStatus "vss(778)" )
				)
				( pin "U5D1.AL24"
					( objectStatus "vss(779)" )
				)
				( pin "U5D1.AL10"
					( objectStatus "vss(780)" )
				)
				( pin "U5D1.AL4"
					( objectStatus "vss(781)" )
				)
				( pin "U5D1.AK85"
					( objectStatus "vss(782)" )
				)
				( pin "U5D1.AK83"
					( objectStatus "vss(783)" )
				)
				( pin "U5D1.AK81"
					( objectStatus "vss(784)" )
				)
				( pin "U5D1.AK79"
					( objectStatus "vss(785)" )
				)
				( pin "U5D1.AK73"
					( objectStatus "vss(786)" )
				)
				( pin "U5D1.AK67"
					( objectStatus "vss(787)" )
				)
				( pin "U5D1.AK65"
					( objectStatus "vss(788)" )
				)
				( pin "U5D1.AK55"
					( objectStatus "vss(789)" )
				)
				( pin "U5D1.AK33"
					( objectStatus "vss(790)" )
				)
				( pin "U5D1.AK31"
					( objectStatus "vss(791)" )
				)
				( pin "U5D1.AK29"
					( objectStatus "vss(792)" )
				)
				( pin "U5D1.AK25"
					( objectStatus "vss(793)" )
				)
				( pin "U5D1.AK23"
					( objectStatus "vss(794)" )
				)
				( pin "U5D1.AK19"
					( objectStatus "vss(795)" )
				)
				( pin "U5D1.AK13"
					( objectStatus "vss(796)" )
				)
				( pin "U5D1.AK9"
					( objectStatus "vss(797)" )
				)
				( pin "U5D1.AJ86"
					( objectStatus "vss(798)" )
				)
				( pin "U5D1.AJ82"
					( objectStatus "vss(799)" )
				)
				( pin "U5D1.AJ78"
					( objectStatus "vss(800)" )
				)
				( pin "U5D1.AJ74"
					( objectStatus "vss(801)" )
				)
				( pin "U5D1.AJ68"
					( objectStatus "vss(802)" )
				)
				( pin "U5D1.AJ66"
					( objectStatus "vss(803)" )
				)
				( pin "U5D1.AJ54"
					( objectStatus "vss(804)" )
				)
				( pin "U5D1.AJ52"
					( objectStatus "vss(805)" )
				)
				( pin "U5D1.AJ50"
					( objectStatus "vss(806)" )
				)
				( pin "U5D1.AJ48"
					( objectStatus "vss(807)" )
				)
				( pin "U5D1.AJ46"
					( objectStatus "vss(808)" )
				)
				( pin "U5D1.AJ34"
					( objectStatus "vss(809)" )
				)
				( pin "U5D1.AJ32"
					( objectStatus "vss(810)" )
				)
				( pin "U5D1.AJ28"
					( objectStatus "vss(811)" )
				)
				( pin "U5D1.AJ26"
					( objectStatus "vss(812)" )
				)
				( pin "U5D1.AJ22"
					( objectStatus "vss(813)" )
				)
				( pin "U5D1.AJ8"
					( objectStatus "vss(814)" )
				)
				( pin "U5D1.AH83"
					( objectStatus "vss(815)" )
				)
				( pin "U5D1.AH77"
					( objectStatus "vss(816)" )
				)
				( pin "U5D1.AH75"
					( objectStatus "vss(817)" )
				)
				( pin "U5D1.AH69"
					( objectStatus "vss(818)" )
				)
				( pin "U5D1.AH65"
					( objectStatus "vss(819)" )
				)
				( pin "U5D1.AH61"
					( objectStatus "vss(820)" )
				)
				( pin "U5D1.AH59"
					( objectStatus "vss(821)" )
				)
				( pin "U5D1.AH53"
					( objectStatus "vss(822)" )
				)
				( pin "U5D1.AH51"
					( objectStatus "vss(823)" )
				)
				( pin "U5D1.AH49"
					( objectStatus "vss(824)" )
				)
				( pin "U5D1.AH47"
					( objectStatus "vss(825)" )
				)
				( pin "U5D1.AH45"
					( objectStatus "vss(826)" )
				)
				( pin "U5D1.AH35"
					( objectStatus "vss(827)" )
				)
				( pin "U5D1.AH33"
					( objectStatus "vss(828)" )
				)
				( pin "U5D1.AH27"
					( objectStatus "vss(829)" )
				)
				( pin "U5D1.AH21"
					( objectStatus "vss(830)" )
				)
				( pin "U5D1.AH5"
					( objectStatus "vss(831)" )
				)
				( pin "U5D1.AH1"
					( objectStatus "vss(832)" )
				)
				( pin "U5D1.AG80"
					( objectStatus "vss(833)" )
				)
				( pin "U5D1.AG78"
					( objectStatus "vss(834)" )
				)
				( pin "U5D1.AG76"
					( objectStatus "vss(835)" )
				)
				( pin "U5D1.AG74"
					( objectStatus "vss(836)" )
				)
				( pin "U5D1.AG70"
					( objectStatus "vss(837)" )
				)
				( pin "U5D1.AG64"
					( objectStatus "vss(838)" )
				)
				( pin "U5D1.AG36"
					( objectStatus "vss(839)" )
				)
				( pin "U5D1.AG18"
					( objectStatus "vss(840)" )
				)
				( pin "U5D1.AG14"
					( objectStatus "vss(841)" )
				)
				( pin "U5D1.AG12"
					( objectStatus "vss(842)" )
				)
				( pin "U5D1.AF85"
					( objectStatus "vss(843)" )
				)
				( pin "U5D1.AF83"
					( objectStatus "vss(844)" )
				)
				( pin "U5D1.AF77"
					( objectStatus "vss(845)" )
				)
				( pin "U5D1.AF73"
					( objectStatus "vss(846)" )
				)
				( pin "U5D1.AF41"
					( objectStatus "vss(847)" )
				)
				( pin "U5D1.AF39"
					( objectStatus "vss(848)" )
				)
				( pin "U5D1.AF37"
					( objectStatus "vss(849)" )
				)
				( pin "U5D1.AF33"
					( objectStatus "vss(850)" )
				)
				( pin "U5D1.AF31"
					( objectStatus "vss(851)" )
				)
				( pin "U5D1.AF29"
					( objectStatus "vss(852)" )
				)
				( pin "U5D1.AF27"
					( objectStatus "vss(853)" )
				)
				( pin "U5D1.AF25"
					( objectStatus "vss(854)" )
				)
				( pin "U5D1.AF23"
					( objectStatus "vss(855)" )
				)
				( pin "U5D1.AF21"
					( objectStatus "vss(856)" )
				)
				( pin "U5D1.AF9"
					( objectStatus "vss(857)" )
				)
				( pin "U5D1.AC52"
					( objectStatus "vss(858)" )
				)
				( pin "U5D1.AF1"
					( objectStatus "vss(859)" )
				)
				( pin "U5D1.AE78"
					( objectStatus "vss(860)" )
				)
				( pin "U5D1.AE70"
					( objectStatus "vss(861)" )
				)
				( pin "U5D1.AE68"
					( objectStatus "vss(862)" )
				)
				( pin "U5D1.AE66"
					( objectStatus "vss(863)" )
				)
				( pin "U5D1.AE64"
					( objectStatus "vss(864)" )
				)
				( pin "U5D1.AE42"
					( objectStatus "vss(865)" )
				)
				( pin "U5D1.AE40"
					( objectStatus "vss(866)" )
				)
				( pin "U5D1.AE38"
					( objectStatus "vss(867)" )
				)
				( pin "U5D1.AE16"
					( objectStatus "vss(868)" )
				)
				( pin "U5D1.AC54"
					( objectStatus "vss(869)" )
				)
				( pin "U5D1.AE8"
					( objectStatus "vss(870)" )
				)
				( pin "U5D1.AE4"
					( objectStatus "vss(871)" )
				)
				( pin "U5D1.AD85"
					( objectStatus "vss(872)" )
				)
				( pin "U5D1.AD83"
					( objectStatus "vss(873)" )
				)
				( pin "U5D1.AD81"
					( objectStatus "vss(874)" )
				)
				( pin "U5D1.AD75"
					( objectStatus "vss(875)" )
				)
				( pin "U5D1.AD73"
					( objectStatus "vss(876)" )
				)
				( pin "U5D1.AD71"
					( objectStatus "vss(877)" )
				)
				( pin "U5D1.AD43"
					( objectStatus "vss(878)" )
				)
				( pin "U5D1.AD39"
					( objectStatus "vss(879)" )
				)
				( pin "U5D1.AD33"
					( objectStatus "vss(880)" )
				)
				( pin "U5D1.AD27"
					( objectStatus "vss(881)" )
				)
				( pin "U5D1.AD21"
					( objectStatus "vss(882)" )
				)
				( pin "U5D1.AD19"
					( objectStatus "vss(883)" )
				)
				( pin "U5D1.AD15"
					( objectStatus "vss(884)" )
				)
				( pin "U5D1.AD13"
					( objectStatus "vss(885)" )
				)
				( pin "U5D1.AD11"
					( objectStatus "vss(886)" )
				)
				( pin "U5D1.AD9"
					( objectStatus "vss(887)" )
				)
				( pin "U5D1.AD7"
					( objectStatus "vss(888)" )
				)
				( pin "U5D1.AD3"
					( objectStatus "vss(889)" )
				)
				( pin "U5D1.AC86"
					( objectStatus "vss(890)" )
				)
				( pin "U5D1.AC84"
					( objectStatus "vss(891)" )
				)
				( pin "U5D1.AC78"
					( objectStatus "vss(892)" )
				)
				( pin "U5D1.AC72"
					( objectStatus "vss(893)" )
				)
				( pin "U5D1.AC70"
					( objectStatus "vss(894)" )
				)
				( pin "U5D1.AC64"
					( objectStatus "vss(895)" )
				)
				( pin "U5D1.AC40"
					( objectStatus "vss(896)" )
				)
				( pin "U5D1.AC38"
					( objectStatus "vss(897)" )
				)
				( pin "U5D1.AC34"
					( objectStatus "vss(898)" )
				)
				( pin "U5D1.AC32"
					( objectStatus "vss(899)" )
				)
				( pin "U5D1.AC28"
					( objectStatus "vss(900)" )
				)
				( pin "U5D1.AC26"
					( objectStatus "vss(901)" )
				)
				( pin "U5D1.AC22"
					( objectStatus "vss(902)" )
				)
				( pin "U5D1.AC18"
					( objectStatus "vss(903)" )
				)
				( pin "U5D1.AB85"
					( objectStatus "vss(904)" )
				)
				( pin "U5D1.AB83"
					( objectStatus "vss(905)" )
				)
				( pin "U5D1.AB79"
					( objectStatus "vss(906)" )
				)
				( pin "U5D1.AB73"
					( objectStatus "vss(907)" )
				)
				( pin "U5D1.AB69"
					( objectStatus "vss(908)" )
				)
				( pin "U5D1.AB65"
					( objectStatus "vss(909)" )
				)
				( pin "U5D1.AB41"
					( objectStatus "vss(910)" )
				)
				( pin "U5D1.AB37"
					( objectStatus "vss(911)" )
				)
				( pin "U5D1.AB35"
					( objectStatus "vss(912)" )
				)
				( pin "U5D1.AB31"
					( objectStatus "vss(913)" )
				)
				( pin "U5D1.AB29"
					( objectStatus "vss(914)" )
				)
				( pin "U5D1.AB25"
					( objectStatus "vss(915)" )
				)
				( pin "U5D1.AB23"
					( objectStatus "vss(916)" )
				)
				( pin "U5D1.AB21"
					( objectStatus "vss(917)" )
				)
				( pin "U5D1.AB11"
					( objectStatus "vss(918)" )
				)
				( pin "U5D1.AB5"
					( objectStatus "vss(919)" )
				)
				( pin "U5D1.AB1"
					( objectStatus "vss(920)" )
				)
				( pin "U5D1.AA82"
					( objectStatus "vss(921)" )
				)
				( pin "U5D1.AA80"
					( objectStatus "vss(922)" )
				)
				( pin "U5D1.AA78"
					( objectStatus "vss(923)" )
				)
				( pin "U5D1.AA76"
					( objectStatus "vss(924)" )
				)
				( pin "U5D1.AA68"
					( objectStatus "vss(925)" )
				)
				( pin "U5D1.AA66"
					( objectStatus "vss(926)" )
				)
				( pin "U5D1.AA64"
					( objectStatus "vss(927)" )
				)
				( pin "U5D1.AA42"
					( objectStatus "vss(928)" )
				)
				( pin "U5D1.AA36"
					( objectStatus "vss(929)" )
				)
				( pin "U5D1.AA30"
					( objectStatus "vss(930)" )
				)
				( pin "U5D1.AA24"
					( objectStatus "vss(931)" )
				)
				( pin "U5D1.AA22"
					( objectStatus "vss(932)" )
				)
				( pin "U5D1.AA18"
					( objectStatus "vss(933)" )
				)
			)
			( gate "U5D1"
				( objectStatus "@baseboard_fab2_lib.baseboard_fab2(sch_1):page40_i23" )
				( pin "U5D1.BG72"
					( objectStatus "vss(614)" )
				)
				( pin "U5D1.BG24"
					( objectStatus "vss(615)" )
				)
				( pin "U5D1.BG22"
					( objectStatus "vss(616)" )
				)
				( pin "U5D1.BG10"
					( objectStatus "vss(617)" )
				)
				( pin "U5D1.BG8"
					( objectStatus "vss(618)" )
				)
				( pin "U5D1.BG6"
					( objectStatus "vss(619)" )
				)
				( pin "U5D1.BF71"
					( objectStatus "vss(620)" )
				)
				( pin "U5D1.BF69"
					( objectStatus "vss(621)" )
				)
				( pin "U5D1.BF67"
					( objectStatus "vss(622)" )
				)
				( pin "U5D1.BF65"
					( objectStatus "vss(623)" )
				)
				( pin "U5D1.BF63"
					( objectStatus "vss(624)" )
				)
				( pin "U5D1.BF25"
					( objectStatus "vss(625)" )
				)
				( pin "U5D1.BF19"
					( objectStatus "vss(626)" )
				)
				( pin "U5D1.BF17"
					( objectStatus "vss(627)" )
				)
				( pin "U5D1.BF15"
					( objectStatus "vss(628)" )
				)
				( pin "U5D1.BF9"
					( objectStatus "vss(629)" )
				)
				( pin "U5D1.BE70"
					( objectStatus "vss(630)" )
				)
				( pin "U5D1.BE68"
					( objectStatus "vss(631)" )
				)
				( pin "U5D1.BE66"
					( objectStatus "vss(632)" )
				)
				( pin "U5D1.BE64"
					( objectStatus "vss(633)" )
				)
				( pin "U5D1.BE26"
					( objectStatus "vss(634)" )
				)
				( pin "U5D1.BE10"
					( objectStatus "vss(635)" )
				)
				( pin "U5D1.BE8"
					( objectStatus "vss(636)" )
				)
				( pin "U5D1.BE6"
					( objectStatus "vss(637)" )
				)
				( pin "U5D1.BE4"
					( objectStatus "vss(638)" )
				)
				( pin "U5D1.BD71"
					( objectStatus "vss(639)" )
				)
				( pin "U5D1.BD63"
					( objectStatus "vss(640)" )
				)
				( pin "U5D1.BD27"
					( objectStatus "vss(641)" )
				)
				( pin "U5D1.BD21"
					( objectStatus "vss(642)" )
				)
				( pin "U5D1.BD15"
					( objectStatus "vss(643)" )
				)
				( pin "U5D1.BD11"
					( objectStatus "vss(644)" )
				)
				( pin "U5D1.BD5"
					( objectStatus "vss(645)" )
				)
				( pin "U5D1.BC82"
					( objectStatus "vss(646)" )
				)
				( pin "U5D1.BC80"
					( objectStatus "vss(647)" )
				)
				( pin "U5D1.BC78"
					( objectStatus "vss(648)" )
				)
				( pin "U5D1.BC76"
					( objectStatus "vss(649)" )
				)
				( pin "U5D1.BC74"
					( objectStatus "vss(650)" )
				)
				( pin "U5D1.BC72"
					( objectStatus "vss(651)" )
				)
				( pin "U5D1.BC70"
					( objectStatus "vss(652)" )
				)
				( pin "U5D1.BC16"
					( objectStatus "vss(653)" )
				)
				( pin "U5D1.BC12"
					( objectStatus "vss(654)" )
				)
				( pin "U5D1.BC8"
					( objectStatus "vss(655)" )
				)
				( pin "U5D1.BC4"
					( objectStatus "vss(656)" )
				)
				( pin "U5D1.BB83"
					( objectStatus "vss(657)" )
				)
				( pin "U5D1.BB81"
					( objectStatus "vss(658)" )
				)
				( pin "U5D1.BB79"
					( objectStatus "vss(659)" )
				)
				( pin "U5D1.BB77"
					( objectStatus "vss(660)" )
				)
				( pin "U5D1.BB75"
					( objectStatus "vss(661)" )
				)
				( pin "U5D1.BB73"
					( objectStatus "vss(662)" )
				)
				( pin "U5D1.BB69"
					( objectStatus "vss(663)" )
				)
				( pin "U5D1.BB63"
					( objectStatus "vss(664)" )
				)
				( pin "U5D1.BB23"
					( objectStatus "vss(665)" )
				)
				( pin "U5D1.BB19"
					( objectStatus "vss(666)" )
				)
				( pin "U5D1.BA84"
					( objectStatus "vss(667)" )
				)
				( pin "U5D1.BA80"
					( objectStatus "vss(668)" )
				)
				( pin "U5D1.BA74"
					( objectStatus "vss(669)" )
				)
				( pin "U5D1.BA68"
					( objectStatus "vss(670)" )
				)
				( pin "U5D1.BA62"
					( objectStatus "vss(671)" )
				)
				( pin "U5D1.BA12"
					( objectStatus "vss(672)" )
				)
				( pin "U5D1.BA6"
					( objectStatus "vss(673)" )
				)
				( pin "U5D1.BA2"
					( objectStatus "vss(674)" )
				)
				( pin "U5D1.AY81"
					( objectStatus "vss(675)" )
				)
				( pin "U5D1.AY79"
					( objectStatus "vss(676)" )
				)
				( pin "U5D1.AY63"
					( objectStatus "vss(677)" )
				)
				( pin "U5D1.AY25"
					( objectStatus "vss(678)" )
				)
				( pin "U5D1.AY23"
					( objectStatus "vss(679)" )
				)
				( pin "U5D1.AY21"
					( objectStatus "vss(680)" )
				)
				( pin "U5D1.AY17"
					( objectStatus "vss(681)" )
				)
				( pin "U5D1.AY15"
					( objectStatus "vss(682)" )
				)
				( pin "U5D1.AY5"
					( objectStatus "vss(683)" )
				)
				( pin "U5D1.AW84"
					( objectStatus "vss(684)" )
				)
				( pin "U5D1.AW82"
					( objectStatus "vss(685)" )
				)
				( pin "U5D1.AW78"
					( objectStatus "vss(686)" )
				)
				( pin "U5D1.AW74"
					( objectStatus "vss(687)" )
				)
				( pin "U5D1.AW72"
					( objectStatus "vss(688)" )
				)
				( pin "U5D1.AW70"
					( objectStatus "vss(689)" )
				)
				( pin "U5D1.AW68"
					( objectStatus "vss(690)" )
				)
				( pin "U5D1.AW66"
					( objectStatus "vss(691)" )
				)
				( pin "U5D1.AW62"
					( objectStatus "vss(692)" )
				)
				( pin "U5D1.AW10"
					( objectStatus "vss(693)" )
				)
				( pin "U5D1.AW2"
					( objectStatus "vss(694)" )
				)
				( pin "U5D1.AV83"
					( objectStatus "vss(695)" )
				)
				( pin "U5D1.AV75"
					( objectStatus "vss(696)" )
				)
				( pin "U5D1.AV67"
					( objectStatus "vss(697)" )
				)
				( pin "U5D1.AV65"
					( objectStatus "vss(698)" )
				)
				( pin "U5D1.AV63"
					( objectStatus "vss(699)" )
				)
				( pin "U5D1.AV25"
					( objectStatus "vss(700)" )
				)
				( pin "U5D1.AV23"
					( objectStatus "vss(701)" )
				)
				( pin "U5D1.AV19"
					( objectStatus "vss(702)" )
				)
				( pin "U5D1.AV13"
					( objectStatus "vss(703)" )
				)
				( pin "U5D1.AV11"
					( objectStatus "vss(704)" )
				)
				( pin "U5D1.AV7"
					( objectStatus "vss(705)" )
				)
				( pin "U5D1.AV3"
					( objectStatus "vss(706)" )
				)
				( pin "U5D1.AV1"
					( objectStatus "vss(707)" )
				)
				( pin "U5D1.AU86"
					( objectStatus "vss(708)" )
				)
				( pin "U5D1.AU84"
					( objectStatus "vss(709)" )
				)
				( pin "U5D1.AU80"
					( objectStatus "vss(710)" )
				)
				( pin "U5D1.AU78"
					( objectStatus "vss(711)" )
				)
				( pin "U5D1.AU76"
					( objectStatus "vss(712)" )
				)
				( pin "U5D1.AU74"
					( objectStatus "vss(713)" )
				)
				( pin "U5D1.AU68"
					( objectStatus "vss(714)" )
				)
				( pin "U5D1.AU64"
					( objectStatus "vss(715)" )
				)
				( pin "U5D1.AU62"
					( objectStatus "vss(716)" )
				)
				( pin "U5D1.AU28"
					( objectStatus "vss(717)" )
				)
				( pin "U5D1.AU26"
					( objectStatus "vss(718)" )
				)
				( pin "U5D1.AU6"
					( objectStatus "vss(719)" )
				)
				( pin "U5D1.AU2"
					( objectStatus "vss(720)" )
				)
				( pin "U5D1.AT85"
					( objectStatus "vss(721)" )
				)
				( pin "U5D1.AT83"
					( objectStatus "vss(722)" )
				)
				( pin "U5D1.AT77"
					( objectStatus "vss(723)" )
				)
				( pin "U5D1.AT73"
					( objectStatus "vss(724)" )
				)
				( pin "U5D1.AT69"
					( objectStatus "vss(725)" )
				)
				( pin "U5D1.AT63"
					( objectStatus "vss(726)" )
				)
				( pin "U5D1.AT61"
					( objectStatus "vss(727)" )
				)
				( pin "U5D1.AT27"
					( objectStatus "vss(728)" )
				)
				( pin "U5D1.AT21"
					( objectStatus "vss(729)" )
				)
				( pin "U5D1.AT17"
					( objectStatus "vss(730)" )
				)
				( pin "U5D1.AT15"
					( objectStatus "vss(731)" )
				)
				( pin "U5D1.P63"
					( objectStatus "vss(732)" )
				)
				( pin "U5D1.AC48"
					( objectStatus "vss(733)" )
				)
				( pin "U5D1.AR78"
					( objectStatus "vss(734)" )
				)
				( pin "U5D1.AR72"
					( objectStatus "vss(735)" )
				)
				( pin "U5D1.AR60"
					( objectStatus "vss(736)" )
				)
				( pin "U5D1.AR30"
					( objectStatus "vss(737)" )
				)
				( pin "U5D1.AR24"
					( objectStatus "vss(738)" )
				)
				( pin "U5D1.AR10"
					( objectStatus "vss(739)" )
				)
				( pin "U5D1.AP85"
					( objectStatus "vss(740)" )
				)
				( pin "U5D1.AP83"
					( objectStatus "vss(741)" )
				)
				( pin "U5D1.AP81"
					( objectStatus "vss(742)" )
				)
				( pin "U5D1.AP75"
					( objectStatus "vss(743)" )
				)
				( pin "U5D1.AP73"
					( objectStatus "vss(744)" )
				)
				( pin "U5D1.AP69"
					( objectStatus "vss(745)" )
				)
				( pin "U5D1.AP67"
					( objectStatus "vss(746)" )
				)
				( pin "U5D1.AP65"
					( objectStatus "vss(747)" )
				)
				( pin "U5D1.AP63"
					( objectStatus "vss(748)" )
				)
				( pin "U5D1.AP59"
					( objectStatus "vss(749)" )
				)
				( pin "U5D1.AP31"
					( objectStatus "vss(750)" )
				)
				( pin "U5D1.AP19"
					( objectStatus "vss(751)" )
				)
				( pin "U5D1.AP13"
					( objectStatus "vss(752)" )
				)
				( pin "U5D1.AP9"
					( objectStatus "vss(753)" )
				)
				( pin "U5D1.AP5"
					( objectStatus "vss(754)" )
				)
				( pin "U5D1.AN78"
					( objectStatus "vss(755)" )
				)
				( pin "U5D1.AN58"
					( objectStatus "vss(756)" )
				)
				( pin "U5D1.AN28"
					( objectStatus "vss(757)" )
				)
				( pin "U5D1.AN6"
					( objectStatus "vss(758)" )
				)
				( pin "U5D1.AN2"
					( objectStatus "vss(759)" )
				)
				( pin "U5D1.AM83"
					( objectStatus "vss(760)" )
				)
				( pin "U5D1.AM79"
					( objectStatus "vss(761)" )
				)
				( pin "U5D1.AM73"
					( objectStatus "vss(762)" )
				)
				( pin "U5D1.AM69"
					( objectStatus "vss(763)" )
				)
				( pin "U5D1.AM63"
					( objectStatus "vss(764)" )
				)
				( pin "U5D1.AM57"
					( objectStatus "vss(765)" )
				)
				( pin "U5D1.AM31"
					( objectStatus "vss(766)" )
				)
				( pin "U5D1.AC50"
					( objectStatus "vss(767)" )
				)
				( pin "U5D1.AM1"
					( objectStatus "vss(768)" )
				)
				( pin "U5D1.AL86"
					( objectStatus "vss(769)" )
				)
				( pin "U5D1.AL82"
					( objectStatus "vss(770)" )
				)
				( pin "U5D1.AL80"
					( objectStatus "vss(771)" )
				)
				( pin "U5D1.AL78"
					( objectStatus "vss(772)" )
				)
				( pin "U5D1.AL76"
					( objectStatus "vss(773)" )
				)
			)
			( gate "U5D1"
				( objectStatus "@baseboard_fab2_lib.baseboard_fab2(sch_1):page41_i283" )
				( pin "U5D1.P49"
					( objectStatus "vss(454)" )
				)
				( pin "U5D1.CJ12"
					( objectStatus "vss(455)" )
				)
				( pin "U5D1.CJ10"
					( objectStatus "vss(456)" )
				)
				( pin "U5D1.CJ8"
					( objectStatus "vss(457)" )
				)
				( pin "U5D1.CJ6"
					( objectStatus "vss(458)" )
				)
				( pin "U5D1.CJ2"
					( objectStatus "vss(459)" )
				)
				( pin "U5D1.CH83"
					( objectStatus "vss(460)" )
				)
				( pin "U5D1.CH81"
					( objectStatus "vss(461)" )
				)
				( pin "U5D1.CH79"
					( objectStatus "vss(462)" )
				)
				( pin "U5D1.CH73"
					( objectStatus "vss(463)" )
				)
				( pin "U5D1.CH67"
					( objectStatus "vss(464)" )
				)
				( pin "U5D1.CH63"
					( objectStatus "vss(465)" )
				)
				( pin "U5D1.CH19"
					( objectStatus "vss(466)" )
				)
				( pin "U5D1.CH15"
					( objectStatus "vss(467)" )
				)
				( pin "U5D1.CH3"
					( objectStatus "vss(468)" )
				)
				( pin "U5D1.CH1"
					( objectStatus "vss(469)" )
				)
				( pin "U5D1.CG80"
					( objectStatus "vss(470)" )
				)
				( pin "U5D1.CG72"
					( objectStatus "vss(471)" )
				)
				( pin "U5D1.CG68"
					( objectStatus "vss(472)" )
				)
				( pin "U5D1.CG62"
					( objectStatus "vss(473)" )
				)
				( pin "U5D1.CG22"
					( objectStatus "vss(474)" )
				)
				( pin "U5D1.CG18"
					( objectStatus "vss(475)" )
				)
				( pin "U5D1.P51"
					( objectStatus "vss(476)" )
				)
				( pin "U5D1.CF83"
					( objectStatus "vss(477)" )
				)
				( pin "U5D1.CF77"
					( objectStatus "vss(478)" )
				)
				( pin "U5D1.CF71"
					( objectStatus "vss(479)" )
				)
				( pin "U5D1.CF69"
					( objectStatus "vss(480)" )
				)
				( pin "U5D1.CF63"
					( objectStatus "vss(481)" )
				)
				( pin "U5D1.CF9"
					( objectStatus "vss(482)" )
				)
				( pin "U5D1.P53"
					( objectStatus "vss(483)" )
				)
				( pin "U5D1.CE82"
					( objectStatus "vss(484)" )
				)
				( pin "U5D1.CE70"
					( objectStatus "vss(485)" )
				)
				( pin "U5D1.CE62"
					( objectStatus "vss(486)" )
				)
				( pin "U5D1.CE26"
					( objectStatus "vss(487)" )
				)
				( pin "U5D1.CE20"
					( objectStatus "vss(488)" )
				)
				( pin "U5D1.CE14"
					( objectStatus "vss(489)" )
				)
				( pin "U5D1.CE10"
					( objectStatus "vss(490)" )
				)
				( pin "U5D1.CD81"
					( objectStatus "vss(491)" )
				)
				( pin "U5D1.CD79"
					( objectStatus "vss(492)" )
				)
				( pin "U5D1.CD77"
					( objectStatus "vss(493)" )
				)
				( pin "U5D1.CD75"
					( objectStatus "vss(494)" )
				)
				( pin "U5D1.CD73"
					( objectStatus "vss(495)" )
				)
				( pin "U5D1.CD63"
					( objectStatus "vss(496)" )
				)
				( pin "U5D1.CD13"
					( objectStatus "vss(497)" )
				)
				( pin "U5D1.CD5"
					( objectStatus "vss(498)" )
				)
				( pin "U5D1.CC82"
					( objectStatus "vss(499)" )
				)
				( pin "U5D1.CC80"
					( objectStatus "vss(500)" )
				)
				( pin "U5D1.CC78"
					( objectStatus "vss(501)" )
				)
				( pin "U5D1.CC76"
					( objectStatus "vss(502)" )
				)
				( pin "U5D1.CC74"
					( objectStatus "vss(503)" )
				)
				( pin "U5D1.CC72"
					( objectStatus "vss(504)" )
				)
				( pin "U5D1.CC64"
					( objectStatus "vss(505)" )
				)
				( pin "U5D1.CC24"
					( objectStatus "vss(506)" )
				)
				( pin "U5D1.CC18"
					( objectStatus "vss(507)" )
				)
				( pin "U5D1.CC16"
					( objectStatus "vss(508)" )
				)
				( pin "U5D1.CC4"
					( objectStatus "vss(509)" )
				)
				( pin "U5D1.CB71"
					( objectStatus "vss(510)" )
				)
				( pin "U5D1.CB63"
					( objectStatus "vss(511)" )
				)
				( pin "U5D1.CB27"
					( objectStatus "vss(512)" )
				)
				( pin "U5D1.CB9"
					( objectStatus "vss(513)" )
				)
				( pin "U5D1.CB7"
					( objectStatus "vss(514)" )
				)
				( pin "U5D1.CA70"
					( objectStatus "vss(515)" )
				)
				( pin "U5D1.CA68"
					( objectStatus "vss(516)" )
				)
				( pin "U5D1.CA66"
					( objectStatus "vss(517)" )
				)
				( pin "U5D1.CA64"
					( objectStatus "vss(518)" )
				)
				( pin "U5D1.CA26"
					( objectStatus "vss(519)" )
				)
				( pin "U5D1.CA18"
					( objectStatus "vss(520)" )
				)
				( pin "U5D1.CA14"
					( objectStatus "vss(521)" )
				)
				( pin "U5D1.CA10"
					( objectStatus "vss(522)" )
				)
				( pin "U5D1.CA8"
					( objectStatus "vss(523)" )
				)
				( pin "U5D1.CA6"
					( objectStatus "vss(524)" )
				)
				( pin "U5D1.CA2"
					( objectStatus "vss(525)" )
				)
				( pin "U5D1.BY71"
					( objectStatus "vss(526)" )
				)
				( pin "U5D1.BY69"
					( objectStatus "vss(527)" )
				)
				( pin "U5D1.BY67"
					( objectStatus "vss(528)" )
				)
				( pin "U5D1.BY65"
					( objectStatus "vss(529)" )
				)
				( pin "U5D1.BY63"
					( objectStatus "vss(530)" )
				)
				( pin "U5D1.BY23"
					( objectStatus "vss(531)" )
				)
				( pin "U5D1.BY13"
					( objectStatus "vss(532)" )
				)
				( pin "U5D1.BY11"
					( objectStatus "vss(533)" )
				)
				( pin "U5D1.BW82"
					( objectStatus "vss(534)" )
				)
				( pin "U5D1.BW80"
					( objectStatus "vss(535)" )
				)
				( pin "U5D1.BW78"
					( objectStatus "vss(536)" )
				)
				( pin "U5D1.BW76"
					( objectStatus "vss(537)" )
				)
				( pin "U5D1.BW74"
					( objectStatus "vss(538)" )
				)
				( pin "U5D1.BW72"
					( objectStatus "vss(539)" )
				)
				( pin "U5D1.BW26"
					( objectStatus "vss(540)" )
				)
				( pin "U5D1.BW18"
					( objectStatus "vss(541)" )
				)
				( pin "U5D1.BW16"
					( objectStatus "vss(542)" )
				)
				( pin "U5D1.BW14"
					( objectStatus "vss(543)" )
				)
				( pin "U5D1.BW12"
					( objectStatus "vss(544)" )
				)
				( pin "U5D1.P55"
					( objectStatus "vss(545)" )
				)
				( pin "U5D1.BW6"
					( objectStatus "vss(546)" )
				)
				( pin "U5D1.BV25"
					( objectStatus "vss(547)" )
				)
				( pin "U5D1.BV17"
					( objectStatus "vss(548)" )
				)
				( pin "U5D1.BU10"
					( objectStatus "vss(549)" )
				)
				( pin "U5D1.BV5"
					( objectStatus "vss(550)" )
				)
				( pin "U5D1.BU8"
					( objectStatus "vss(551)" )
				)
				( pin "U5D1.BT25"
					( objectStatus "vss(552)" )
				)
				( pin "U5D1.BT23"
					( objectStatus "vss(553)" )
				)
				( pin "U5D1.BT21"
					( objectStatus "vss(554)" )
				)
				( pin "U5D1.BT5"
					( objectStatus "vss(555)" )
				)
				( pin "U5D1.BT3"
					( objectStatus "vss(556)" )
				)
				( pin "U5D1.BR82"
					( objectStatus "vss(557)" )
				)
				( pin "U5D1.BR80"
					( objectStatus "vss(558)" )
				)
				( pin "U5D1.BR78"
					( objectStatus "vss(559)" )
				)
				( pin "U5D1.BR76"
					( objectStatus "vss(560)" )
				)
				( pin "U5D1.BR74"
					( objectStatus "vss(561)" )
				)
				( pin "U5D1.BR72"
					( objectStatus "vss(562)" )
				)
				( pin "U5D1.BR70"
					( objectStatus "vss(563)" )
				)
				( pin "U5D1.BR68"
					( objectStatus "vss(564)" )
				)
				( pin "U5D1.BR66"
					( objectStatus "vss(565)" )
				)
				( pin "U5D1.BR64"
					( objectStatus "vss(566)" )
				)
				( pin "U5D1.P57"
					( objectStatus "vss(567)" )
				)
				( pin "U5D1.BR16"
					( objectStatus "vss(568)" )
				)
				( pin "U5D1.BR10"
					( objectStatus "vss(569)" )
				)
				( pin "U5D1.BR6"
					( objectStatus "vss(570)" )
				)
				( pin "U5D1.BP27"
					( objectStatus "vss(571)" )
				)
				( pin "U5D1.BP3"
					( objectStatus "vss(572)" )
				)
				( pin "U5D1.BN26"
					( objectStatus "vss(573)" )
				)
				( pin "U5D1.BN20"
					( objectStatus "vss(574)" )
				)
				( pin "U5D1.BN10"
					( objectStatus "vss(575)" )
				)
				( pin "U5D1.BN6"
					( objectStatus "vss(576)" )
				)
				( pin "U5D1.BM25"
					( objectStatus "vss(577)" )
				)
				( pin "U5D1.P59"
					( objectStatus "vss(578)" )
				)
				( pin "U5D1.BM15"
					( objectStatus "vss(579)" )
				)
				( pin "U5D1.BM13"
					( objectStatus "vss(580)" )
				)
				( pin "U5D1.BM9"
					( objectStatus "vss(581)" )
				)
				( pin "U5D1.BL82"
					( objectStatus "vss(582)" )
				)
				( pin "U5D1.BL80"
					( objectStatus "vss(583)" )
				)
				( pin "U5D1.BL78"
					( objectStatus "vss(584)" )
				)
				( pin "U5D1.BL76"
					( objectStatus "vss(585)" )
				)
				( pin "U5D1.BL74"
					( objectStatus "vss(586)" )
				)
				( pin "U5D1.BL72"
					( objectStatus "vss(587)" )
				)
				( pin "U5D1.BL70"
					( objectStatus "vss(588)" )
				)
				( pin "U5D1.BL68"
					( objectStatus "vss(589)" )
				)
				( pin "U5D1.BL66"
					( objectStatus "vss(590)" )
				)
				( pin "U5D1.BL64"
					( objectStatus "vss(591)" )
				)
				( pin "U5D1.BL24"
					( objectStatus "vss(592)" )
				)
				( pin "U5D1.BL22"
					( objectStatus "vss(593)" )
				)
				( pin "U5D1.P61"
					( objectStatus "vss(594)" )
				)
				( pin "U5D1.BL12"
					( objectStatus "vss(595)" )
				)
				( pin "U5D1.BL10"
					( objectStatus "vss(596)" )
				)
				( pin "U5D1.BL6"
					( objectStatus "vss(597)" )
				)
				( pin "U5D1.BK19"
					( objectStatus "vss(598)" )
				)
				( pin "U5D1.BK11"
					( objectStatus "vss(599)" )
				)
				( pin "U5D1.BK7"
					( objectStatus "vss(600)" )
				)
				( pin "U5D1.BK3"
					( objectStatus "vss(601)" )
				)
				( pin "U5D1.BJ6"
					( objectStatus "vss(602)" )
				)
				( pin "U5D1.BJ4"
					( objectStatus "vss(603)" )
				)
				( pin "U5D1.BH21"
					( objectStatus "vss(604)" )
				)
				( pin "U5D1.BH15"
					( objectStatus "vss(605)" )
				)
				( pin "U5D1.BH11"
					( objectStatus "vss(606)" )
				)
				( pin "U5D1.BH9"
					( objectStatus "vss(607)" )
				)
				( pin "U5D1.BH7"
					( objectStatus "vss(608)" )
				)
				( pin "U5D1.BG82"
					( objectStatus "vss(609)" )
				)
				( pin "U5D1.BG80"
					( objectStatus "vss(610)" )
				)
				( pin "U5D1.BG78"
					( objectStatus "vss(611)" )
				)
				( pin "U5D1.BG76"
					( objectStatus "vss(612)" )
				)
				( pin "U5D1.BG74"
					( objectStatus "vss(613)" )
				)
			)
			( gate "U5D1"
				( objectStatus "@baseboard_fab2_lib.baseboard_fab2(sch_1):page41_i284" )
				( pin "U5D1.DA46"
					( objectStatus "vss(294)" )
				)
				( pin "U5D1.DA44"
					( objectStatus "vss(295)" )
				)
				( pin "U5D1.DA38"
					( objectStatus "vss(296)" )
				)
				( pin "U5D1.DA36"
					( objectStatus "vss(297)" )
				)
				( pin "U5D1.DA34"
					( objectStatus "vss(298)" )
				)
				( pin "U5D1.DA32"
					( objectStatus "vss(299)" )
				)
				( pin "U5D1.DA30"
					( objectStatus "vss(300)" )
				)
				( pin "U5D1.DA28"
					( objectStatus "vss(301)" )
				)
				( pin "U5D1.DA26"
					( objectStatus "vss(302)" )
				)
				( pin "U5D1.DA18"
					( objectStatus "vss(303)" )
				)
				( pin "U5D1.H53"
					( objectStatus "vss(304)" )
				)
				( pin "U5D1.DA6"
					( objectStatus "vss(305)" )
				)
				( pin "U5D1.CY85"
					( objectStatus "vss(306)" )
				)
				( pin "U5D1.CY83"
					( objectStatus "vss(307)" )
				)
				( pin "U5D1.CY77"
					( objectStatus "vss(308)" )
				)
				( pin "U5D1.CY75"
					( objectStatus "vss(309)" )
				)
				( pin "U5D1.CY69"
					( objectStatus "vss(310)" )
				)
				( pin "U5D1.CY65"
					( objectStatus "vss(311)" )
				)
				( pin "U5D1.CY61"
					( objectStatus "vss(312)" )
				)
				( pin "U5D1.CY59"
					( objectStatus "vss(313)" )
				)
				( pin "U5D1.CY51"
					( objectStatus "vss(314)" )
				)
				( pin "U5D1.CY45"
					( objectStatus "vss(315)" )
				)
				( pin "U5D1.CY41"
					( objectStatus "vss(316)" )
				)
				( pin "U5D1.CY21"
					( objectStatus "vss(317)" )
				)
				( pin "U5D1.CY15"
					( objectStatus "vss(318)" )
				)
				( pin "U5D1.CY13"
					( objectStatus "vss(319)" )
				)
				( pin "U5D1.CY9"
					( objectStatus "vss(320)" )
				)
				( pin "U5D1.CY1"
					( objectStatus "vss(321)" )
				)
				( pin "U5D1.CW82"
					( objectStatus "vss(322)" )
				)
				( pin "U5D1.CW78"
					( objectStatus "vss(323)" )
				)
				( pin "U5D1.CW74"
					( objectStatus "vss(324)" )
				)
				( pin "U5D1.CW68"
					( objectStatus "vss(325)" )
				)
				( pin "U5D1.CW66"
					( objectStatus "vss(326)" )
				)
				( pin "U5D1.CW64"
					( objectStatus "vss(327)" )
				)
				( pin "U5D1.CW54"
					( objectStatus "vss(328)" )
				)
				( pin "U5D1.CW52"
					( objectStatus "vss(329)" )
				)
				( pin "U5D1.CW42"
					( objectStatus "vss(330)" )
				)
				( pin "U5D1.CW40"
					( objectStatus "vss(331)" )
				)
				( pin "U5D1.CW38"
					( objectStatus "vss(332)" )
				)
				( pin "U5D1.CW32"
					( objectStatus "vss(333)" )
				)
				( pin "U5D1.CW26"
					( objectStatus "vss(334)" )
				)
				( pin "U5D1.CW12"
					( objectStatus "vss(335)" )
				)
				( pin "U5D1.CV83"
					( objectStatus "vss(336)" )
				)
				( pin "U5D1.CV81"
					( objectStatus "vss(337)" )
				)
				( pin "U5D1.CV79"
					( objectStatus "vss(338)" )
				)
				( pin "U5D1.CV73"
					( objectStatus "vss(339)" )
				)
				( pin "U5D1.CV67"
					( objectStatus "vss(340)" )
				)
				( pin "U5D1.CV63"
					( objectStatus "vss(341)" )
				)
				( pin "U5D1.CV55"
					( objectStatus "vss(342)" )
				)
				( pin "U5D1.CV53"
					( objectStatus "vss(343)" )
				)
				( pin "U5D1.CV41"
					( objectStatus "vss(344)" )
				)
				( pin "U5D1.CV39"
					( objectStatus "vss(345)" )
				)
				( pin "U5D1.CV37"
					( objectStatus "vss(346)" )
				)
				( pin "U5D1.CV33"
					( objectStatus "vss(347)" )
				)
				( pin "U5D1.CV31"
					( objectStatus "vss(348)" )
				)
				( pin "U5D1.CV27"
					( objectStatus "vss(349)" )
				)
				( pin "U5D1.CV25"
					( objectStatus "vss(350)" )
				)
				( pin "U5D1.CV17"
					( objectStatus "vss(351)" )
				)
				( pin "U5D1.H55"
					( objectStatus "vss(352)" )
				)
				( pin "U5D1.CV1"
					( objectStatus "vss(353)" )
				)
				( pin "U5D1.CU86"
					( objectStatus "vss(354)" )
				)
				( pin "U5D1.CU82"
					( objectStatus "vss(355)" )
				)
				( pin "U5D1.CU80"
					( objectStatus "vss(356)" )
				)
				( pin "U5D1.CU78"
					( objectStatus "vss(357)" )
				)
				( pin "U5D1.CU76"
					( objectStatus "vss(358)" )
				)
				( pin "U5D1.CU68"
					( objectStatus "vss(359)" )
				)
				( pin "U5D1.CU62"
					( objectStatus "vss(360)" )
				)
				( pin "U5D1.CU56"
					( objectStatus "vss(361)" )
				)
				( pin "U5D1.CU36"
					( objectStatus "vss(362)" )
				)
				( pin "U5D1.CU34"
					( objectStatus "vss(363)" )
				)
				( pin "U5D1.CU30"
					( objectStatus "vss(364)" )
				)
				( pin "U5D1.CU28"
					( objectStatus "vss(365)" )
				)
				( pin "U5D1.CU22"
					( objectStatus "vss(366)" )
				)
				( pin "U5D1.CU4"
					( objectStatus "vss(367)" )
				)
				( pin "U5D1.CT85"
					( objectStatus "vss(368)" )
				)
				( pin "U5D1.CT83"
					( objectStatus "vss(369)" )
				)
				( pin "U5D1.CT79"
					( objectStatus "vss(370)" )
				)
				( pin "U5D1.CT73"
					( objectStatus "vss(371)" )
				)
				( pin "U5D1.CT57"
					( objectStatus "vss(372)" )
				)
				( pin "U5D1.CT35"
					( objectStatus "vss(373)" )
				)
				( pin "U5D1.CT33"
					( objectStatus "vss(374)" )
				)
				( pin "U5D1.CT29"
					( objectStatus "vss(375)" )
				)
				( pin "U5D1.CT27"
					( objectStatus "vss(376)" )
				)
				( pin "U5D1.CT19"
					( objectStatus "vss(377)" )
				)
				( pin "U5D1.CT13"
					( objectStatus "vss(378)" )
				)
				( pin "U5D1.H57"
					( objectStatus "vss(379)" )
				)
				( pin "U5D1.CR86"
					( objectStatus "vss(380)" )
				)
				( pin "U5D1.CR78"
					( objectStatus "vss(381)" )
				)
				( pin "U5D1.CR68"
					( objectStatus "vss(382)" )
				)
				( pin "U5D1.CR66"
					( objectStatus "vss(383)" )
				)
				( pin "U5D1.CR64"
					( objectStatus "vss(384)" )
				)
				( pin "U5D1.CR62"
					( objectStatus "vss(385)" )
				)
				( pin "U5D1.CR58"
					( objectStatus "vss(386)" )
				)
				( pin "U5D1.CR32"
					( objectStatus "vss(387)" )
				)
				( pin "U5D1.CR24"
					( objectStatus "vss(388)" )
				)
				( pin "U5D1.CR22"
					( objectStatus "vss(389)" )
				)
				( pin "U5D1.CR10"
					( objectStatus "vss(390)" )
				)
				( pin "U5D1.CR6"
					( objectStatus "vss(391)" )
				)
				( pin "U5D1.CP83"
					( objectStatus "vss(392)" )
				)
				( pin "U5D1.CP81"
					( objectStatus "vss(393)" )
				)
				( pin "U5D1.CP75"
					( objectStatus "vss(394)" )
				)
				( pin "U5D1.CP73"
					( objectStatus "vss(395)" )
				)
				( pin "U5D1.CP69"
					( objectStatus "vss(396)" )
				)
				( pin "U5D1.CP59"
					( objectStatus "vss(397)" )
				)
				( pin "U5D1.CP25"
					( objectStatus "vss(398)" )
				)
				( pin "U5D1.H59"
					( objectStatus "vss(399)" )
				)
				( pin "U5D1.CP1"
					( objectStatus "vss(400)" )
				)
				( pin "U5D1.CN78"
					( objectStatus "vss(401)" )
				)
				( pin "U5D1.CN68"
					( objectStatus "vss(402)" )
				)
				( pin "U5D1.CN62"
					( objectStatus "vss(403)" )
				)
				( pin "U5D1.CN60"
					( objectStatus "vss(404)" )
				)
				( pin "U5D1.CN32"
					( objectStatus "vss(405)" )
				)
				( pin "U5D1.CN26"
					( objectStatus "vss(406)" )
				)
				( pin "U5D1.H61"
					( objectStatus "vss(407)" )
				)
				( pin "U5D1.CN12"
					( objectStatus "vss(408)" )
				)
				( pin "U5D1.CN2"
					( objectStatus "vss(409)" )
				)
				( pin "U5D1.CM85"
					( objectStatus "vss(410)" )
				)
				( pin "U5D1.CM83"
					( objectStatus "vss(411)" )
				)
				( pin "U5D1.CM77"
					( objectStatus "vss(412)" )
				)
				( pin "U5D1.CM73"
					( objectStatus "vss(413)" )
				)
				( pin "U5D1.CM67"
					( objectStatus "vss(414)" )
				)
				( pin "U5D1.CM63"
					( objectStatus "vss(415)" )
				)
				( pin "U5D1.CM61"
					( objectStatus "vss(416)" )
				)
				( pin "U5D1.CM31"
					( objectStatus "vss(417)" )
				)
				( pin "U5D1.CM5"
					( objectStatus "vss(418)" )
				)
				( pin "U5D1.CM29"
					( objectStatus "vss(419)" )
				)
				( pin "U5D1.CM19"
					( objectStatus "vss(420)" )
				)
				( pin "U5D1.CL80"
					( objectStatus "vss(421)" )
				)
				( pin "U5D1.CL78"
					( objectStatus "vss(422)" )
				)
				( pin "U5D1.CL76"
					( objectStatus "vss(423)" )
				)
				( pin "U5D1.CL74"
					( objectStatus "vss(424)" )
				)
				( pin "U5D1.CL66"
					( objectStatus "vss(425)" )
				)
				( pin "U5D1.CL64"
					( objectStatus "vss(426)" )
				)
				( pin "U5D1.CL62"
					( objectStatus "vss(427)" )
				)
				( pin "U5D1.H63"
					( objectStatus "vss(428)" )
				)
				( pin "U5D1.P45"
					( objectStatus "vss(429)" )
				)
				( pin "U5D1.CL18"
					( objectStatus "vss(430)" )
				)
				( pin "U5D1.CL14"
					( objectStatus "vss(431)" )
				)
				( pin "U5D1.CL8"
					( objectStatus "vss(432)" )
				)
				( pin "U5D1.CK85"
					( objectStatus "vss(433)" )
				)
				( pin "U5D1.CK83"
					( objectStatus "vss(434)" )
				)
				( pin "U5D1.CK75"
					( objectStatus "vss(435)" )
				)
				( pin "U5D1.CK73"
					( objectStatus "vss(436)" )
				)
				( pin "U5D1.CK71"
					( objectStatus "vss(437)" )
				)
				( pin "U5D1.CK69"
					( objectStatus "vss(438)" )
				)
				( pin "U5D1.CK67"
					( objectStatus "vss(439)" )
				)
				( pin "U5D1.CK65"
					( objectStatus "vss(440)" )
				)
				( pin "U5D1.CK63"
					( objectStatus "vss(441)" )
				)
				( pin "U5D1.CK27"
					( objectStatus "vss(442)" )
				)
				( pin "U5D1.CK21"
					( objectStatus "vss(443)" )
				)
				( pin "U5D1.CK15"
					( objectStatus "vss(444)" )
				)
				( pin "U5D1.CK11"
					( objectStatus "vss(445)" )
				)
				( pin "U5D1.CJ86"
					( objectStatus "vss(446)" )
				)
				( pin "U5D1.CJ84"
					( objectStatus "vss(447)" )
				)
				( pin "U5D1.CJ82"
					( objectStatus "vss(448)" )
				)
				( pin "U5D1.CJ78"
					( objectStatus "vss(449)" )
				)
				( pin "U5D1.CJ76"
					( objectStatus "vss(450)" )
				)
				( pin "U5D1.CJ74"
					( objectStatus "vss(451)" )
				)
				( pin "U5D1.CJ62"
					( objectStatus "vss(452)" )
				)
				( pin "U5D1.P47"
					( objectStatus "vss(453)" )
				)
			)
			( gate "U5D1"
				( objectStatus "@baseboard_fab2_lib.baseboard_fab2(sch_1):page41_i285" )
				( pin "U5D1.DN72"
					( objectStatus "vss(134)" )
				)
				( pin "U5D1.DN68"
					( objectStatus "vss(135)" )
				)
				( pin "U5D1.DN38"
					( objectStatus "vss(136)" )
				)
				( pin "U5D1.DN32"
					( objectStatus "vss(137)" )
				)
				( pin "U5D1.DN26"
					( objectStatus "vss(138)" )
				)
				( pin "U5D1.DN22"
					( objectStatus "vss(139)" )
				)
				( pin "U5D1.DN12"
					( objectStatus "vss(140)" )
				)
				( pin "U5D1.BH17"
					( objectStatus "vss(141)" )
				)
				( pin "U5D1.DN2"
					( objectStatus "vss(142)" )
				)
				( pin "U5D1.DM83"
					( objectStatus "vss(143)" )
				)
				( pin "U5D1.DM77"
					( objectStatus "vss(144)" )
				)
				( pin "U5D1.DM73"
					( objectStatus "vss(145)" )
				)
				( pin "U5D1.DM65"
					( objectStatus "vss(146)" )
				)
				( pin "U5D1.DM39"
					( objectStatus "vss(147)" )
				)
				( pin "U5D1.DM37"
					( objectStatus "vss(148)" )
				)
				( pin "U5D1.DM33"
					( objectStatus "vss(149)" )
				)
				( pin "U5D1.DM31"
					( objectStatus "vss(150)" )
				)
				( pin "U5D1.DM27"
					( objectStatus "vss(151)" )
				)
				( pin "U5D1.DM25"
					( objectStatus "vss(152)" )
				)
				( pin "U5D1.H45"
					( objectStatus "vss(153)" )
				)
				( pin "U5D1.DM15"
					( objectStatus "vss(154)" )
				)
				( pin "U5D1.DL80"
					( objectStatus "vss(155)" )
				)
				( pin "U5D1.DL78"
					( objectStatus "vss(156)" )
				)
				( pin "U5D1.DL76"
					( objectStatus "vss(157)" )
				)
				( pin "U5D1.DL74"
					( objectStatus "vss(158)" )
				)
				( pin "U5D1.DL70"
					( objectStatus "vss(159)" )
				)
				( pin "U5D1.DL68"
					( objectStatus "vss(160)" )
				)
				( pin "U5D1.DL40"
					( objectStatus "vss(161)" )
				)
				( pin "U5D1.DL36"
					( objectStatus "vss(162)" )
				)
				( pin "U5D1.DL34"
					( objectStatus "vss(163)" )
				)
				( pin "U5D1.DL30"
					( objectStatus "vss(164)" )
				)
				( pin "U5D1.DL28"
					( objectStatus "vss(165)" )
				)
				( pin "U5D1.DL24"
					( objectStatus "vss(166)" )
				)
				( pin "U5D1.DL22"
					( objectStatus "vss(167)" )
				)
				( pin "U5D1.DL4"
					( objectStatus "vss(168)" )
				)
				( pin "U5D1.DL18"
					( objectStatus "vss(169)" )
				)
				( pin "U5D1.DL16"
					( objectStatus "vss(170)" )
				)
				( pin "U5D1.DK85"
					( objectStatus "vss(171)" )
				)
				( pin "U5D1.DK83"
					( objectStatus "vss(172)" )
				)
				( pin "U5D1.DK77"
					( objectStatus "vss(173)" )
				)
				( pin "U5D1.DK75"
					( objectStatus "vss(174)" )
				)
				( pin "U5D1.DK73"
					( objectStatus "vss(175)" )
				)
				( pin "U5D1.DK41"
					( objectStatus "vss(176)" )
				)
				( pin "U5D1.DK39"
					( objectStatus "vss(177)" )
				)
				( pin "U5D1.DK35"
					( objectStatus "vss(178)" )
				)
				( pin "U5D1.DK29"
					( objectStatus "vss(179)" )
				)
				( pin "U5D1.DK23"
					( objectStatus "vss(180)" )
				)
				( pin "U5D1.DK7"
					( objectStatus "vss(181)" )
				)
				( pin "U5D1.DJ84"
					( objectStatus "vss(182)" )
				)
				( pin "U5D1.DJ82"
					( objectStatus "vss(183)" )
				)
				( pin "U5D1.DJ78"
					( objectStatus "vss(184)" )
				)
				( pin "U5D1.DJ74"
					( objectStatus "vss(185)" )
				)
				( pin "U5D1.DJ68"
					( objectStatus "vss(186)" )
				)
				( pin "U5D1.DJ42"
					( objectStatus "vss(187)" )
				)
				( pin "U5D1.DJ38"
					( objectStatus "vss(188)" )
				)
				( pin "U5D1.DJ22"
					( objectStatus "vss(189)" )
				)
				( pin "U5D1.H47"
					( objectStatus "vss(190)" )
				)
				( pin "U5D1.DJ10"
					( objectStatus "vss(191)" )
				)
				( pin "U5D1.DJ2"
					( objectStatus "vss(192)" )
				)
				( pin "U5D1.DH83"
					( objectStatus "vss(193)" )
				)
				( pin "U5D1.DH81"
					( objectStatus "vss(194)" )
				)
				( pin "U5D1.DH79"
					( objectStatus "vss(195)" )
				)
				( pin "U5D1.DH73"
					( objectStatus "vss(196)" )
				)
				( pin "U5D1.DH71"
					( objectStatus "vss(197)" )
				)
				( pin "U5D1.DH67"
					( objectStatus "vss(198)" )
				)
				( pin "U5D1.DH41"
					( objectStatus "vss(199)" )
				)
				( pin "U5D1.DH37"
					( objectStatus "vss(200)" )
				)
				( pin "U5D1.DH35"
					( objectStatus "vss(201)" )
				)
				( pin "U5D1.DH33"
					( objectStatus "vss(202)" )
				)
				( pin "U5D1.DH31"
					( objectStatus "vss(203)" )
				)
				( pin "U5D1.DH29"
					( objectStatus "vss(204)" )
				)
				( pin "U5D1.DH27"
					( objectStatus "vss(205)" )
				)
				( pin "U5D1.DH25"
					( objectStatus "vss(206)" )
				)
				( pin "U5D1.DH23"
					( objectStatus "vss(207)" )
				)
				( pin "U5D1.DH15"
					( objectStatus "vss(208)" )
				)
				( pin "U5D1.DH13"
					( objectStatus "vss(209)" )
				)
				( pin "U5D1.DG82"
					( objectStatus "vss(210)" )
				)
				( pin "U5D1.DG80"
					( objectStatus "vss(211)" )
				)
				( pin "U5D1.DG78"
					( objectStatus "vss(212)" )
				)
				( pin "U5D1.DG76"
					( objectStatus "vss(213)" )
				)
				( pin "U5D1.DG68"
					( objectStatus "vss(214)" )
				)
				( pin "U5D1.DG66"
					( objectStatus "vss(215)" )
				)
				( pin "U5D1.DG24"
					( objectStatus "vss(216)" )
				)
				( pin "U5D1.DG16"
					( objectStatus "vss(217)" )
				)
				( pin "U5D1.DG14"
					( objectStatus "vss(218)" )
				)
				( pin "U5D1.H49"
					( objectStatus "vss(219)" )
				)
				( pin "U5D1.DG2"
					( objectStatus "vss(220)" )
				)
				( pin "U5D1.DF85"
					( objectStatus "vss(221)" )
				)
				( pin "U5D1.DF83"
					( objectStatus "vss(222)" )
				)
				( pin "U5D1.DF79"
					( objectStatus "vss(223)" )
				)
				( pin "U5D1.DF73"
					( objectStatus "vss(224)" )
				)
				( pin "U5D1.DF69"
					( objectStatus "vss(225)" )
				)
				( pin "U5D1.DF65"
					( objectStatus "vss(226)" )
				)
				( pin "U5D1.DF41"
					( objectStatus "vss(227)" )
				)
				( pin "U5D1.DF39"
					( objectStatus "vss(228)" )
				)
				( pin "U5D1.DF37"
					( objectStatus "vss(229)" )
				)
				( pin "U5D1.DF35"
					( objectStatus "vss(230)" )
				)
				( pin "U5D1.DF29"
					( objectStatus "vss(231)" )
				)
				( pin "U5D1.DF19"
					( objectStatus "vss(232)" )
				)
				( pin "U5D1.H51"
					( objectStatus "vss(233)" )
				)
				( pin "U5D1.DF7"
					( objectStatus "vss(234)" )
				)
				( pin "U5D1.DF5"
					( objectStatus "vss(235)" )
				)
				( pin "U5D1.DE78"
					( objectStatus "vss(236)" )
				)
				( pin "U5D1.DE72"
					( objectStatus "vss(237)" )
				)
				( pin "U5D1.DE70"
					( objectStatus "vss(238)" )
				)
				( pin "U5D1.DE64"
					( objectStatus "vss(239)" )
				)
				( pin "U5D1.DE36"
					( objectStatus "vss(240)" )
				)
				( pin "U5D1.DE34"
					( objectStatus "vss(241)" )
				)
				( pin "U5D1.DE30"
					( objectStatus "vss(242)" )
				)
				( pin "U5D1.DE28"
					( objectStatus "vss(243)" )
				)
				( pin "U5D1.DE24"
					( objectStatus "vss(244)" )
				)
				( pin "U5D1.DE20"
					( objectStatus "vss(245)" )
				)
				( pin "U5D1.DE18"
					( objectStatus "vss(246)" )
				)
				( pin "U5D1.DE8"
					( objectStatus "vss(247)" )
				)
				( pin "U5D1.DE6"
					( objectStatus "vss(248)" )
				)
				( pin "U5D1.DD83"
					( objectStatus "vss(249)" )
				)
				( pin "U5D1.DD81"
					( objectStatus "vss(250)" )
				)
				( pin "U5D1.DD75"
					( objectStatus "vss(251)" )
				)
				( pin "U5D1.DD73"
					( objectStatus "vss(252)" )
				)
				( pin "U5D1.DD71"
					( objectStatus "vss(253)" )
				)
				( pin "U5D1.DD37"
					( objectStatus "vss(254)" )
				)
				( pin "U5D1.DD33"
					( objectStatus "vss(255)" )
				)
				( pin "U5D1.DD31"
					( objectStatus "vss(256)" )
				)
				( pin "U5D1.DD27"
					( objectStatus "vss(257)" )
				)
				( pin "U5D1.DD23"
					( objectStatus "vss(258)" )
				)
				( pin "U5D1.DD11"
					( objectStatus "vss(259)" )
				)
				( pin "U5D1.DC86"
					( objectStatus "vss(260)" )
				)
				( pin "U5D1.DC84"
					( objectStatus "vss(261)" )
				)
				( pin "U5D1.DC78"
					( objectStatus "vss(262)" )
				)
				( pin "U5D1.DC70"
					( objectStatus "vss(263)" )
				)
				( pin "U5D1.DC68"
					( objectStatus "vss(264)" )
				)
				( pin "U5D1.DC66"
					( objectStatus "vss(265)" )
				)
				( pin "U5D1.DC64"
					( objectStatus "vss(266)" )
				)
				( pin "U5D1.DC42"
					( objectStatus "vss(267)" )
				)
				( pin "U5D1.DC38"
					( objectStatus "vss(268)" )
				)
				( pin "U5D1.DC32"
					( objectStatus "vss(269)" )
				)
				( pin "U5D1.DC26"
					( objectStatus "vss(270)" )
				)
				( pin "U5D1.DC24"
					( objectStatus "vss(271)" )
				)
				( pin "U5D1.DC14"
					( objectStatus "vss(272)" )
				)
				( pin "U5D1.DB85"
					( objectStatus "vss(273)" )
				)
				( pin "U5D1.DB83"
					( objectStatus "vss(274)" )
				)
				( pin "U5D1.DB77"
					( objectStatus "vss(275)" )
				)
				( pin "U5D1.DB73"
					( objectStatus "vss(276)" )
				)
				( pin "U5D1.DB49"
					( objectStatus "vss(277)" )
				)
				( pin "U5D1.DB47"
					( objectStatus "vss(278)" )
				)
				( pin "U5D1.DB41"
					( objectStatus "vss(279)" )
				)
				( pin "U5D1.DB39"
					( objectStatus "vss(280)" )
				)
				( pin "U5D1.DB25"
					( objectStatus "vss(281)" )
				)
				( pin "U5D1.DB23"
					( objectStatus "vss(282)" )
				)
				( pin "U5D1.DB17"
					( objectStatus "vss(283)" )
				)
				( pin "U5D1.DB13"
					( objectStatus "vss(284)" )
				)
				( pin "U5D1.DB3"
					( objectStatus "vss(285)" )
				)
				( pin "U5D1.DA80"
					( objectStatus "vss(286)" )
				)
				( pin "U5D1.DA78"
					( objectStatus "vss(287)" )
				)
				( pin "U5D1.DA76"
					( objectStatus "vss(288)" )
				)
				( pin "U5D1.DA74"
					( objectStatus "vss(289)" )
				)
				( pin "U5D1.DA70"
					( objectStatus "vss(290)" )
				)
				( pin "U5D1.DA64"
					( objectStatus "vss(291)" )
				)
				( pin "U5D1.DA50"
					( objectStatus "vss(292)" )
				)
				( pin "U5D1.DA48"
					( objectStatus "vss(293)" )
				)
			)
			( gate "U5D1"
				( objectStatus "@baseboard_fab2_lib.baseboard_fab2(sch_1):page41_i286" )
				( pin "U5D1.EF79"
					( objectStatus "vss(0)" )
				)
				( pin "U5D1.EF75"
					( objectStatus "vss(1)" )
				)
				( pin "U5D1.EF71"
					( objectStatus "vss(2)" )
				)
				( pin "U5D1.EE78"
					( objectStatus "vss(3)" )
				)
				( pin "U5D1.EE76"
					( objectStatus "vss(4)" )
				)
				( pin "U5D1.EE70"
					( objectStatus "vss(5)" )
				)
				( pin "U5D1.EE36"
					( objectStatus "vss(6)" )
				)
				( pin "U5D1.EE34"
					( objectStatus "vss(7)" )
				)
				( pin "U5D1.EE30"
					( objectStatus "vss(8)" )
				)
				( pin "U5D1.EE28"
					( objectStatus "vss(9)" )
				)
				( pin "U5D1.EE24"
					( objectStatus "vss(10)" )
				)
				( pin "U5D1.ED77"
					( objectStatus "vss(11)" )
				)
				( pin "U5D1.ED35"
					( objectStatus "vss(12)" )
				)
				( pin "U5D1.ED29"
					( objectStatus "vss(13)" )
				)
				( pin "U5D1.ED23"
					( objectStatus "vss(14)" )
				)
				( pin "U5D1.ED15"
					( objectStatus "vss(15)" )
				)
				( pin "U5D1.ED11"
					( objectStatus "vss(16)" )
				)
				( pin "U5D1.EC76"
					( objectStatus "vss(17)" )
				)
				( pin "U5D1.EC74"
					( objectStatus "vss(18)" )
				)
				( pin "U5D1.EC72"
					( objectStatus "vss(19)" )
				)
				( pin "U5D1.EC70"
					( objectStatus "vss(20)" )
				)
				( pin "U5D1.EC10"
					( objectStatus "vss(21)" )
				)
				( pin "U5D1.EB69"
					( objectStatus "vss(22)" )
				)
				( pin "U5D1.EB65"
					( objectStatus "vss(23)" )
				)
				( pin "U5D1.EB41"
					( objectStatus "vss(24)" )
				)
				( pin "U5D1.EB39"
					( objectStatus "vss(25)" )
				)
				( pin "U5D1.EB37"
					( objectStatus "vss(26)" )
				)
				( pin "U5D1.EB35"
					( objectStatus "vss(27)" )
				)
				( pin "U5D1.EB33"
					( objectStatus "vss(28)" )
				)
				( pin "U5D1.EB31"
					( objectStatus "vss(29)" )
				)
				( pin "U5D1.EB29"
					( objectStatus "vss(30)" )
				)
				( pin "U5D1.EB27"
					( objectStatus "vss(31)" )
				)
				( pin "U5D1.EB25"
					( objectStatus "vss(32)" )
				)
				( pin "U5D1.EB23"
					( objectStatus "vss(33)" )
				)
				( pin "U5D1.BR18"
					( objectStatus "vss(34)" )
				)
				( pin "U5D1.EB13"
					( objectStatus "vss(35)" )
				)
				( pin "U5D1.EA82"
					( objectStatus "vss(36)" )
				)
				( pin "U5D1.EA80"
					( objectStatus "vss(37)" )
				)
				( pin "U5D1.EA78"
					( objectStatus "vss(38)" )
				)
				( pin "U5D1.EA76"
					( objectStatus "vss(39)" )
				)
				( pin "U5D1.EA70"
					( objectStatus "vss(40)" )
				)
				( pin "U5D1.EA64"
					( objectStatus "vss(41)" )
				)
				( pin "U5D1.EA42"
					( objectStatus "vss(42)" )
				)
				( pin "U5D1.EA22"
					( objectStatus "vss(43)" )
				)
				( pin "U5D1.EA20"
					( objectStatus "vss(44)" )
				)
				( pin "U5D1.EA16"
					( objectStatus "vss(45)" )
				)
				( pin "U5D1.J16"
					( objectStatus "vss(46)" )
				)
				( pin "U5D1.EA6"
					( objectStatus "vss(47)" )
				)
				( pin "U5D1.DY75"
					( objectStatus "vss(48)" )
				)
				( pin "U5D1.DY71"
					( objectStatus "vss(49)" )
				)
				( pin "U5D1.DY41"
					( objectStatus "vss(50)" )
				)
				( pin "U5D1.DY35"
					( objectStatus "vss(51)" )
				)
				( pin "U5D1.DY29"
					( objectStatus "vss(52)" )
				)
				( pin "U5D1.DY23"
					( objectStatus "vss(53)" )
				)
				( pin "U5D1.DY19"
					( objectStatus "vss(54)" )
				)
				( pin "U5D1.DY5"
					( objectStatus "vss(55)" )
				)
				( pin "U5D1.DW84"
					( objectStatus "vss(56)" )
				)
				( pin "U5D1.DW82"
					( objectStatus "vss(57)" )
				)
				( pin "U5D1.DW8"
					( objectStatus "vss(58)" )
				)
				( pin "U5D1.DW76"
					( objectStatus "vss(59)" )
				)
				( pin "U5D1.DW74"
					( objectStatus "vss(60)" )
				)
				( pin "U5D1.DW72"
					( objectStatus "vss(61)" )
				)
				( pin "U5D1.DW70"
					( objectStatus "vss(62)" )
				)
				( pin "U5D1.DW68"
					( objectStatus "vss(63)" )
				)
				( pin "U5D1.DW66"
					( objectStatus "vss(64)" )
				)
				( pin "U5D1.DW64"
					( objectStatus "vss(65)" )
				)
				( pin "U5D1.DW40"
					( objectStatus "vss(66)" )
				)
				( pin "U5D1.DW36"
					( objectStatus "vss(67)" )
				)
				( pin "U5D1.DW34"
					( objectStatus "vss(68)" )
				)
				( pin "U5D1.DW30"
					( objectStatus "vss(69)" )
				)
				( pin "U5D1.DW28"
					( objectStatus "vss(70)" )
				)
				( pin "U5D1.DW24"
					( objectStatus "vss(71)" )
				)
				( pin "U5D1.DW20"
					( objectStatus "vss(72)" )
				)
				( pin "U5D1.DW12"
					( objectStatus "vss(73)" )
				)
				( pin "U5D1.DV81"
					( objectStatus "vss(74)" )
				)
				( pin "U5D1.DV77"
					( objectStatus "vss(75)" )
				)
				( pin "U5D1.DV73"
					( objectStatus "vss(76)" )
				)
				( pin "U5D1.DV39"
					( objectStatus "vss(77)" )
				)
				( pin "U5D1.DV37"
					( objectStatus "vss(78)" )
				)
				( pin "U5D1.DV33"
					( objectStatus "vss(79)" )
				)
				( pin "U5D1.DV31"
					( objectStatus "vss(80)" )
				)
				( pin "U5D1.DV27"
					( objectStatus "vss(81)" )
				)
				( pin "U5D1.DV25"
					( objectStatus "vss(82)" )
				)
				( pin "U5D1.DV21"
					( objectStatus "vss(83)" )
				)
				( pin "U5D1.DU84"
					( objectStatus "vss(84)" )
				)
				( pin "U5D1.DU82"
					( objectStatus "vss(85)" )
				)
				( pin "U5D1.DU80"
					( objectStatus "vss(86)" )
				)
				( pin "U5D1.DU78"
					( objectStatus "vss(87)" )
				)
				( pin "U5D1.DU72"
					( objectStatus "vss(88)" )
				)
				( pin "U5D1.DU70"
					( objectStatus "vss(89)" )
				)
				( pin "U5D1.DU38"
					( objectStatus "vss(90)" )
				)
				( pin "U5D1.DU32"
					( objectStatus "vss(91)" )
				)
				( pin "U5D1.DU26"
					( objectStatus "vss(92)" )
				)
				( pin "U5D1.DU22"
					( objectStatus "vss(93)" )
				)
				( pin "U5D1.CN14"
					( objectStatus "vss(94)" )
				)
				( pin "U5D1.DU14"
					( objectStatus "vss(95)" )
				)
				( pin "U5D1.DU10"
					( objectStatus "vss(96)" )
				)
				( pin "U5D1.DT85"
					( objectStatus "vss(97)" )
				)
				( pin "U5D1.DT83"
					( objectStatus "vss(98)" )
				)
				( pin "U5D1.DT79"
					( objectStatus "vss(99)" )
				)
				( pin "U5D1.DT69"
					( objectStatus "vss(100)" )
				)
				( pin "U5D1.DT65"
					( objectStatus "vss(101)" )
				)
				( pin "U5D1.DH21"
					( objectStatus "vss(102)" )
				)
				( pin "U5D1.DT17"
					( objectStatus "vss(103)" )
				)
				( pin "U5D1.DT3"
					( objectStatus "vss(104)" )
				)
				( pin "U5D1.DR78"
					( objectStatus "vss(105)" )
				)
				( pin "U5D1.DR76"
					( objectStatus "vss(106)" )
				)
				( pin "U5D1.DR74"
					( objectStatus "vss(107)" )
				)
				( pin "U5D1.DR72"
					( objectStatus "vss(108)" )
				)
				( pin "U5D1.DR70"
					( objectStatus "vss(109)" )
				)
				( pin "U5D1.DR68"
					( objectStatus "vss(110)" )
				)
				( pin "U5D1.DR66"
					( objectStatus "vss(111)" )
				)
				( pin "U5D1.DR42"
					( objectStatus "vss(112)" )
				)
				( pin "U5D1.DR40"
					( objectStatus "vss(113)" )
				)
				( pin "U5D1.DR38"
					( objectStatus "vss(114)" )
				)
				( pin "U5D1.DR36"
					( objectStatus "vss(115)" )
				)
				( pin "U5D1.DR34"
					( objectStatus "vss(116)" )
				)
				( pin "U5D1.DR32"
					( objectStatus "vss(117)" )
				)
				( pin "U5D1.DR30"
					( objectStatus "vss(118)" )
				)
				( pin "U5D1.DR28"
					( objectStatus "vss(119)" )
				)
				( pin "U5D1.DR26"
					( objectStatus "vss(120)" )
				)
				( pin "U5D1.DR24"
					( objectStatus "vss(121)" )
				)
				( pin "U5D1.DR22"
					( objectStatus "vss(122)" )
				)
				( pin "U5D1.DR20"
					( objectStatus "vss(123)" )
				)
				( pin "U5D1.CL22"
					( objectStatus "vss(124)" )
				)
				( pin "U5D1.CA20"
					( objectStatus "vss(125)" )
				)
				( pin "U5D1.DR6"
					( objectStatus "vss(126)" )
				)
				( pin "U5D1.BR26"
					( objectStatus "vss(127)" )
				)
				( pin "U5D1.DP83"
					( objectStatus "vss(128)" )
				)
				( pin "U5D1.DP81"
					( objectStatus "vss(129)" )
				)
				( pin "U5D1.DP71"
					( objectStatus "vss(130)" )
				)
				( pin "U5D1.DP69"
					( objectStatus "vss(131)" )
				)
				( pin "U5D1.DP67"
					( objectStatus "vss(132)" )
				)
				( pin "U5D1.DN78"
					( objectStatus "vss(133)" )
				)
			)
			( gate "C5P18"
				( objectStatus "@baseboard_fab2_lib.baseboard_fab2(sch_1):page42_i2" )
				( pin "C5P18.1"
					( objectStatus "a" )
				)
				( pin "C5P18.2"
					( objectStatus "b" )
				)
			)
			( gate "C5P28"
				( objectStatus "@baseboard_fab2_lib.baseboard_fab2(sch_1):page42_i3" )
				( pin "C5P28.1"
					( objectStatus "a" )
				)
				( pin "C5P28.2"
					( objectStatus "b" )
				)
			)
			( gate "C5P11"
				( objectStatus "@baseboard_fab2_lib.baseboard_fab2(sch_1):page42_i4" )
				( pin "C5P11.1"
					( objectStatus "a" )
				)
				( pin "C5P11.2"
					( objectStatus "b" )
				)
			)
			( gate "C5P10"
				( objectStatus "@baseboard_fab2_lib.baseboard_fab2(sch_1):page42_i6" )
				( pin "C5P10.1"
					( objectStatus "a" )
				)
				( pin "C5P10.2"
					( objectStatus "b" )
				)
			)
			( gate "C4P3"
				( objectStatus "@baseboard_fab2_lib.baseboard_fab2(sch_1):page42_i8" )
				( pin "C4P3.1"
					( objectStatus "a" )
				)
				( pin "C4P3.2"
					( objectStatus "b" )
				)
			)
			( gate "C4P7"
				( objectStatus "@baseboard_fab2_lib.baseboard_fab2(sch_1):page42_i9" )
				( pin "C4P7.1"
					( objectStatus "a" )
				)
				( pin "C4P7.2"
					( objectStatus "b" )
				)
			)
			( gate "C4P1"
				( objectStatus "@baseboard_fab2_lib.baseboard_fab2(sch_1):page42_i10" )
				( pin "C4P1.1"
					( objectStatus "a" )
				)
				( pin "C4P1.2"
					( objectStatus "b" )
				)
			)
			( gate "C4P9"
				( objectStatus "@baseboard_fab2_lib.baseboard_fab2(sch_1):page42_i12" )
				( pin "C4P9.1"
					( objectStatus "a" )
				)
				( pin "C4P9.2"
					( objectStatus "b" )
				)
			)
			( gate "C5P19"
				( objectStatus "@baseboard_fab2_lib.baseboard_fab2(sch_1):page42_i13" )
				( pin "C5P19.1"
					( objectStatus "a" )
				)
				( pin "C5P19.2"
					( objectStatus "b" )
				)
			)
			( gate "C4P4"
				( objectStatus "@baseboard_fab2_lib.baseboard_fab2(sch_1):page42_i14" )
				( pin "C4P4.1"
					( objectStatus "a" )
				)
				( pin "C4P4.2"
					( objectStatus "b" )
				)
			)
			( gate "C4P10"
				( objectStatus "@baseboard_fab2_lib.baseboard_fab2(sch_1):page42_i17" )
				( pin "C4P10.1"
					( objectStatus "a" )
				)
				( pin "C4P10.2"
					( objectStatus "b" )
				)
			)
			( gate "C5P9"
				( objectStatus "@baseboard_fab2_lib.baseboard_fab2(sch_1):page42_i18" )
				( pin "C5P9.1"
					( objectStatus "a" )
				)
				( pin "C5P9.2"
					( objectStatus "b" )
				)
			)
			( gate "C5P8"
				( objectStatus "@baseboard_fab2_lib.baseboard_fab2(sch_1):page42_i19" )
				( pin "C5P8.1"
					( objectStatus "a" )
				)
				( pin "C5P8.2"
					( objectStatus "b" )
				)
			)
			( gate "C5P7"
				( objectStatus "@baseboard_fab2_lib.baseboard_fab2(sch_1):page42_i25" )
				( pin "C5P7.1"
					( objectStatus "a" )
				)
				( pin "C5P7.2"
					( objectStatus "b" )
				)
			)
			( gate "C5P4"
				( objectStatus "@baseboard_fab2_lib.baseboard_fab2(sch_1):page42_i27" )
				( pin "C5P4.1"
					( objectStatus "a" )
				)
				( pin "C5P4.2"
					( objectStatus "b" )
				)
			)
			( gate "C5P23"
				( objectStatus "@baseboard_fab2_lib.baseboard_fab2(sch_1):page42_i28" )
				( pin "C5P23.1"
					( objectStatus "a" )
				)
				( pin "C5P23.2"
					( objectStatus "b" )
				)
			)
			( gate "C5P24"
				( objectStatus "@baseboard_fab2_lib.baseboard_fab2(sch_1):page42_i33" )
				( pin "C5P24.1"
					( objectStatus "a" )
				)
				( pin "C5P24.2"
					( objectStatus "b" )
				)
			)
			( gate "C5P25"
				( objectStatus "@baseboard_fab2_lib.baseboard_fab2(sch_1):page42_i37" )
				( pin "C5P25.1"
					( objectStatus "a" )
				)
				( pin "C5P25.2"
					( objectStatus "b" )
				)
			)
			( gate "C5P6"
				( objectStatus "@baseboard_fab2_lib.baseboard_fab2(sch_1):page42_i38" )
				( pin "C5P6.1"
					( objectStatus "a" )
				)
				( pin "C5P6.2"
					( objectStatus "b" )
				)
			)
			( gate "C5P41"
				( objectStatus "@baseboard_fab2_lib.baseboard_fab2(sch_1):page42_i40" )
				( pin "C5P41.1"
					( objectStatus "a" )
				)
				( pin "C5P41.2"
					( objectStatus "b" )
				)
			)
			( gate "C5P14"
				( objectStatus "@baseboard_fab2_lib.baseboard_fab2(sch_1):page42_i41" )
				( pin "C5P14.1"
					( objectStatus "a" )
				)
				( pin "C5P14.2"
					( objectStatus "b" )
				)
			)
			( gate "C5P5"
				( objectStatus "@baseboard_fab2_lib.baseboard_fab2(sch_1):page42_i42" )
				( pin "C5P5.1"
					( objectStatus "a" )
				)
				( pin "C5P5.2"
					( objectStatus "b" )
				)
			)
			( gate "C5P27"
				( objectStatus "@baseboard_fab2_lib.baseboard_fab2(sch_1):page42_i44" )
				( pin "C5P27.1"
					( objectStatus "a" )
				)
				( pin "C5P27.2"
					( objectStatus "b" )
				)
			)
			( gate "C5P33"
				( objectStatus "@baseboard_fab2_lib.baseboard_fab2(sch_1):page42_i50" )
				( pin "C5P33.1"
					( objectStatus "a" )
				)
				( pin "C5P33.2"
					( objectStatus "b" )
				)
			)
			( gate "C5P35"
				( objectStatus "@baseboard_fab2_lib.baseboard_fab2(sch_1):page42_i51" )
				( pin "C5P35.1"
					( objectStatus "a" )
				)
				( pin "C5P35.2"
					( objectStatus "b" )
				)
			)
			( gate "C5P32"
				( objectStatus "@baseboard_fab2_lib.baseboard_fab2(sch_1):page42_i53" )
				( pin "C5P32.1"
					( objectStatus "a" )
				)
				( pin "C5P32.2"
					( objectStatus "b" )
				)
			)
			( gate "C5P34"
				( objectStatus "@baseboard_fab2_lib.baseboard_fab2(sch_1):page42_i54" )
				( pin "C5P34.1"
					( objectStatus "a" )
				)
				( pin "C5P34.2"
					( objectStatus "b" )
				)
			)
			( gate "C5P22"
				( objectStatus "@baseboard_fab2_lib.baseboard_fab2(sch_1):page42_i55" )
				( pin "C5P22.1"
					( objectStatus "a" )
				)
				( pin "C5P22.2"
					( objectStatus "b" )
				)
			)
			( gate "C5P26"
				( objectStatus "@baseboard_fab2_lib.baseboard_fab2(sch_1):page42_i56" )
				( pin "C5P26.1"
					( objectStatus "a" )
				)
				( pin "C5P26.2"
					( objectStatus "b" )
				)
			)
			( gate "C5P40"
				( objectStatus "@baseboard_fab2_lib.baseboard_fab2(sch_1):page42_i57" )
				( pin "C5P40.1"
					( objectStatus "a" )
				)
				( pin "C5P40.2"
					( objectStatus "b" )
				)
			)
			( gate "C5P42"
				( objectStatus "@baseboard_fab2_lib.baseboard_fab2(sch_1):page42_i59" )
				( pin "C5P42.1"
					( objectStatus "a" )
				)
				( pin "C5P42.2"
					( objectStatus "b" )
				)
			)
			( gate "C5P43"
				( objectStatus "@baseboard_fab2_lib.baseboard_fab2(sch_1):page42_i60" )
				( pin "C5P43.1"
					( objectStatus "a" )
				)
				( pin "C5P43.2"
					( objectStatus "b" )
				)
			)
			( gate "C5P44"
				( objectStatus "@baseboard_fab2_lib.baseboard_fab2(sch_1):page42_i61" )
				( pin "C5P44.1"
					( objectStatus "a" )
				)
				( pin "C5P44.2"
					( objectStatus "b" )
				)
			)
			( gate "C5P37"
				( objectStatus "@baseboard_fab2_lib.baseboard_fab2(sch_1):page42_i63" )
				( pin "C5P37.1"
					( objectStatus "a" )
				)
				( pin "C5P37.2"
					( objectStatus "b" )
				)
			)
			( gate "C5P36"
				( objectStatus "@baseboard_fab2_lib.baseboard_fab2(sch_1):page42_i65" )
				( pin "C5P36.1"
					( objectStatus "a" )
				)
				( pin "C5P36.2"
					( objectStatus "b" )
				)
			)
			( gate "C6D8"
				( objectStatus "@baseboard_fab2_lib.baseboard_fab2(sch_1):page42_i68" )
				( pin "C6D8.1"
					( objectStatus "a" )
				)
				( pin "C6D8.2"
					( objectStatus "b" )
				)
			)
			( gate "C5D38"
				( objectStatus "@baseboard_fab2_lib.baseboard_fab2(sch_1):page42_i69" )
				( pin "C5D38.1"
					( objectStatus "a" )
				)
				( pin "C5D38.2"
					( objectStatus "b" )
				)
			)
			( gate "C5D37"
				( objectStatus "@baseboard_fab2_lib.baseboard_fab2(sch_1):page42_i70" )
				( pin "C5D37.1"
					( objectStatus "a" )
				)
				( pin "C5D37.2"
					( objectStatus "b" )
				)
			)
			( gate "C6D7"
				( objectStatus "@baseboard_fab2_lib.baseboard_fab2(sch_1):page42_i72" )
				( pin "C6D7.1"
					( objectStatus "a" )
				)
				( pin "C6D7.2"
					( objectStatus "b" )
				)
			)
			( gate "C6D4"
				( objectStatus "@baseboard_fab2_lib.baseboard_fab2(sch_1):page42_i74" )
				( pin "C6D4.1"
					( objectStatus "a" )
				)
				( pin "C6D4.2"
					( objectStatus "b" )
				)
			)
			( gate "C6D5"
				( objectStatus "@baseboard_fab2_lib.baseboard_fab2(sch_1):page42_i75" )
				( pin "C6D5.1"
					( objectStatus "a" )
				)
				( pin "C6D5.2"
					( objectStatus "b" )
				)
			)
			( gate "C6D2"
				( objectStatus "@baseboard_fab2_lib.baseboard_fab2(sch_1):page42_i77" )
				( pin "C6D2.1"
					( objectStatus "a" )
				)
				( pin "C6D2.2"
					( objectStatus "b" )
				)
			)
			( gate "C6D3"
				( objectStatus "@baseboard_fab2_lib.baseboard_fab2(sch_1):page42_i80" )
				( pin "C6D3.1"
					( objectStatus "a" )
				)
				( pin "C6D3.2"
					( objectStatus "b" )
				)
			)
			( gate "C6D6"
				( objectStatus "@baseboard_fab2_lib.baseboard_fab2(sch_1):page42_i81" )
				( pin "C6D6.1"
					( objectStatus "a" )
				)
				( pin "C6D6.2"
					( objectStatus "b" )
				)
			)
			( gate "C5D51"
				( objectStatus "@baseboard_fab2_lib.baseboard_fab2(sch_1):page42_i83" )
				( pin "C5D51.1"
					( objectStatus "a" )
				)
				( pin "C5D51.2"
					( objectStatus "b" )
				)
			)
			( gate "C5D21"
				( objectStatus "@baseboard_fab2_lib.baseboard_fab2(sch_1):page42_i88" )
				( pin "C5D21.1"
					( objectStatus "a" )
				)
				( pin "C5D21.2"
					( objectStatus "b" )
				)
			)
			( gate "C5D50"
				( objectStatus "@baseboard_fab2_lib.baseboard_fab2(sch_1):page42_i89" )
				( pin "C5D50.1"
					( objectStatus "a" )
				)
				( pin "C5D50.2"
					( objectStatus "b" )
				)
			)
			( gate "C5D48"
				( objectStatus "@baseboard_fab2_lib.baseboard_fab2(sch_1):page42_i90" )
				( pin "C5D48.1"
					( objectStatus "a" )
				)
				( pin "C5D48.2"
					( objectStatus "b" )
				)
			)
			( gate "C5D13"
				( objectStatus "@baseboard_fab2_lib.baseboard_fab2(sch_1):page42_i91" )
				( pin "C5D13.1"
					( objectStatus "a" )
				)
				( pin "C5D13.2"
					( objectStatus "b" )
				)
			)
			( gate "C5D11"
				( objectStatus "@baseboard_fab2_lib.baseboard_fab2(sch_1):page42_i93" )
				( pin "C5D11.1"
					( objectStatus "a" )
				)
				( pin "C5D11.2"
					( objectStatus "b" )
				)
			)
			( gate "C5D12"
				( objectStatus "@baseboard_fab2_lib.baseboard_fab2(sch_1):page42_i94" )
				( pin "C5D12.1"
					( objectStatus "a" )
				)
				( pin "C5D12.2"
					( objectStatus "b" )
				)
			)
			( gate "C5D23"
				( objectStatus "@baseboard_fab2_lib.baseboard_fab2(sch_1):page42_i98" )
				( pin "C5D23.1"
					( objectStatus "a" )
				)
				( pin "C5D23.2"
					( objectStatus "b" )
				)
			)
			( gate "C5D28"
				( objectStatus "@baseboard_fab2_lib.baseboard_fab2(sch_1):page42_i100" )
				( pin "C5D28.1"
					( objectStatus "a" )
				)
				( pin "C5D28.2"
					( objectStatus "b" )
				)
			)
			( gate "C5D29"
				( objectStatus "@baseboard_fab2_lib.baseboard_fab2(sch_1):page42_i102" )
				( pin "C5D29.1"
					( objectStatus "a" )
				)
				( pin "C5D29.2"
					( objectStatus "b" )
				)
			)
			( gate "C5D32"
				( objectStatus "@baseboard_fab2_lib.baseboard_fab2(sch_1):page42_i103" )
				( pin "C5D32.1"
					( objectStatus "a" )
				)
				( pin "C5D32.2"
					( objectStatus "b" )
				)
			)
			( gate "C5D47"
				( objectStatus "@baseboard_fab2_lib.baseboard_fab2(sch_1):page42_i104" )
				( pin "C5D47.1"
					( objectStatus "a" )
				)
				( pin "C5D47.2"
					( objectStatus "b" )
				)
			)
			( gate "C5D31"
				( objectStatus "@baseboard_fab2_lib.baseboard_fab2(sch_1):page42_i106" )
				( pin "C5D31.1"
					( objectStatus "a" )
				)
				( pin "C5D31.2"
					( objectStatus "b" )
				)
			)
			( gate "C5D46"
				( objectStatus "@baseboard_fab2_lib.baseboard_fab2(sch_1):page42_i107" )
				( pin "C5D46.1"
					( objectStatus "a" )
				)
				( pin "C5D46.2"
					( objectStatus "b" )
				)
			)
			( gate "C5D10"
				( objectStatus "@baseboard_fab2_lib.baseboard_fab2(sch_1):page42_i108" )
				( pin "C5D10.1"
					( objectStatus "a" )
				)
				( pin "C5D10.2"
					( objectStatus "b" )
				)
			)
			( gate "C5D27"
				( objectStatus "@baseboard_fab2_lib.baseboard_fab2(sch_1):page42_i109" )
				( pin "C5D27.1"
					( objectStatus "a" )
				)
				( pin "C5D27.2"
					( objectStatus "b" )
				)
			)
			( gate "C5D30"
				( objectStatus "@baseboard_fab2_lib.baseboard_fab2(sch_1):page42_i111" )
				( pin "C5D30.1"
					( objectStatus "a" )
				)
				( pin "C5D30.2"
					( objectStatus "b" )
				)
			)
			( gate "C5D60"
				( objectStatus "@baseboard_fab2_lib.baseboard_fab2(sch_1):page42_i112" )
				( pin "C5D60.1"
					( objectStatus "a" )
				)
				( pin "C5D60.2"
					( objectStatus "b" )
				)
			)
			( gate "C5D61"
				( objectStatus "@baseboard_fab2_lib.baseboard_fab2(sch_1):page42_i113" )
				( pin "C5D61.1"
					( objectStatus "a" )
				)
				( pin "C5D61.2"
					( objectStatus "b" )
				)
			)
			( gate "C5D41"
				( objectStatus "@baseboard_fab2_lib.baseboard_fab2(sch_1):page42_i114" )
				( pin "C5D41.1"
					( objectStatus "a" )
				)
				( pin "C5D41.2"
					( objectStatus "b" )
				)
			)
			( gate "C5D40"
				( objectStatus "@baseboard_fab2_lib.baseboard_fab2(sch_1):page42_i115" )
				( pin "C5D40.1"
					( objectStatus "a" )
				)
				( pin "C5D40.2"
					( objectStatus "b" )
				)
			)
			( gate "C5D14"
				( objectStatus "@baseboard_fab2_lib.baseboard_fab2(sch_1):page42_i117" )
				( pin "C5D14.1"
					( objectStatus "a" )
				)
				( pin "C5D14.2"
					( objectStatus "b" )
				)
			)
			( gate "C5D17"
				( objectStatus "@baseboard_fab2_lib.baseboard_fab2(sch_1):page42_i118" )
				( pin "C5D17.1"
					( objectStatus "a" )
				)
				( pin "C5D17.2"
					( objectStatus "b" )
				)
			)
			( gate "C5D58"
				( objectStatus "@baseboard_fab2_lib.baseboard_fab2(sch_1):page42_i120" )
				( pin "C5D58.1"
					( objectStatus "a" )
				)
				( pin "C5D58.2"
					( objectStatus "b" )
				)
			)
			( gate "C5D16"
				( objectStatus "@baseboard_fab2_lib.baseboard_fab2(sch_1):page42_i123" )
				( pin "C5D16.1"
					( objectStatus "a" )
				)
				( pin "C5D16.2"
					( objectStatus "b" )
				)
			)
			( gate "C5D5"
				( objectStatus "@baseboard_fab2_lib.baseboard_fab2(sch_1):page42_i125" )
				( pin "C5D5.1"
					( objectStatus "a" )
				)
				( pin "C5D5.2"
					( objectStatus "b" )
				)
			)
			( gate "C5D1"
				( objectStatus "@baseboard_fab2_lib.baseboard_fab2(sch_1):page42_i126" )
				( pin "C5D1.1"
					( objectStatus "a" )
				)
				( pin "C5D1.2"
					( objectStatus "b" )
				)
			)
			( gate "C5D4"
				( objectStatus "@baseboard_fab2_lib.baseboard_fab2(sch_1):page42_i127" )
				( pin "C5D4.1"
					( objectStatus "a" )
				)
				( pin "C5D4.2"
					( objectStatus "b" )
				)
			)
			( gate "C5D19"
				( objectStatus "@baseboard_fab2_lib.baseboard_fab2(sch_1):page42_i128" )
				( pin "C5D19.1"
					( objectStatus "a" )
				)
				( pin "C5D19.2"
					( objectStatus "b" )
				)
			)
			( gate "C5D59"
				( objectStatus "@baseboard_fab2_lib.baseboard_fab2(sch_1):page42_i129" )
				( pin "C5D59.1"
					( objectStatus "a" )
				)
				( pin "C5D59.2"
					( objectStatus "b" )
				)
			)
			( gate "C5D3"
				( objectStatus "@baseboard_fab2_lib.baseboard_fab2(sch_1):page42_i130" )
				( pin "C5D3.1"
					( objectStatus "a" )
				)
				( pin "C5D3.2"
					( objectStatus "b" )
				)
			)
			( gate "C5D43"
				( objectStatus "@baseboard_fab2_lib.baseboard_fab2(sch_1):page42_i131" )
				( pin "C5D43.1"
					( objectStatus "a" )
				)
				( pin "C5D43.2"
					( objectStatus "b" )
				)
			)
			( gate "C5D15"
				( objectStatus "@baseboard_fab2_lib.baseboard_fab2(sch_1):page42_i132" )
				( pin "C5D15.1"
					( objectStatus "a" )
				)
				( pin "C5D15.2"
					( objectStatus "b" )
				)
			)
			( gate "C5D18"
				( objectStatus "@baseboard_fab2_lib.baseboard_fab2(sch_1):page42_i134" )
				( pin "C5D18.1"
					( objectStatus "a" )
				)
				( pin "C5D18.2"
					( objectStatus "b" )
				)
			)
			( gate "C5D42"
				( objectStatus "@baseboard_fab2_lib.baseboard_fab2(sch_1):page42_i135" )
				( pin "C5D42.1"
					( objectStatus "a" )
				)
				( pin "C5D42.2"
					( objectStatus "b" )
				)
			)
			( gate "C5D2"
				( objectStatus "@baseboard_fab2_lib.baseboard_fab2(sch_1):page42_i136" )
				( pin "C5D2.1"
					( objectStatus "a" )
				)
				( pin "C5D2.2"
					( objectStatus "b" )
				)
			)
			( gate "C5D24"
				( objectStatus "@baseboard_fab2_lib.baseboard_fab2(sch_1):page42_i138" )
				( pin "C5D24.1"
					( objectStatus "a" )
				)
				( pin "C5D24.2"
					( objectStatus "b" )
				)
			)
			( gate "C5D39"
				( objectStatus "@baseboard_fab2_lib.baseboard_fab2(sch_1):page42_i140" )
				( pin "C5D39.1"
					( objectStatus "a" )
				)
				( pin "C5D39.2"
					( objectStatus "b" )
				)
			)
			( gate "C5D44"
				( objectStatus "@baseboard_fab2_lib.baseboard_fab2(sch_1):page42_i142" )
				( pin "C5D44.1"
					( objectStatus "a" )
				)
				( pin "C5D44.2"
					( objectStatus "b" )
				)
			)
			( gate "C6D9"
				( objectStatus "@baseboard_fab2_lib.baseboard_fab2(sch_1):page42_i145" )
				( pin "C6D9.1"
					( objectStatus "a" )
				)
				( pin "C6D9.2"
					( objectStatus "b" )
				)
			)
			( gate "C6D10"
				( objectStatus "@baseboard_fab2_lib.baseboard_fab2(sch_1):page42_i147" )
				( pin "C6D10.1"
					( objectStatus "a" )
				)
				( pin "C6D10.2"
					( objectStatus "b" )
				)
			)
			( gate "C5P30"
				( objectStatus "@baseboard_fab2_lib.baseboard_fab2(sch_1):page42_i148" )
				( pin "C5P30.1"
					( objectStatus "a" )
				)
				( pin "C5P30.2"
					( objectStatus "b" )
				)
			)
			( gate "C5P29"
				( objectStatus "@baseboard_fab2_lib.baseboard_fab2(sch_1):page42_i149" )
				( pin "C5P29.1"
					( objectStatus "a" )
				)
				( pin "C5P29.2"
					( objectStatus "b" )
				)
			)
			( gate "C5D36"
				( objectStatus "@baseboard_fab2_lib.baseboard_fab2(sch_1):page42_i151" )
				( pin "C5D36.1"
					( objectStatus "a" )
				)
				( pin "C5D36.2"
					( objectStatus "b" )
				)
			)
			( gate "C5D49"
				( objectStatus "@baseboard_fab2_lib.baseboard_fab2(sch_1):page42_i152" )
				( pin "C5D49.1"
					( objectStatus "a" )
				)
				( pin "C5D49.2"
					( objectStatus "b" )
				)
			)
			( gate "C5D22"
				( objectStatus "@baseboard_fab2_lib.baseboard_fab2(sch_1):page42_i153" )
				( pin "C5D22.1"
					( objectStatus "a" )
				)
				( pin "C5D22.2"
					( objectStatus "b" )
				)
			)
			( gate "C5D26"
				( objectStatus "@baseboard_fab2_lib.baseboard_fab2(sch_1):page42_i154" )
				( pin "C5D26.1"
					( objectStatus "a" )
				)
				( pin "C5D26.2"
					( objectStatus "b" )
				)
			)
			( gate "C5D25"
				( objectStatus "@baseboard_fab2_lib.baseboard_fab2(sch_1):page42_i155" )
				( pin "C5D25.1"
					( objectStatus "a" )
				)
				( pin "C5D25.2"
					( objectStatus "b" )
				)
			)
			( gate "C5D45"
				( objectStatus "@baseboard_fab2_lib.baseboard_fab2(sch_1):page42_i156" )
				( pin "C5D45.1"
					( objectStatus "a" )
				)
				( pin "C5D45.2"
					( objectStatus "b" )
				)
			)
			( gate "C5P31"
				( objectStatus "@baseboard_fab2_lib.baseboard_fab2(sch_1):page42_i162" )
				( pin "C5P31.1"
					( objectStatus "a" )
				)
				( pin "C5P31.2"
					( objectStatus "b" )
				)
			)
			( gate "C4P2"
				( objectStatus "@baseboard_fab2_lib.baseboard_fab2(sch_1):page42_i163" )
				( pin "C4P2.1"
					( objectStatus "a" )
				)
				( pin "C4P2.2"
					( objectStatus "b" )
				)
			)
			( gate "C4P6"
				( objectStatus "@baseboard_fab2_lib.baseboard_fab2(sch_1):page42_i164" )
				( pin "C4P6.1"
					( objectStatus "a" )
				)
				( pin "C4P6.2"
					( objectStatus "b" )
				)
			)
			( gate "C4P5"
				( objectStatus "@baseboard_fab2_lib.baseboard_fab2(sch_1):page42_i172" )
				( pin "C4P5.1"
					( objectStatus "a" )
				)
				( pin "C4P5.2"
					( objectStatus "b" )
				)
			)
			( gate "C5D20"
				( objectStatus "@baseboard_fab2_lib.baseboard_fab2(sch_1):page42_i173" )
				( pin "C5D20.1"
					( objectStatus "a" )
				)
				( pin "C5D20.2"
					( objectStatus "b" )
				)
			)
			( gate "C5D33"
				( objectStatus "@baseboard_fab2_lib.baseboard_fab2(sch_1):page42_i174" )
				( pin "C5D33.1"
					( objectStatus "a" )
				)
				( pin "C5D33.2"
					( objectStatus "b" )
				)
			)
			( gate "C5D34"
				( objectStatus "@baseboard_fab2_lib.baseboard_fab2(sch_1):page42_i175" )
				( pin "C5D34.1"
					( objectStatus "a" )
				)
				( pin "C5D34.2"
					( objectStatus "b" )
				)
			)
			( gate "C5D35"
				( objectStatus "@baseboard_fab2_lib.baseboard_fab2(sch_1):page42_i176" )
				( pin "C5D35.1"
					( objectStatus "a" )
				)
				( pin "C5D35.2"
					( objectStatus "b" )
				)
			)
			( gate "C4P8"
				( objectStatus "@baseboard_fab2_lib.baseboard_fab2(sch_1):page42_i178" )
				( pin "C4P8.1"
					( objectStatus "a" )
				)
				( pin "C4P8.2"
					( objectStatus "b" )
				)
			)
			( gate "C5D53"
				( objectStatus "@baseboard_fab2_lib.baseboard_fab2(sch_1):page42_i179" )
				( pin "C5D53.1"
					( objectStatus "a" )
				)
				( pin "C5D53.2"
					( objectStatus "b" )
				)
			)
			( gate "C5D52"
				( objectStatus "@baseboard_fab2_lib.baseboard_fab2(sch_1):page42_i180" )
				( pin "C5D52.1"
					( objectStatus "a" )
				)
				( pin "C5D52.2"
					( objectStatus "b" )
				)
			)
			( gate "C5P12"
				( objectStatus "@baseboard_fab2_lib.baseboard_fab2(sch_1):page42_i183" )
				( pin "C5P12.1"
					( objectStatus "a" )
				)
				( pin "C5P12.2"
					( objectStatus "b" )
				)
			)
			( gate "C5P21"
				( objectStatus "@baseboard_fab2_lib.baseboard_fab2(sch_1):page42_i184" )
				( pin "C5P21.1"
					( objectStatus "a" )
				)
				( pin "C5P21.2"
					( objectStatus "b" )
				)
			)
			( gate "C5P20"
				( objectStatus "@baseboard_fab2_lib.baseboard_fab2(sch_1):page42_i185" )
				( pin "C5P20.1"
					( objectStatus "a" )
				)
				( pin "C5P20.2"
					( objectStatus "b" )
				)
			)
			( gate "C5P13"
				( objectStatus "@baseboard_fab2_lib.baseboard_fab2(sch_1):page42_i186" )
				( pin "C5P13.1"
					( objectStatus "a" )
				)
				( pin "C5P13.2"
					( objectStatus "b" )
				)
			)
			( gate "C5P15"
				( objectStatus "@baseboard_fab2_lib.baseboard_fab2(sch_1):page42_i187" )
				( pin "C5P15.1"
					( objectStatus "a" )
				)
				( pin "C5P15.2"
					( objectStatus "b" )
				)
			)
			( gate "C5P16"
				( objectStatus "@baseboard_fab2_lib.baseboard_fab2(sch_1):page42_i188" )
				( pin "C5P16.1"
					( objectStatus "a" )
				)
				( pin "C5P16.2"
					( objectStatus "b" )
				)
			)
			( gate "C5P3"
				( objectStatus "@baseboard_fab2_lib.baseboard_fab2(sch_1):page42_i189" )
				( pin "C5P3.1"
					( objectStatus "a" )
				)
				( pin "C5P3.2"
					( objectStatus "b" )
				)
			)
			( gate "C5P17"
				( objectStatus "@baseboard_fab2_lib.baseboard_fab2(sch_1):page42_i190" )
				( pin "C5P17.1"
					( objectStatus "a" )
				)
				( pin "C5P17.2"
					( objectStatus "b" )
				)
			)
			( gate "J4G1"
				( objectStatus "@baseboard_fab2_lib.baseboard_fab2(sch_1):page43_i1" )
				( pin "J4G1.79"
					( objectStatus "a0" )
				)
				( pin "J4G1.72"
					( objectStatus "a1" )
				)
				( pin "J4G1.216"
					( objectStatus "a2" )
				)
				( pin "J4G1.71"
					( objectStatus "a3" )
				)
				( pin "J4G1.214"
					( objectStatus "a4" )
				)
				( pin "J4G1.213"
					( objectStatus "a5" )
				)
				( pin "J4G1.69"
					( objectStatus "a6" )
				)
				( pin "J4G1.211"
					( objectStatus "a7" )
				)
				( pin "J4G1.68"
					( objectStatus "a8" )
				)
				( pin "J4G1.66"
					( objectStatus "a9" )
				)
				( pin "J4G1.225"
					( objectStatus "a10" )
				)
				( pin "J4G1.210"
					( objectStatus "a11" )
				)
				( pin "J4G1.65"
					( objectStatus "a12" )
				)
				( pin "J4G1.232"
					( objectStatus "a13" )
				)
				( pin "J4G1.228"
					( objectStatus "a14_we_n" )
				)
				( pin "J4G1.86"
					( objectStatus "a15_cas_n" )
				)
				( pin "J4G1.82"
					( objectStatus "a16_ras_n" )
				)
				( pin "J4G1.234"
					( objectStatus "a17" )
				)
				( pin "J4G1.62"
					( objectStatus "act_n" )
				)
				( pin "J4G1.208"
					( objectStatus "alert_n" )
				)
				( pin "J4G1.81"
					( objectStatus "ba(0)" )
				)
				( pin "J4G1.224"
					( objectStatus "ba(1)" )
				)
				( pin "J4G1.63"
					( objectStatus "bg(0)" )
				)
				( pin "J4G1.207"
					( objectStatus "bg(1)" )
				)
				( pin "J4G1.235"
					( objectStatus "c(2)" )
				)
				( pin "J4G1.49"
					( objectStatus "cb(0)" )
				)
				( pin "J4G1.194"
					( objectStatus "cb(1)" )
				)
				( pin "J4G1.56"
					( objectStatus "cb(2)" )
				)
				( pin "J4G1.201"
					( objectStatus "cb(3)" )
				)
				( pin "J4G1.47"
					( objectStatus "cb(4)" )
				)
				( pin "J4G1.192"
					( objectStatus "cb(5)" )
				)
				( pin "J4G1.54"
					( objectStatus "cb(6)" )
				)
				( pin "J4G1.199"
					( objectStatus "cb(7)" )
				)
				( pin "J4G1.75"
					( objectStatus "ck0n" )
				)
				( pin "J4G1.74"
					( objectStatus "ck0p" )
				)
				( pin "J4G1.219"
					( objectStatus "ck1n" )
				)
				( pin "J4G1.218"
					( objectStatus "ck1p" )
				)
				( pin "J4G1.60"
					( objectStatus "cke(0)" )
				)
				( pin "J4G1.203"
					( objectStatus "cke(1)" )
				)
				( pin "J4G1.5"
					( objectStatus "dq(0)" )
				)
				( pin "J4G1.150"
					( objectStatus "dq(1)" )
				)
				( pin "J4G1.12"
					( objectStatus "dq(2)" )
				)
				( pin "J4G1.157"
					( objectStatus "dq(3)" )
				)
				( pin "J4G1.3"
					( objectStatus "dq(4)" )
				)
				( pin "J4G1.148"
					( objectStatus "dq(5)" )
				)
				( pin "J4G1.10"
					( objectStatus "dq(6)" )
				)
				( pin "J4G1.155"
					( objectStatus "dq(7)" )
				)
				( pin "J4G1.16"
					( objectStatus "dq(8)" )
				)
				( pin "J4G1.161"
					( objectStatus "dq(9)" )
				)
				( pin "J4G1.23"
					( objectStatus "dq(10)" )
				)
				( pin "J4G1.168"
					( objectStatus "dq(11)" )
				)
				( pin "J4G1.14"
					( objectStatus "dq(12)" )
				)
				( pin "J4G1.159"
					( objectStatus "dq(13)" )
				)
				( pin "J4G1.21"
					( objectStatus "dq(14)" )
				)
				( pin "J4G1.166"
					( objectStatus "dq(15)" )
				)
				( pin "J4G1.27"
					( objectStatus "dq(16)" )
				)
				( pin "J4G1.172"
					( objectStatus "dq(17)" )
				)
				( pin "J4G1.34"
					( objectStatus "dq(18)" )
				)
				( pin "J4G1.179"
					( objectStatus "dq(19)" )
				)
				( pin "J4G1.25"
					( objectStatus "dq(20)" )
				)
				( pin "J4G1.170"
					( objectStatus "dq(21)" )
				)
				( pin "J4G1.32"
					( objectStatus "dq(22)" )
				)
				( pin "J4G1.177"
					( objectStatus "dq(23)" )
				)
				( pin "J4G1.38"
					( objectStatus "dq(24)" )
				)
				( pin "J4G1.183"
					( objectStatus "dq(25)" )
				)
				( pin "J4G1.45"
					( objectStatus "dq(26)" )
				)
				( pin "J4G1.190"
					( objectStatus "dq(27)" )
				)
				( pin "J4G1.36"
					( objectStatus "dq(28)" )
				)
				( pin "J4G1.181"
					( objectStatus "dq(29)" )
				)
				( pin "J4G1.43"
					( objectStatus "dq(30)" )
				)
				( pin "J4G1.188"
					( objectStatus "dq(31)" )
				)
				( pin "J4G1.97"
					( objectStatus "dq(32)" )
				)
				( pin "J4G1.242"
					( objectStatus "dq(33)" )
				)
				( pin "J4G1.104"
					( objectStatus "dq(34)" )
				)
				( pin "J4G1.249"
					( objectStatus "dq(35)" )
				)
				( pin "J4G1.95"
					( objectStatus "dq(36)" )
				)
				( pin "J4G1.240"
					( objectStatus "dq(37)" )
				)
				( pin "J4G1.102"
					( objectStatus "dq(38)" )
				)
				( pin "J4G1.247"
					( objectStatus "dq(39)" )
				)
				( pin "J4G1.108"
					( objectStatus "dq(40)" )
				)
				( pin "J4G1.253"
					( objectStatus "dq(41)" )
				)
				( pin "J4G1.115"
					( objectStatus "dq(42)" )
				)
				( pin "J4G1.260"
					( objectStatus "dq(43)" )
				)
				( pin "J4G1.106"
					( objectStatus "dq(44)" )
				)
				( pin "J4G1.251"
					( objectStatus "dq(45)" )
				)
				( pin "J4G1.113"
					( objectStatus "dq(46)" )
				)
				( pin "J4G1.258"
					( objectStatus "dq(47)" )
				)
				( pin "J4G1.119"
					( objectStatus "dq(48)" )
				)
				( pin "J4G1.264"
					( objectStatus "dq(49)" )
				)
				( pin "J4G1.126"
					( objectStatus "dq(50)" )
				)
				( pin "J4G1.271"
					( objectStatus "dq(51)" )
				)
				( pin "J4G1.117"
					( objectStatus "dq(52)" )
				)
				( pin "J4G1.262"
					( objectStatus "dq(53)" )
				)
				( pin "J4G1.124"
					( objectStatus "dq(54)" )
				)
				( pin "J4G1.269"
					( objectStatus "dq(55)" )
				)
				( pin "J4G1.130"
					( objectStatus "dq(56)" )
				)
				( pin "J4G1.275"
					( objectStatus "dq(57)" )
				)
				( pin "J4G1.137"
					( objectStatus "dq(58)" )
				)
				( pin "J4G1.282"
					( objectStatus "dq(59)" )
				)
				( pin "J4G1.128"
					( objectStatus "dq(60)" )
				)
				( pin "J4G1.273"
					( objectStatus "dq(61)" )
				)
				( pin "J4G1.135"
					( objectStatus "dq(62)" )
				)
				( pin "J4G1.280"
					( objectStatus "dq(63)" )
				)
				( pin "J4G1.78"
					( objectStatus "event_n" )
				)
				( pin "J4G1.87"
					( objectStatus "odt(0)" )
				)
				( pin "J4G1.91"
					( objectStatus "odt(1)" )
				)
				( pin "J4G1.222"
					( objectStatus "par" )
				)
				( pin "J4G1.58"
					( objectStatus "reset_n" )
				)
				( pin "J4G1.205"
					( objectStatus "rfu(0)" )
				)
				( pin "J4G1.227"
					( objectStatus "rfu(1)" )
				)
				( pin "J4G1.144"
					( objectStatus "rfu(2)" )
				)
				( pin "J4G1.84"
					( objectStatus "s0_n" )
				)
				( pin "J4G1.89"
					( objectStatus "s1_n" )
				)
				( pin "J4G1.93"
					( objectStatus "s2_n_c(0)" )
				)
				( pin "J4G1.237"
					( objectStatus "s3_n_c(1)" )
				)
				( pin "J4G1.139"
					( objectStatus "sa(0)" )
				)
				( pin "J4G1.140"
					( objectStatus "sa(1)" )
				)
				( pin "J4G1.238"
					( objectStatus "sa(2)" )
				)
				( pin "J4G1.230"
					( objectStatus "save_n_nc" )
				)
				( pin "J4G1.141"
					( objectStatus "scl" )
				)
				( pin "J4G1.285"
					( objectStatus "sda" )
				)
				( pin "J4G1.284"
					( objectStatus "vddspd" )
				)
				( pin "J4G1.146"
					( objectStatus "vrefca" )
				)
			)
			( gate "J4G1"
				( objectStatus "@baseboard_fab2_lib.baseboard_fab2(sch_1):page43_i2" )
				( pin "J4G1.152"
					( objectStatus "dqs0n" )
				)
				( pin "J4G1.153"
					( objectStatus "dqs0p" )
				)
				( pin "J4G1.163"
					( objectStatus "dqs1n" )
				)
				( pin "J4G1.164"
					( objectStatus "dqs1p" )
				)
				( pin "J4G1.174"
					( objectStatus "dqs2n" )
				)
				( pin "J4G1.175"
					( objectStatus "dqs2p" )
				)
				( pin "J4G1.185"
					( objectStatus "dqs3n" )
				)
				( pin "J4G1.186"
					( objectStatus "dqs3p" )
				)
				( pin "J4G1.244"
					( objectStatus "dqs4n" )
				)
				( pin "J4G1.245"
					( objectStatus "dqs4p" )
				)
				( pin "J4G1.255"
					( objectStatus "dqs5n" )
				)
				( pin "J4G1.256"
					( objectStatus "dqs5p" )
				)
				( pin "J4G1.266"
					( objectStatus "dqs6n" )
				)
				( pin "J4G1.267"
					( objectStatus "dqs6p" )
				)
				( pin "J4G1.277"
					( objectStatus "dqs7n" )
				)
				( pin "J4G1.278"
					( objectStatus "dqs7p" )
				)
				( pin "J4G1.196"
					( objectStatus "dqs8n" )
				)
				( pin "J4G1.197"
					( objectStatus "dqs8p" )
				)
				( pin "J4G1.8"
					( objectStatus "dqs9n" )
				)
				( pin "J4G1.7"
					( objectStatus "dqs9p" )
				)
				( pin "J4G1.19"
					( objectStatus "dqs10n" )
				)
				( pin "J4G1.18"
					( objectStatus "dqs10p" )
				)
				( pin "J4G1.30"
					( objectStatus "dqs11n" )
				)
				( pin "J4G1.29"
					( objectStatus "dqs11p" )
				)
				( pin "J4G1.41"
					( objectStatus "dqs12n" )
				)
				( pin "J4G1.40"
					( objectStatus "dqs12p" )
				)
				( pin "J4G1.100"
					( objectStatus "dqs13n" )
				)
				( pin "J4G1.99"
					( objectStatus "dqs13p" )
				)
				( pin "J4G1.111"
					( objectStatus "dqs14n" )
				)
				( pin "J4G1.110"
					( objectStatus "dqs14p" )
				)
				( pin "J4G1.122"
					( objectStatus "dqs15n" )
				)
				( pin "J4G1.121"
					( objectStatus "dqs15p" )
				)
				( pin "J4G1.133"
					( objectStatus "dqs16n" )
				)
				( pin "J4G1.132"
					( objectStatus "dqs16p" )
				)
				( pin "J4G1.52"
					( objectStatus "dqs17n" )
				)
				( pin "J4G1.51"
					( objectStatus "dqs17p" )
				)
			)
			( gate "J4G1"
				( objectStatus "@baseboard_fab2_lib.baseboard_fab2(sch_1):page43_i259" )
				( pin "J4G1.283"
					( objectStatus "vss(0)" )
				)
				( pin "J4G1.281"
					( objectStatus "vss(1)" )
				)
				( pin "J4G1.279"
					( objectStatus "vss(2)" )
				)
				( pin "J4G1.276"
					( objectStatus "vss(3)" )
				)
				( pin "J4G1.274"
					( objectStatus "vss(4)" )
				)
				( pin "J4G1.272"
					( objectStatus "vss(5)" )
				)
				( pin "J4G1.270"
					( objectStatus "vss(6)" )
				)
				( pin "J4G1.268"
					( objectStatus "vss(7)" )
				)
				( pin "J4G1.265"
					( objectStatus "vss(8)" )
				)
				( pin "J4G1.263"
					( objectStatus "vss(9)" )
				)
				( pin "J4G1.261"
					( objectStatus "vss(10)" )
				)
				( pin "J4G1.259"
					( objectStatus "vss(11)" )
				)
				( pin "J4G1.257"
					( objectStatus "vss(12)" )
				)
				( pin "J4G1.254"
					( objectStatus "vss(13)" )
				)
				( pin "J4G1.252"
					( objectStatus "vss(14)" )
				)
				( pin "J4G1.250"
					( objectStatus "vss(15)" )
				)
				( pin "J4G1.248"
					( objectStatus "vss(16)" )
				)
				( pin "J4G1.246"
					( objectStatus "vss(17)" )
				)
				( pin "J4G1.243"
					( objectStatus "vss(18)" )
				)
				( pin "J4G1.241"
					( objectStatus "vss(19)" )
				)
				( pin "J4G1.239"
					( objectStatus "vss(20)" )
				)
				( pin "J4G1.202"
					( objectStatus "vss(21)" )
				)
				( pin "J4G1.200"
					( objectStatus "vss(22)" )
				)
				( pin "J4G1.198"
					( objectStatus "vss(23)" )
				)
				( pin "J4G1.195"
					( objectStatus "vss(24)" )
				)
				( pin "J4G1.193"
					( objectStatus "vss(25)" )
				)
				( pin "J4G1.191"
					( objectStatus "vss(26)" )
				)
				( pin "J4G1.189"
					( objectStatus "vss(27)" )
				)
				( pin "J4G1.187"
					( objectStatus "vss(28)" )
				)
				( pin "J4G1.184"
					( objectStatus "vss(29)" )
				)
				( pin "J4G1.182"
					( objectStatus "vss(30)" )
				)
				( pin "J4G1.180"
					( objectStatus "vss(31)" )
				)
				( pin "J4G1.178"
					( objectStatus "vss(32)" )
				)
				( pin "J4G1.176"
					( objectStatus "vss(33)" )
				)
				( pin "J4G1.173"
					( objectStatus "vss(34)" )
				)
				( pin "J4G1.171"
					( objectStatus "vss(35)" )
				)
				( pin "J4G1.169"
					( objectStatus "vss(36)" )
				)
				( pin "J4G1.167"
					( objectStatus "vss(37)" )
				)
				( pin "J4G1.165"
					( objectStatus "vss(38)" )
				)
				( pin "J4G1.162"
					( objectStatus "vss(39)" )
				)
				( pin "J4G1.160"
					( objectStatus "vss(40)" )
				)
				( pin "J4G1.158"
					( objectStatus "vss(41)" )
				)
				( pin "J4G1.156"
					( objectStatus "vss(42)" )
				)
				( pin "J4G1.154"
					( objectStatus "vss(43)" )
				)
				( pin "J4G1.151"
					( objectStatus "vss(44)" )
				)
				( pin "J4G1.149"
					( objectStatus "vss(45)" )
				)
				( pin "J4G1.147"
					( objectStatus "vss(46)" )
				)
				( pin "J4G1.138"
					( objectStatus "vss(47)" )
				)
				( pin "J4G1.136"
					( objectStatus "vss(48)" )
				)
				( pin "J4G1.134"
					( objectStatus "vss(49)" )
				)
				( pin "J4G1.131"
					( objectStatus "vss(50)" )
				)
				( pin "J4G1.129"
					( objectStatus "vss(51)" )
				)
				( pin "J4G1.127"
					( objectStatus "vss(52)" )
				)
				( pin "J4G1.125"
					( objectStatus "vss(53)" )
				)
				( pin "J4G1.123"
					( objectStatus "vss(54)" )
				)
				( pin "J4G1.120"
					( objectStatus "vss(55)" )
				)
				( pin "J4G1.118"
					( objectStatus "vss(56)" )
				)
				( pin "J4G1.116"
					( objectStatus "vss(57)" )
				)
				( pin "J4G1.114"
					( objectStatus "vss(58)" )
				)
				( pin "J4G1.112"
					( objectStatus "vss(59)" )
				)
				( pin "J4G1.109"
					( objectStatus "vss(60)" )
				)
				( pin "J4G1.107"
					( objectStatus "vss(61)" )
				)
				( pin "J4G1.105"
					( objectStatus "vss(62)" )
				)
				( pin "J4G1.103"
					( objectStatus "vss(63)" )
				)
				( pin "J4G1.101"
					( objectStatus "vss(64)" )
				)
				( pin "J4G1.98"
					( objectStatus "vss(65)" )
				)
				( pin "J4G1.96"
					( objectStatus "vss(66)" )
				)
				( pin "J4G1.94"
					( objectStatus "vss(67)" )
				)
				( pin "J4G1.57"
					( objectStatus "vss(68)" )
				)
				( pin "J4G1.55"
					( objectStatus "vss(69)" )
				)
				( pin "J4G1.53"
					( objectStatus "vss(70)" )
				)
				( pin "J4G1.50"
					( objectStatus "vss(71)" )
				)
				( pin "J4G1.48"
					( objectStatus "vss(72)" )
				)
				( pin "J4G1.46"
					( objectStatus "vss(73)" )
				)
				( pin "J4G1.44"
					( objectStatus "vss(74)" )
				)
				( pin "J4G1.42"
					( objectStatus "vss(75)" )
				)
				( pin "J4G1.39"
					( objectStatus "vss(76)" )
				)
				( pin "J4G1.37"
					( objectStatus "vss(77)" )
				)
				( pin "J4G1.35"
					( objectStatus "vss(78)" )
				)
				( pin "J4G1.33"
					( objectStatus "vss(79)" )
				)
				( pin "J4G1.31"
					( objectStatus "vss(80)" )
				)
				( pin "J4G1.28"
					( objectStatus "vss(81)" )
				)
				( pin "J4G1.26"
					( objectStatus "vss(82)" )
				)
				( pin "J4G1.24"
					( objectStatus "vss(83)" )
				)
				( pin "J4G1.22"
					( objectStatus "vss(84)" )
				)
				( pin "J4G1.20"
					( objectStatus "vss(85)" )
				)
				( pin "J4G1.17"
					( objectStatus "vss(86)" )
				)
				( pin "J4G1.15"
					( objectStatus "vss(87)" )
				)
				( pin "J4G1.13"
					( objectStatus "vss(88)" )
				)
				( pin "J4G1.11"
					( objectStatus "vss(89)" )
				)
				( pin "J4G1.9"
					( objectStatus "vss(90)" )
				)
				( pin "J4G1.6"
					( objectStatus "vss(91)" )
				)
				( pin "J4G1.4"
					( objectStatus "vss(92)" )
				)
				( pin "J4G1.2"
					( objectStatus "vss(93)" )
				)
			)
			( gate "J4G1"
				( objectStatus "@baseboard_fab2_lib.baseboard_fab2(sch_1):page43_i260" )
				( pin "J4G1.145"
					( objectStatus "\12v\(0)" )
				)
				( pin "J4G1.1"
					( objectStatus "\12v\(1)" )
				)
				( pin "J4G1.236"
					( objectStatus "vdd(0)" )
				)
				( pin "J4G1.233"
					( objectStatus "vdd(1)" )
				)
				( pin "J4G1.231"
					( objectStatus "vdd(2)" )
				)
				( pin "J4G1.229"
					( objectStatus "vdd(3)" )
				)
				( pin "J4G1.226"
					( objectStatus "vdd(4)" )
				)
				( pin "J4G1.223"
					( objectStatus "vdd(5)" )
				)
				( pin "J4G1.220"
					( objectStatus "vdd(6)" )
				)
				( pin "J4G1.217"
					( objectStatus "vdd(7)" )
				)
				( pin "J4G1.215"
					( objectStatus "vdd(8)" )
				)
				( pin "J4G1.212"
					( objectStatus "vdd(9)" )
				)
				( pin "J4G1.209"
					( objectStatus "vdd(10)" )
				)
				( pin "J4G1.206"
					( objectStatus "vdd(11)" )
				)
				( pin "J4G1.204"
					( objectStatus "vdd(12)" )
				)
				( pin "J4G1.92"
					( objectStatus "vdd(13)" )
				)
				( pin "J4G1.90"
					( objectStatus "vdd(14)" )
				)
				( pin "J4G1.88"
					( objectStatus "vdd(15)" )
				)
				( pin "J4G1.85"
					( objectStatus "vdd(16)" )
				)
				( pin "J4G1.83"
					( objectStatus "vdd(17)" )
				)
				( pin "J4G1.80"
					( objectStatus "vdd(18)" )
				)
				( pin "J4G1.76"
					( objectStatus "vdd(19)" )
				)
				( pin "J4G1.73"
					( objectStatus "vdd(20)" )
				)
				( pin "J4G1.70"
					( objectStatus "vdd(21)" )
				)
				( pin "J4G1.67"
					( objectStatus "vdd(22)" )
				)
				( pin "J4G1.64"
					( objectStatus "vdd(23)" )
				)
				( pin "J4G1.61"
					( objectStatus "vdd(24)" )
				)
				( pin "J4G1.59"
					( objectStatus "vdd(25)" )
				)
				( pin "J4G1.287"
					( objectStatus "vpp(0)" )
				)
				( pin "J4G1.286"
					( objectStatus "vpp(1)" )
				)
				( pin "J4G1.288"
					( objectStatus "vpp(2)" )
				)
				( pin "J4G1.143"
					( objectStatus "vpp(3)" )
				)
				( pin "J4G1.142"
					( objectStatus "vpp(4)" )
				)
				( pin "J4G1.221"
					( objectStatus "vtt(0)" )
				)
				( pin "J4G1.77"
					( objectStatus "vtt(1)" )
				)
			)
			( gate "C4F10"
				( objectStatus "@baseboard_fab2_lib.baseboard_fab2(sch_1):page43_i272" )
				( pin "C4F10.1"
					( objectStatus "a" )
				)
				( pin "C4F10.2"
					( objectStatus "b" )
				)
			)
			( gate "C6T1"
				( objectStatus "@baseboard_fab2_lib.baseboard_fab2(sch_1):page44_i2" )
				( pin "C6T1.1"
					( objectStatus "a" )
				)
				( pin "C6T1.2"
					( objectStatus "b" )
				)
			)
			( gate "J6T1"
				( objectStatus "@baseboard_fab2_lib.baseboard_fab2(sch_1):page44_i13" )
				( pin "J6T1.79"
					( objectStatus "a0" )
				)
				( pin "J6T1.72"
					( objectStatus "a1" )
				)
				( pin "J6T1.216"
					( objectStatus "a2" )
				)
				( pin "J6T1.71"
					( objectStatus "a3" )
				)
				( pin "J6T1.214"
					( objectStatus "a4" )
				)
				( pin "J6T1.213"
					( objectStatus "a5" )
				)
				( pin "J6T1.69"
					( objectStatus "a6" )
				)
				( pin "J6T1.211"
					( objectStatus "a7" )
				)
				( pin "J6T1.68"
					( objectStatus "a8" )
				)
				( pin "J6T1.66"
					( objectStatus "a9" )
				)
				( pin "J6T1.225"
					( objectStatus "a10" )
				)
				( pin "J6T1.210"
					( objectStatus "a11" )
				)
				( pin "J6T1.65"
					( objectStatus "a12" )
				)
				( pin "J6T1.232"
					( objectStatus "a13" )
				)
				( pin "J6T1.228"
					( objectStatus "a14_we_n" )
				)
				( pin "J6T1.86"
					( objectStatus "a15_cas_n" )
				)
				( pin "J6T1.82"
					( objectStatus "a16_ras_n" )
				)
				( pin "J6T1.234"
					( objectStatus "a17" )
				)
				( pin "J6T1.62"
					( objectStatus "act_n" )
				)
				( pin "J6T1.208"
					( objectStatus "alert_n" )
				)
				( pin "J6T1.81"
					( objectStatus "ba(0)" )
				)
				( pin "J6T1.224"
					( objectStatus "ba(1)" )
				)
				( pin "J6T1.63"
					( objectStatus "bg(0)" )
				)
				( pin "J6T1.207"
					( objectStatus "bg(1)" )
				)
				( pin "J6T1.235"
					( objectStatus "c(2)" )
				)
				( pin "J6T1.49"
					( objectStatus "cb(0)" )
				)
				( pin "J6T1.194"
					( objectStatus "cb(1)" )
				)
				( pin "J6T1.56"
					( objectStatus "cb(2)" )
				)
				( pin "J6T1.201"
					( objectStatus "cb(3)" )
				)
				( pin "J6T1.47"
					( objectStatus "cb(4)" )
				)
				( pin "J6T1.192"
					( objectStatus "cb(5)" )
				)
				( pin "J6T1.54"
					( objectStatus "cb(6)" )
				)
				( pin "J6T1.199"
					( objectStatus "cb(7)" )
				)
				( pin "J6T1.75"
					( objectStatus "ck0n" )
				)
				( pin "J6T1.74"
					( objectStatus "ck0p" )
				)
				( pin "J6T1.219"
					( objectStatus "ck1n" )
				)
				( pin "J6T1.218"
					( objectStatus "ck1p" )
				)
				( pin "J6T1.60"
					( objectStatus "cke(0)" )
				)
				( pin "J6T1.203"
					( objectStatus "cke(1)" )
				)
				( pin "J6T1.5"
					( objectStatus "dq(0)" )
				)
				( pin "J6T1.150"
					( objectStatus "dq(1)" )
				)
				( pin "J6T1.12"
					( objectStatus "dq(2)" )
				)
				( pin "J6T1.157"
					( objectStatus "dq(3)" )
				)
				( pin "J6T1.3"
					( objectStatus "dq(4)" )
				)
				( pin "J6T1.148"
					( objectStatus "dq(5)" )
				)
				( pin "J6T1.10"
					( objectStatus "dq(6)" )
				)
				( pin "J6T1.155"
					( objectStatus "dq(7)" )
				)
				( pin "J6T1.16"
					( objectStatus "dq(8)" )
				)
				( pin "J6T1.161"
					( objectStatus "dq(9)" )
				)
				( pin "J6T1.23"
					( objectStatus "dq(10)" )
				)
				( pin "J6T1.168"
					( objectStatus "dq(11)" )
				)
				( pin "J6T1.14"
					( objectStatus "dq(12)" )
				)
				( pin "J6T1.159"
					( objectStatus "dq(13)" )
				)
				( pin "J6T1.21"
					( objectStatus "dq(14)" )
				)
				( pin "J6T1.166"
					( objectStatus "dq(15)" )
				)
				( pin "J6T1.27"
					( objectStatus "dq(16)" )
				)
				( pin "J6T1.172"
					( objectStatus "dq(17)" )
				)
				( pin "J6T1.34"
					( objectStatus "dq(18)" )
				)
				( pin "J6T1.179"
					( objectStatus "dq(19)" )
				)
				( pin "J6T1.25"
					( objectStatus "dq(20)" )
				)
				( pin "J6T1.170"
					( objectStatus "dq(21)" )
				)
				( pin "J6T1.32"
					( objectStatus "dq(22)" )
				)
				( pin "J6T1.177"
					( objectStatus "dq(23)" )
				)
				( pin "J6T1.38"
					( objectStatus "dq(24)" )
				)
				( pin "J6T1.183"
					( objectStatus "dq(25)" )
				)
				( pin "J6T1.45"
					( objectStatus "dq(26)" )
				)
				( pin "J6T1.190"
					( objectStatus "dq(27)" )
				)
				( pin "J6T1.36"
					( objectStatus "dq(28)" )
				)
				( pin "J6T1.181"
					( objectStatus "dq(29)" )
				)
				( pin "J6T1.43"
					( objectStatus "dq(30)" )
				)
				( pin "J6T1.188"
					( objectStatus "dq(31)" )
				)
				( pin "J6T1.97"
					( objectStatus "dq(32)" )
				)
				( pin "J6T1.242"
					( objectStatus "dq(33)" )
				)
				( pin "J6T1.104"
					( objectStatus "dq(34)" )
				)
				( pin "J6T1.249"
					( objectStatus "dq(35)" )
				)
				( pin "J6T1.95"
					( objectStatus "dq(36)" )
				)
				( pin "J6T1.240"
					( objectStatus "dq(37)" )
				)
				( pin "J6T1.102"
					( objectStatus "dq(38)" )
				)
				( pin "J6T1.247"
					( objectStatus "dq(39)" )
				)
				( pin "J6T1.108"
					( objectStatus "dq(40)" )
				)
				( pin "J6T1.253"
					( objectStatus "dq(41)" )
				)
				( pin "J6T1.115"
					( objectStatus "dq(42)" )
				)
				( pin "J6T1.260"
					( objectStatus "dq(43)" )
				)
				( pin "J6T1.106"
					( objectStatus "dq(44)" )
				)
				( pin "J6T1.251"
					( objectStatus "dq(45)" )
				)
				( pin "J6T1.113"
					( objectStatus "dq(46)" )
				)
				( pin "J6T1.258"
					( objectStatus "dq(47)" )
				)
				( pin "J6T1.119"
					( objectStatus "dq(48)" )
				)
				( pin "J6T1.264"
					( objectStatus "dq(49)" )
				)
				( pin "J6T1.126"
					( objectStatus "dq(50)" )
				)
				( pin "J6T1.271"
					( objectStatus "dq(51)" )
				)
				( pin "J6T1.117"
					( objectStatus "dq(52)" )
				)
				( pin "J6T1.262"
					( objectStatus "dq(53)" )
				)
				( pin "J6T1.124"
					( objectStatus "dq(54)" )
				)
				( pin "J6T1.269"
					( objectStatus "dq(55)" )
				)
				( pin "J6T1.130"
					( objectStatus "dq(56)" )
				)
				( pin "J6T1.275"
					( objectStatus "dq(57)" )
				)
				( pin "J6T1.137"
					( objectStatus "dq(58)" )
				)
				( pin "J6T1.282"
					( objectStatus "dq(59)" )
				)
				( pin "J6T1.128"
					( objectStatus "dq(60)" )
				)
				( pin "J6T1.273"
					( objectStatus "dq(61)" )
				)
				( pin "J6T1.135"
					( objectStatus "dq(62)" )
				)
				( pin "J6T1.280"
					( objectStatus "dq(63)" )
				)
				( pin "J6T1.78"
					( objectStatus "event_n" )
				)
				( pin "J6T1.87"
					( objectStatus "odt(0)" )
				)
				( pin "J6T1.91"
					( objectStatus "odt(1)" )
				)
				( pin "J6T1.222"
					( objectStatus "par" )
				)
				( pin "J6T1.58"
					( objectStatus "reset_n" )
				)
				( pin "J6T1.205"
					( objectStatus "rfu(0)" )
				)
				( pin "J6T1.227"
					( objectStatus "rfu(1)" )
				)
				( pin "J6T1.144"
					( objectStatus "rfu(2)" )
				)
				( pin "J6T1.84"
					( objectStatus "s0_n" )
				)
				( pin "J6T1.89"
					( objectStatus "s1_n" )
				)
				( pin "J6T1.93"
					( objectStatus "s2_n_c(0)" )
				)
				( pin "J6T1.237"
					( objectStatus "s3_n_c(1)" )
				)
				( pin "J6T1.139"
					( objectStatus "sa(0)" )
				)
				( pin "J6T1.140"
					( objectStatus "sa(1)" )
				)
				( pin "J6T1.238"
					( objectStatus "sa(2)" )
				)
				( pin "J6T1.230"
					( objectStatus "save_n_nc" )
				)
				( pin "J6T1.141"
					( objectStatus "scl" )
				)
				( pin "J6T1.285"
					( objectStatus "sda" )
				)
				( pin "J6T1.284"
					( objectStatus "vddspd" )
				)
				( pin "J6T1.146"
					( objectStatus "vrefca" )
				)
			)
			( gate "J6T1"
				( objectStatus "@baseboard_fab2_lib.baseboard_fab2(sch_1):page44_i75" )
				( pin "J6T1.145"
					( objectStatus "\12v\(0)" )
				)
				( pin "J6T1.1"
					( objectStatus "\12v\(1)" )
				)
				( pin "J6T1.236"
					( objectStatus "vdd(0)" )
				)
				( pin "J6T1.233"
					( objectStatus "vdd(1)" )
				)
				( pin "J6T1.231"
					( objectStatus "vdd(2)" )
				)
				( pin "J6T1.229"
					( objectStatus "vdd(3)" )
				)
				( pin "J6T1.226"
					( objectStatus "vdd(4)" )
				)
				( pin "J6T1.223"
					( objectStatus "vdd(5)" )
				)
				( pin "J6T1.220"
					( objectStatus "vdd(6)" )
				)
				( pin "J6T1.217"
					( objectStatus "vdd(7)" )
				)
				( pin "J6T1.215"
					( objectStatus "vdd(8)" )
				)
				( pin "J6T1.212"
					( objectStatus "vdd(9)" )
				)
				( pin "J6T1.209"
					( objectStatus "vdd(10)" )
				)
				( pin "J6T1.206"
					( objectStatus "vdd(11)" )
				)
				( pin "J6T1.204"
					( objectStatus "vdd(12)" )
				)
				( pin "J6T1.92"
					( objectStatus "vdd(13)" )
				)
				( pin "J6T1.90"
					( objectStatus "vdd(14)" )
				)
				( pin "J6T1.88"
					( objectStatus "vdd(15)" )
				)
				( pin "J6T1.85"
					( objectStatus "vdd(16)" )
				)
				( pin "J6T1.83"
					( objectStatus "vdd(17)" )
				)
				( pin "J6T1.80"
					( objectStatus "vdd(18)" )
				)
				( pin "J6T1.76"
					( objectStatus "vdd(19)" )
				)
				( pin "J6T1.73"
					( objectStatus "vdd(20)" )
				)
				( pin "J6T1.70"
					( objectStatus "vdd(21)" )
				)
				( pin "J6T1.67"
					( objectStatus "vdd(22)" )
				)
				( pin "J6T1.64"
					( objectStatus "vdd(23)" )
				)
				( pin "J6T1.61"
					( objectStatus "vdd(24)" )
				)
				( pin "J6T1.59"
					( objectStatus "vdd(25)" )
				)
				( pin "J6T1.287"
					( objectStatus "vpp(0)" )
				)
				( pin "J6T1.286"
					( objectStatus "vpp(1)" )
				)
				( pin "J6T1.288"
					( objectStatus "vpp(2)" )
				)
				( pin "J6T1.143"
					( objectStatus "vpp(3)" )
				)
				( pin "J6T1.142"
					( objectStatus "vpp(4)" )
				)
				( pin "J6T1.221"
					( objectStatus "vtt(0)" )
				)
				( pin "J6T1.77"
					( objectStatus "vtt(1)" )
				)
			)
			( gate "J6T1"
				( objectStatus "@baseboard_fab2_lib.baseboard_fab2(sch_1):page44_i120" )
				( pin "J6T1.152"
					( objectStatus "dqs0n" )
				)
				( pin "J6T1.153"
					( objectStatus "dqs0p" )
				)
				( pin "J6T1.163"
					( objectStatus "dqs1n" )
				)
				( pin "J6T1.164"
					( objectStatus "dqs1p" )
				)
				( pin "J6T1.174"
					( objectStatus "dqs2n" )
				)
				( pin "J6T1.175"
					( objectStatus "dqs2p" )
				)
				( pin "J6T1.185"
					( objectStatus "dqs3n" )
				)
				( pin "J6T1.186"
					( objectStatus "dqs3p" )
				)
				( pin "J6T1.244"
					( objectStatus "dqs4n" )
				)
				( pin "J6T1.245"
					( objectStatus "dqs4p" )
				)
				( pin "J6T1.255"
					( objectStatus "dqs5n" )
				)
				( pin "J6T1.256"
					( objectStatus "dqs5p" )
				)
				( pin "J6T1.266"
					( objectStatus "dqs6n" )
				)
				( pin "J6T1.267"
					( objectStatus "dqs6p" )
				)
				( pin "J6T1.277"
					( objectStatus "dqs7n" )
				)
				( pin "J6T1.278"
					( objectStatus "dqs7p" )
				)
				( pin "J6T1.196"
					( objectStatus "dqs8n" )
				)
				( pin "J6T1.197"
					( objectStatus "dqs8p" )
				)
				( pin "J6T1.8"
					( objectStatus "dqs9n" )
				)
				( pin "J6T1.7"
					( objectStatus "dqs9p" )
				)
				( pin "J6T1.19"
					( objectStatus "dqs10n" )
				)
				( pin "J6T1.18"
					( objectStatus "dqs10p" )
				)
				( pin "J6T1.30"
					( objectStatus "dqs11n" )
				)
				( pin "J6T1.29"
					( objectStatus "dqs11p" )
				)
				( pin "J6T1.41"
					( objectStatus "dqs12n" )
				)
				( pin "J6T1.40"
					( objectStatus "dqs12p" )
				)
				( pin "J6T1.100"
					( objectStatus "dqs13n" )
				)
				( pin "J6T1.99"
					( objectStatus "dqs13p" )
				)
				( pin "J6T1.111"
					( objectStatus "dqs14n" )
				)
				( pin "J6T1.110"
					( objectStatus "dqs14p" )
				)
				( pin "J6T1.122"
					( objectStatus "dqs15n" )
				)
				( pin "J6T1.121"
					( objectStatus "dqs15p" )
				)
				( pin "J6T1.133"
					( objectStatus "dqs16n" )
				)
				( pin "J6T1.132"
					( objectStatus "dqs16p" )
				)
				( pin "J6T1.52"
					( objectStatus "dqs17n" )
				)
				( pin "J6T1.51"
					( objectStatus "dqs17p" )
				)
			)
			( gate "J6T1"
				( objectStatus "@baseboard_fab2_lib.baseboard_fab2(sch_1):page44_i139" )
				( pin "J6T1.283"
					( objectStatus "vss(0)" )
				)
				( pin "J6T1.281"
					( objectStatus "vss(1)" )
				)
				( pin "J6T1.279"
					( objectStatus "vss(2)" )
				)
				( pin "J6T1.276"
					( objectStatus "vss(3)" )
				)
				( pin "J6T1.274"
					( objectStatus "vss(4)" )
				)
				( pin "J6T1.272"
					( objectStatus "vss(5)" )
				)
				( pin "J6T1.270"
					( objectStatus "vss(6)" )
				)
				( pin "J6T1.268"
					( objectStatus "vss(7)" )
				)
				( pin "J6T1.265"
					( objectStatus "vss(8)" )
				)
				( pin "J6T1.263"
					( objectStatus "vss(9)" )
				)
				( pin "J6T1.261"
					( objectStatus "vss(10)" )
				)
				( pin "J6T1.259"
					( objectStatus "vss(11)" )
				)
				( pin "J6T1.257"
					( objectStatus "vss(12)" )
				)
				( pin "J6T1.254"
					( objectStatus "vss(13)" )
				)
				( pin "J6T1.252"
					( objectStatus "vss(14)" )
				)
				( pin "J6T1.250"
					( objectStatus "vss(15)" )
				)
				( pin "J6T1.248"
					( objectStatus "vss(16)" )
				)
				( pin "J6T1.246"
					( objectStatus "vss(17)" )
				)
				( pin "J6T1.243"
					( objectStatus "vss(18)" )
				)
				( pin "J6T1.241"
					( objectStatus "vss(19)" )
				)
				( pin "J6T1.239"
					( objectStatus "vss(20)" )
				)
				( pin "J6T1.202"
					( objectStatus "vss(21)" )
				)
				( pin "J6T1.200"
					( objectStatus "vss(22)" )
				)
				( pin "J6T1.198"
					( objectStatus "vss(23)" )
				)
				( pin "J6T1.195"
					( objectStatus "vss(24)" )
				)
				( pin "J6T1.193"
					( objectStatus "vss(25)" )
				)
				( pin "J6T1.191"
					( objectStatus "vss(26)" )
				)
				( pin "J6T1.189"
					( objectStatus "vss(27)" )
				)
				( pin "J6T1.187"
					( objectStatus "vss(28)" )
				)
				( pin "J6T1.184"
					( objectStatus "vss(29)" )
				)
				( pin "J6T1.182"
					( objectStatus "vss(30)" )
				)
				( pin "J6T1.180"
					( objectStatus "vss(31)" )
				)
				( pin "J6T1.178"
					( objectStatus "vss(32)" )
				)
				( pin "J6T1.176"
					( objectStatus "vss(33)" )
				)
				( pin "J6T1.173"
					( objectStatus "vss(34)" )
				)
				( pin "J6T1.171"
					( objectStatus "vss(35)" )
				)
				( pin "J6T1.169"
					( objectStatus "vss(36)" )
				)
				( pin "J6T1.167"
					( objectStatus "vss(37)" )
				)
				( pin "J6T1.165"
					( objectStatus "vss(38)" )
				)
				( pin "J6T1.162"
					( objectStatus "vss(39)" )
				)
				( pin "J6T1.160"
					( objectStatus "vss(40)" )
				)
				( pin "J6T1.158"
					( objectStatus "vss(41)" )
				)
				( pin "J6T1.156"
					( objectStatus "vss(42)" )
				)
				( pin "J6T1.154"
					( objectStatus "vss(43)" )
				)
				( pin "J6T1.151"
					( objectStatus "vss(44)" )
				)
				( pin "J6T1.149"
					( objectStatus "vss(45)" )
				)
				( pin "J6T1.147"
					( objectStatus "vss(46)" )
				)
				( pin "J6T1.138"
					( objectStatus "vss(47)" )
				)
				( pin "J6T1.136"
					( objectStatus "vss(48)" )
				)
				( pin "J6T1.134"
					( objectStatus "vss(49)" )
				)
				( pin "J6T1.131"
					( objectStatus "vss(50)" )
				)
				( pin "J6T1.129"
					( objectStatus "vss(51)" )
				)
				( pin "J6T1.127"
					( objectStatus "vss(52)" )
				)
				( pin "J6T1.125"
					( objectStatus "vss(53)" )
				)
				( pin "J6T1.123"
					( objectStatus "vss(54)" )
				)
				( pin "J6T1.120"
					( objectStatus "vss(55)" )
				)
				( pin "J6T1.118"
					( objectStatus "vss(56)" )
				)
				( pin "J6T1.116"
					( objectStatus "vss(57)" )
				)
				( pin "J6T1.114"
					( objectStatus "vss(58)" )
				)
				( pin "J6T1.112"
					( objectStatus "vss(59)" )
				)
				( pin "J6T1.109"
					( objectStatus "vss(60)" )
				)
				( pin "J6T1.107"
					( objectStatus "vss(61)" )
				)
				( pin "J6T1.105"
					( objectStatus "vss(62)" )
				)
				( pin "J6T1.103"
					( objectStatus "vss(63)" )
				)
				( pin "J6T1.101"
					( objectStatus "vss(64)" )
				)
				( pin "J6T1.98"
					( objectStatus "vss(65)" )
				)
				( pin "J6T1.96"
					( objectStatus "vss(66)" )
				)
				( pin "J6T1.94"
					( objectStatus "vss(67)" )
				)
				( pin "J6T1.57"
					( objectStatus "vss(68)" )
				)
				( pin "J6T1.55"
					( objectStatus "vss(69)" )
				)
				( pin "J6T1.53"
					( objectStatus "vss(70)" )
				)
				( pin "J6T1.50"
					( objectStatus "vss(71)" )
				)
				( pin "J6T1.48"
					( objectStatus "vss(72)" )
				)
				( pin "J6T1.46"
					( objectStatus "vss(73)" )
				)
				( pin "J6T1.44"
					( objectStatus "vss(74)" )
				)
				( pin "J6T1.42"
					( objectStatus "vss(75)" )
				)
				( pin "J6T1.39"
					( objectStatus "vss(76)" )
				)
				( pin "J6T1.37"
					( objectStatus "vss(77)" )
				)
				( pin "J6T1.35"
					( objectStatus "vss(78)" )
				)
				( pin "J6T1.33"
					( objectStatus "vss(79)" )
				)
				( pin "J6T1.31"
					( objectStatus "vss(80)" )
				)
				( pin "J6T1.28"
					( objectStatus "vss(81)" )
				)
				( pin "J6T1.26"
					( objectStatus "vss(82)" )
				)
				( pin "J6T1.24"
					( objectStatus "vss(83)" )
				)
				( pin "J6T1.22"
					( objectStatus "vss(84)" )
				)
				( pin "J6T1.20"
					( objectStatus "vss(85)" )
				)
				( pin "J6T1.17"
					( objectStatus "vss(86)" )
				)
				( pin "J6T1.15"
					( objectStatus "vss(87)" )
				)
				( pin "J6T1.13"
					( objectStatus "vss(88)" )
				)
				( pin "J6T1.11"
					( objectStatus "vss(89)" )
				)
				( pin "J6T1.9"
					( objectStatus "vss(90)" )
				)
				( pin "J6T1.6"
					( objectStatus "vss(91)" )
				)
				( pin "J6T1.4"
					( objectStatus "vss(92)" )
				)
				( pin "J6T1.2"
					( objectStatus "vss(93)" )
				)
			)
			( gate "J4G2"
				( objectStatus "@baseboard_fab2_lib.baseboard_fab2(sch_1):page45_i43" )
				( pin "J4G2.283"
					( objectStatus "vss(0)" )
				)
				( pin "J4G2.281"
					( objectStatus "vss(1)" )
				)
				( pin "J4G2.279"
					( objectStatus "vss(2)" )
				)
				( pin "J4G2.276"
					( objectStatus "vss(3)" )
				)
				( pin "J4G2.274"
					( objectStatus "vss(4)" )
				)
				( pin "J4G2.272"
					( objectStatus "vss(5)" )
				)
				( pin "J4G2.270"
					( objectStatus "vss(6)" )
				)
				( pin "J4G2.268"
					( objectStatus "vss(7)" )
				)
				( pin "J4G2.265"
					( objectStatus "vss(8)" )
				)
				( pin "J4G2.263"
					( objectStatus "vss(9)" )
				)
				( pin "J4G2.261"
					( objectStatus "vss(10)" )
				)
				( pin "J4G2.259"
					( objectStatus "vss(11)" )
				)
				( pin "J4G2.257"
					( objectStatus "vss(12)" )
				)
				( pin "J4G2.254"
					( objectStatus "vss(13)" )
				)
				( pin "J4G2.252"
					( objectStatus "vss(14)" )
				)
				( pin "J4G2.250"
					( objectStatus "vss(15)" )
				)
				( pin "J4G2.248"
					( objectStatus "vss(16)" )
				)
				( pin "J4G2.246"
					( objectStatus "vss(17)" )
				)
				( pin "J4G2.243"
					( objectStatus "vss(18)" )
				)
				( pin "J4G2.241"
					( objectStatus "vss(19)" )
				)
				( pin "J4G2.239"
					( objectStatus "vss(20)" )
				)
				( pin "J4G2.202"
					( objectStatus "vss(21)" )
				)
				( pin "J4G2.200"
					( objectStatus "vss(22)" )
				)
				( pin "J4G2.198"
					( objectStatus "vss(23)" )
				)
				( pin "J4G2.195"
					( objectStatus "vss(24)" )
				)
				( pin "J4G2.193"
					( objectStatus "vss(25)" )
				)
				( pin "J4G2.191"
					( objectStatus "vss(26)" )
				)
				( pin "J4G2.189"
					( objectStatus "vss(27)" )
				)
				( pin "J4G2.187"
					( objectStatus "vss(28)" )
				)
				( pin "J4G2.184"
					( objectStatus "vss(29)" )
				)
				( pin "J4G2.182"
					( objectStatus "vss(30)" )
				)
				( pin "J4G2.180"
					( objectStatus "vss(31)" )
				)
				( pin "J4G2.178"
					( objectStatus "vss(32)" )
				)
				( pin "J4G2.176"
					( objectStatus "vss(33)" )
				)
				( pin "J4G2.173"
					( objectStatus "vss(34)" )
				)
				( pin "J4G2.171"
					( objectStatus "vss(35)" )
				)
				( pin "J4G2.169"
					( objectStatus "vss(36)" )
				)
				( pin "J4G2.167"
					( objectStatus "vss(37)" )
				)
				( pin "J4G2.165"
					( objectStatus "vss(38)" )
				)
				( pin "J4G2.162"
					( objectStatus "vss(39)" )
				)
				( pin "J4G2.160"
					( objectStatus "vss(40)" )
				)
				( pin "J4G2.158"
					( objectStatus "vss(41)" )
				)
				( pin "J4G2.156"
					( objectStatus "vss(42)" )
				)
				( pin "J4G2.154"
					( objectStatus "vss(43)" )
				)
				( pin "J4G2.151"
					( objectStatus "vss(44)" )
				)
				( pin "J4G2.149"
					( objectStatus "vss(45)" )
				)
				( pin "J4G2.147"
					( objectStatus "vss(46)" )
				)
				( pin "J4G2.138"
					( objectStatus "vss(47)" )
				)
				( pin "J4G2.136"
					( objectStatus "vss(48)" )
				)
				( pin "J4G2.134"
					( objectStatus "vss(49)" )
				)
				( pin "J4G2.131"
					( objectStatus "vss(50)" )
				)
				( pin "J4G2.129"
					( objectStatus "vss(51)" )
				)
				( pin "J4G2.127"
					( objectStatus "vss(52)" )
				)
				( pin "J4G2.125"
					( objectStatus "vss(53)" )
				)
				( pin "J4G2.123"
					( objectStatus "vss(54)" )
				)
				( pin "J4G2.120"
					( objectStatus "vss(55)" )
				)
				( pin "J4G2.118"
					( objectStatus "vss(56)" )
				)
				( pin "J4G2.116"
					( objectStatus "vss(57)" )
				)
				( pin "J4G2.114"
					( objectStatus "vss(58)" )
				)
				( pin "J4G2.112"
					( objectStatus "vss(59)" )
				)
				( pin "J4G2.109"
					( objectStatus "vss(60)" )
				)
				( pin "J4G2.107"
					( objectStatus "vss(61)" )
				)
				( pin "J4G2.105"
					( objectStatus "vss(62)" )
				)
				( pin "J4G2.103"
					( objectStatus "vss(63)" )
				)
				( pin "J4G2.101"
					( objectStatus "vss(64)" )
				)
				( pin "J4G2.98"
					( objectStatus "vss(65)" )
				)
				( pin "J4G2.96"
					( objectStatus "vss(66)" )
				)
				( pin "J4G2.94"
					( objectStatus "vss(67)" )
				)
				( pin "J4G2.57"
					( objectStatus "vss(68)" )
				)
				( pin "J4G2.55"
					( objectStatus "vss(69)" )
				)
				( pin "J4G2.53"
					( objectStatus "vss(70)" )
				)
				( pin "J4G2.50"
					( objectStatus "vss(71)" )
				)
				( pin "J4G2.48"
					( objectStatus "vss(72)" )
				)
				( pin "J4G2.46"
					( objectStatus "vss(73)" )
				)
				( pin "J4G2.44"
					( objectStatus "vss(74)" )
				)
				( pin "J4G2.42"
					( objectStatus "vss(75)" )
				)
				( pin "J4G2.39"
					( objectStatus "vss(76)" )
				)
				( pin "J4G2.37"
					( objectStatus "vss(77)" )
				)
				( pin "J4G2.35"
					( objectStatus "vss(78)" )
				)
				( pin "J4G2.33"
					( objectStatus "vss(79)" )
				)
				( pin "J4G2.31"
					( objectStatus "vss(80)" )
				)
				( pin "J4G2.28"
					( objectStatus "vss(81)" )
				)
				( pin "J4G2.26"
					( objectStatus "vss(82)" )
				)
				( pin "J4G2.24"
					( objectStatus "vss(83)" )
				)
				( pin "J4G2.22"
					( objectStatus "vss(84)" )
				)
				( pin "J4G2.20"
					( objectStatus "vss(85)" )
				)
				( pin "J4G2.17"
					( objectStatus "vss(86)" )
				)
				( pin "J4G2.15"
					( objectStatus "vss(87)" )
				)
				( pin "J4G2.13"
					( objectStatus "vss(88)" )
				)
				( pin "J4G2.11"
					( objectStatus "vss(89)" )
				)
				( pin "J4G2.9"
					( objectStatus "vss(90)" )
				)
				( pin "J4G2.6"
					( objectStatus "vss(91)" )
				)
				( pin "J4G2.4"
					( objectStatus "vss(92)" )
				)
				( pin "J4G2.2"
					( objectStatus "vss(93)" )
				)
			)
			( gate "J4G2"
				( objectStatus "@baseboard_fab2_lib.baseboard_fab2(sch_1):page45_i61" )
				( pin "J4G2.152"
					( objectStatus "dqs0n" )
				)
				( pin "J4G2.153"
					( objectStatus "dqs0p" )
				)
				( pin "J4G2.163"
					( objectStatus "dqs1n" )
				)
				( pin "J4G2.164"
					( objectStatus "dqs1p" )
				)
				( pin "J4G2.174"
					( objectStatus "dqs2n" )
				)
				( pin "J4G2.175"
					( objectStatus "dqs2p" )
				)
				( pin "J4G2.185"
					( objectStatus "dqs3n" )
				)
				( pin "J4G2.186"
					( objectStatus "dqs3p" )
				)
				( pin "J4G2.244"
					( objectStatus "dqs4n" )
				)
				( pin "J4G2.245"
					( objectStatus "dqs4p" )
				)
				( pin "J4G2.255"
					( objectStatus "dqs5n" )
				)
				( pin "J4G2.256"
					( objectStatus "dqs5p" )
				)
				( pin "J4G2.266"
					( objectStatus "dqs6n" )
				)
				( pin "J4G2.267"
					( objectStatus "dqs6p" )
				)
				( pin "J4G2.277"
					( objectStatus "dqs7n" )
				)
				( pin "J4G2.278"
					( objectStatus "dqs7p" )
				)
				( pin "J4G2.196"
					( objectStatus "dqs8n" )
				)
				( pin "J4G2.197"
					( objectStatus "dqs8p" )
				)
				( pin "J4G2.8"
					( objectStatus "dqs9n" )
				)
				( pin "J4G2.7"
					( objectStatus "dqs9p" )
				)
				( pin "J4G2.19"
					( objectStatus "dqs10n" )
				)
				( pin "J4G2.18"
					( objectStatus "dqs10p" )
				)
				( pin "J4G2.30"
					( objectStatus "dqs11n" )
				)
				( pin "J4G2.29"
					( objectStatus "dqs11p" )
				)
				( pin "J4G2.41"
					( objectStatus "dqs12n" )
				)
				( pin "J4G2.40"
					( objectStatus "dqs12p" )
				)
				( pin "J4G2.100"
					( objectStatus "dqs13n" )
				)
				( pin "J4G2.99"
					( objectStatus "dqs13p" )
				)
				( pin "J4G2.111"
					( objectStatus "dqs14n" )
				)
				( pin "J4G2.110"
					( objectStatus "dqs14p" )
				)
				( pin "J4G2.122"
					( objectStatus "dqs15n" )
				)
				( pin "J4G2.121"
					( objectStatus "dqs15p" )
				)
				( pin "J4G2.133"
					( objectStatus "dqs16n" )
				)
				( pin "J4G2.132"
					( objectStatus "dqs16p" )
				)
				( pin "J4G2.52"
					( objectStatus "dqs17n" )
				)
				( pin "J4G2.51"
					( objectStatus "dqs17p" )
				)
			)
			( gate "J4G2"
				( objectStatus "@baseboard_fab2_lib.baseboard_fab2(sch_1):page45_i111" )
				( pin "J4G2.79"
					( objectStatus "a0" )
				)
				( pin "J4G2.72"
					( objectStatus "a1" )
				)
				( pin "J4G2.216"
					( objectStatus "a2" )
				)
				( pin "J4G2.71"
					( objectStatus "a3" )
				)
				( pin "J4G2.214"
					( objectStatus "a4" )
				)
				( pin "J4G2.213"
					( objectStatus "a5" )
				)
				( pin "J4G2.69"
					( objectStatus "a6" )
				)
				( pin "J4G2.211"
					( objectStatus "a7" )
				)
				( pin "J4G2.68"
					( objectStatus "a8" )
				)
				( pin "J4G2.66"
					( objectStatus "a9" )
				)
				( pin "J4G2.225"
					( objectStatus "a10" )
				)
				( pin "J4G2.210"
					( objectStatus "a11" )
				)
				( pin "J4G2.65"
					( objectStatus "a12" )
				)
				( pin "J4G2.232"
					( objectStatus "a13" )
				)
				( pin "J4G2.228"
					( objectStatus "a14_we_n" )
				)
				( pin "J4G2.86"
					( objectStatus "a15_cas_n" )
				)
				( pin "J4G2.82"
					( objectStatus "a16_ras_n" )
				)
				( pin "J4G2.234"
					( objectStatus "a17" )
				)
				( pin "J4G2.62"
					( objectStatus "act_n" )
				)
				( pin "J4G2.208"
					( objectStatus "alert_n" )
				)
				( pin "J4G2.81"
					( objectStatus "ba(0)" )
				)
				( pin "J4G2.224"
					( objectStatus "ba(1)" )
				)
				( pin "J4G2.63"
					( objectStatus "bg(0)" )
				)
				( pin "J4G2.207"
					( objectStatus "bg(1)" )
				)
				( pin "J4G2.235"
					( objectStatus "c(2)" )
				)
				( pin "J4G2.49"
					( objectStatus "cb(0)" )
				)
				( pin "J4G2.194"
					( objectStatus "cb(1)" )
				)
				( pin "J4G2.56"
					( objectStatus "cb(2)" )
				)
				( pin "J4G2.201"
					( objectStatus "cb(3)" )
				)
				( pin "J4G2.47"
					( objectStatus "cb(4)" )
				)
				( pin "J4G2.192"
					( objectStatus "cb(5)" )
				)
				( pin "J4G2.54"
					( objectStatus "cb(6)" )
				)
				( pin "J4G2.199"
					( objectStatus "cb(7)" )
				)
				( pin "J4G2.75"
					( objectStatus "ck0n" )
				)
				( pin "J4G2.74"
					( objectStatus "ck0p" )
				)
				( pin "J4G2.219"
					( objectStatus "ck1n" )
				)
				( pin "J4G2.218"
					( objectStatus "ck1p" )
				)
				( pin "J4G2.60"
					( objectStatus "cke(0)" )
				)
				( pin "J4G2.203"
					( objectStatus "cke(1)" )
				)
				( pin "J4G2.5"
					( objectStatus "dq(0)" )
				)
				( pin "J4G2.150"
					( objectStatus "dq(1)" )
				)
				( pin "J4G2.12"
					( objectStatus "dq(2)" )
				)
				( pin "J4G2.157"
					( objectStatus "dq(3)" )
				)
				( pin "J4G2.3"
					( objectStatus "dq(4)" )
				)
				( pin "J4G2.148"
					( objectStatus "dq(5)" )
				)
				( pin "J4G2.10"
					( objectStatus "dq(6)" )
				)
				( pin "J4G2.155"
					( objectStatus "dq(7)" )
				)
				( pin "J4G2.16"
					( objectStatus "dq(8)" )
				)
				( pin "J4G2.161"
					( objectStatus "dq(9)" )
				)
				( pin "J4G2.23"
					( objectStatus "dq(10)" )
				)
				( pin "J4G2.168"
					( objectStatus "dq(11)" )
				)
				( pin "J4G2.14"
					( objectStatus "dq(12)" )
				)
				( pin "J4G2.159"
					( objectStatus "dq(13)" )
				)
				( pin "J4G2.21"
					( objectStatus "dq(14)" )
				)
				( pin "J4G2.166"
					( objectStatus "dq(15)" )
				)
				( pin "J4G2.27"
					( objectStatus "dq(16)" )
				)
				( pin "J4G2.172"
					( objectStatus "dq(17)" )
				)
				( pin "J4G2.34"
					( objectStatus "dq(18)" )
				)
				( pin "J4G2.179"
					( objectStatus "dq(19)" )
				)
				( pin "J4G2.25"
					( objectStatus "dq(20)" )
				)
				( pin "J4G2.170"
					( objectStatus "dq(21)" )
				)
				( pin "J4G2.32"
					( objectStatus "dq(22)" )
				)
				( pin "J4G2.177"
					( objectStatus "dq(23)" )
				)
				( pin "J4G2.38"
					( objectStatus "dq(24)" )
				)
				( pin "J4G2.183"
					( objectStatus "dq(25)" )
				)
				( pin "J4G2.45"
					( objectStatus "dq(26)" )
				)
				( pin "J4G2.190"
					( objectStatus "dq(27)" )
				)
				( pin "J4G2.36"
					( objectStatus "dq(28)" )
				)
				( pin "J4G2.181"
					( objectStatus "dq(29)" )
				)
				( pin "J4G2.43"
					( objectStatus "dq(30)" )
				)
				( pin "J4G2.188"
					( objectStatus "dq(31)" )
				)
				( pin "J4G2.97"
					( objectStatus "dq(32)" )
				)
				( pin "J4G2.242"
					( objectStatus "dq(33)" )
				)
				( pin "J4G2.104"
					( objectStatus "dq(34)" )
				)
				( pin "J4G2.249"
					( objectStatus "dq(35)" )
				)
				( pin "J4G2.95"
					( objectStatus "dq(36)" )
				)
				( pin "J4G2.240"
					( objectStatus "dq(37)" )
				)
				( pin "J4G2.102"
					( objectStatus "dq(38)" )
				)
				( pin "J4G2.247"
					( objectStatus "dq(39)" )
				)
				( pin "J4G2.108"
					( objectStatus "dq(40)" )
				)
				( pin "J4G2.253"
					( objectStatus "dq(41)" )
				)
				( pin "J4G2.115"
					( objectStatus "dq(42)" )
				)
				( pin "J4G2.260"
					( objectStatus "dq(43)" )
				)
				( pin "J4G2.106"
					( objectStatus "dq(44)" )
				)
				( pin "J4G2.251"
					( objectStatus "dq(45)" )
				)
				( pin "J4G2.113"
					( objectStatus "dq(46)" )
				)
				( pin "J4G2.258"
					( objectStatus "dq(47)" )
				)
				( pin "J4G2.119"
					( objectStatus "dq(48)" )
				)
				( pin "J4G2.264"
					( objectStatus "dq(49)" )
				)
				( pin "J4G2.126"
					( objectStatus "dq(50)" )
				)
				( pin "J4G2.271"
					( objectStatus "dq(51)" )
				)
				( pin "J4G2.117"
					( objectStatus "dq(52)" )
				)
				( pin "J4G2.262"
					( objectStatus "dq(53)" )
				)
				( pin "J4G2.124"
					( objectStatus "dq(54)" )
				)
				( pin "J4G2.269"
					( objectStatus "dq(55)" )
				)
				( pin "J4G2.130"
					( objectStatus "dq(56)" )
				)
				( pin "J4G2.275"
					( objectStatus "dq(57)" )
				)
				( pin "J4G2.137"
					( objectStatus "dq(58)" )
				)
				( pin "J4G2.282"
					( objectStatus "dq(59)" )
				)
				( pin "J4G2.128"
					( objectStatus "dq(60)" )
				)
				( pin "J4G2.273"
					( objectStatus "dq(61)" )
				)
				( pin "J4G2.135"
					( objectStatus "dq(62)" )
				)
				( pin "J4G2.280"
					( objectStatus "dq(63)" )
				)
				( pin "J4G2.78"
					( objectStatus "event_n" )
				)
				( pin "J4G2.87"
					( objectStatus "odt(0)" )
				)
				( pin "J4G2.91"
					( objectStatus "odt(1)" )
				)
				( pin "J4G2.222"
					( objectStatus "par" )
				)
				( pin "J4G2.58"
					( objectStatus "reset_n" )
				)
				( pin "J4G2.205"
					( objectStatus "rfu(0)" )
				)
				( pin "J4G2.227"
					( objectStatus "rfu(1)" )
				)
				( pin "J4G2.144"
					( objectStatus "rfu(2)" )
				)
				( pin "J4G2.84"
					( objectStatus "s0_n" )
				)
				( pin "J4G2.89"
					( objectStatus "s1_n" )
				)
				( pin "J4G2.93"
					( objectStatus "s2_n_c(0)" )
				)
				( pin "J4G2.237"
					( objectStatus "s3_n_c(1)" )
				)
				( pin "J4G2.139"
					( objectStatus "sa(0)" )
				)
				( pin "J4G2.140"
					( objectStatus "sa(1)" )
				)
				( pin "J4G2.238"
					( objectStatus "sa(2)" )
				)
				( pin "J4G2.230"
					( objectStatus "save_n_nc" )
				)
				( pin "J4G2.141"
					( objectStatus "scl" )
				)
				( pin "J4G2.285"
					( objectStatus "sda" )
				)
				( pin "J4G2.284"
					( objectStatus "vddspd" )
				)
				( pin "J4G2.146"
					( objectStatus "vrefca" )
				)
			)
			( gate "J4G2"
				( objectStatus "@baseboard_fab2_lib.baseboard_fab2(sch_1):page45_i169" )
				( pin "J4G2.145"
					( objectStatus "\12v\(0)" )
				)
				( pin "J4G2.1"
					( objectStatus "\12v\(1)" )
				)
				( pin "J4G2.236"
					( objectStatus "vdd(0)" )
				)
				( pin "J4G2.233"
					( objectStatus "vdd(1)" )
				)
				( pin "J4G2.231"
					( objectStatus "vdd(2)" )
				)
				( pin "J4G2.229"
					( objectStatus "vdd(3)" )
				)
				( pin "J4G2.226"
					( objectStatus "vdd(4)" )
				)
				( pin "J4G2.223"
					( objectStatus "vdd(5)" )
				)
				( pin "J4G2.220"
					( objectStatus "vdd(6)" )
				)
				( pin "J4G2.217"
					( objectStatus "vdd(7)" )
				)
				( pin "J4G2.215"
					( objectStatus "vdd(8)" )
				)
				( pin "J4G2.212"
					( objectStatus "vdd(9)" )
				)
				( pin "J4G2.209"
					( objectStatus "vdd(10)" )
				)
				( pin "J4G2.206"
					( objectStatus "vdd(11)" )
				)
				( pin "J4G2.204"
					( objectStatus "vdd(12)" )
				)
				( pin "J4G2.92"
					( objectStatus "vdd(13)" )
				)
				( pin "J4G2.90"
					( objectStatus "vdd(14)" )
				)
				( pin "J4G2.88"
					( objectStatus "vdd(15)" )
				)
				( pin "J4G2.85"
					( objectStatus "vdd(16)" )
				)
				( pin "J4G2.83"
					( objectStatus "vdd(17)" )
				)
				( pin "J4G2.80"
					( objectStatus "vdd(18)" )
				)
				( pin "J4G2.76"
					( objectStatus "vdd(19)" )
				)
				( pin "J4G2.73"
					( objectStatus "vdd(20)" )
				)
				( pin "J4G2.70"
					( objectStatus "vdd(21)" )
				)
				( pin "J4G2.67"
					( objectStatus "vdd(22)" )
				)
				( pin "J4G2.64"
					( objectStatus "vdd(23)" )
				)
				( pin "J4G2.61"
					( objectStatus "vdd(24)" )
				)
				( pin "J4G2.59"
					( objectStatus "vdd(25)" )
				)
				( pin "J4G2.287"
					( objectStatus "vpp(0)" )
				)
				( pin "J4G2.286"
					( objectStatus "vpp(1)" )
				)
				( pin "J4G2.288"
					( objectStatus "vpp(2)" )
				)
				( pin "J4G2.143"
					( objectStatus "vpp(3)" )
				)
				( pin "J4G2.142"
					( objectStatus "vpp(4)" )
				)
				( pin "J4G2.221"
					( objectStatus "vtt(0)" )
				)
				( pin "J4G2.77"
					( objectStatus "vtt(1)" )
				)
			)
			( gate "C4G3"
				( objectStatus "@baseboard_fab2_lib.baseboard_fab2(sch_1):page45_i179" )
				( pin "C4G3.1"
					( objectStatus "a" )
				)
				( pin "C4G3.2"
					( objectStatus "b" )
				)
			)
			( gate "C6U9"
				( objectStatus "@baseboard_fab2_lib.baseboard_fab2(sch_1):page46_i5" )
				( pin "C6U9.1"
					( objectStatus "a" )
				)
				( pin "C6U9.2"
					( objectStatus "b" )
				)
			)
			( gate "J6U1"
				( objectStatus "@baseboard_fab2_lib.baseboard_fab2(sch_1):page46_i14" )
				( pin "J6U1.79"
					( objectStatus "a0" )
				)
				( pin "J6U1.72"
					( objectStatus "a1" )
				)
				( pin "J6U1.216"
					( objectStatus "a2" )
				)
				( pin "J6U1.71"
					( objectStatus "a3" )
				)
				( pin "J6U1.214"
					( objectStatus "a4" )
				)
				( pin "J6U1.213"
					( objectStatus "a5" )
				)
				( pin "J6U1.69"
					( objectStatus "a6" )
				)
				( pin "J6U1.211"
					( objectStatus "a7" )
				)
				( pin "J6U1.68"
					( objectStatus "a8" )
				)
				( pin "J6U1.66"
					( objectStatus "a9" )
				)
				( pin "J6U1.225"
					( objectStatus "a10" )
				)
				( pin "J6U1.210"
					( objectStatus "a11" )
				)
				( pin "J6U1.65"
					( objectStatus "a12" )
				)
				( pin "J6U1.232"
					( objectStatus "a13" )
				)
				( pin "J6U1.228"
					( objectStatus "a14_we_n" )
				)
				( pin "J6U1.86"
					( objectStatus "a15_cas_n" )
				)
				( pin "J6U1.82"
					( objectStatus "a16_ras_n" )
				)
				( pin "J6U1.234"
					( objectStatus "a17" )
				)
				( pin "J6U1.62"
					( objectStatus "act_n" )
				)
				( pin "J6U1.208"
					( objectStatus "alert_n" )
				)
				( pin "J6U1.81"
					( objectStatus "ba(0)" )
				)
				( pin "J6U1.224"
					( objectStatus "ba(1)" )
				)
				( pin "J6U1.63"
					( objectStatus "bg(0)" )
				)
				( pin "J6U1.207"
					( objectStatus "bg(1)" )
				)
				( pin "J6U1.235"
					( objectStatus "c(2)" )
				)
				( pin "J6U1.49"
					( objectStatus "cb(0)" )
				)
				( pin "J6U1.194"
					( objectStatus "cb(1)" )
				)
				( pin "J6U1.56"
					( objectStatus "cb(2)" )
				)
				( pin "J6U1.201"
					( objectStatus "cb(3)" )
				)
				( pin "J6U1.47"
					( objectStatus "cb(4)" )
				)
				( pin "J6U1.192"
					( objectStatus "cb(5)" )
				)
				( pin "J6U1.54"
					( objectStatus "cb(6)" )
				)
				( pin "J6U1.199"
					( objectStatus "cb(7)" )
				)
				( pin "J6U1.75"
					( objectStatus "ck0n" )
				)
				( pin "J6U1.74"
					( objectStatus "ck0p" )
				)
				( pin "J6U1.219"
					( objectStatus "ck1n" )
				)
				( pin "J6U1.218"
					( objectStatus "ck1p" )
				)
				( pin "J6U1.60"
					( objectStatus "cke(0)" )
				)
				( pin "J6U1.203"
					( objectStatus "cke(1)" )
				)
				( pin "J6U1.5"
					( objectStatus "dq(0)" )
				)
				( pin "J6U1.150"
					( objectStatus "dq(1)" )
				)
				( pin "J6U1.12"
					( objectStatus "dq(2)" )
				)
				( pin "J6U1.157"
					( objectStatus "dq(3)" )
				)
				( pin "J6U1.3"
					( objectStatus "dq(4)" )
				)
				( pin "J6U1.148"
					( objectStatus "dq(5)" )
				)
				( pin "J6U1.10"
					( objectStatus "dq(6)" )
				)
				( pin "J6U1.155"
					( objectStatus "dq(7)" )
				)
				( pin "J6U1.16"
					( objectStatus "dq(8)" )
				)
				( pin "J6U1.161"
					( objectStatus "dq(9)" )
				)
				( pin "J6U1.23"
					( objectStatus "dq(10)" )
				)
				( pin "J6U1.168"
					( objectStatus "dq(11)" )
				)
				( pin "J6U1.14"
					( objectStatus "dq(12)" )
				)
				( pin "J6U1.159"
					( objectStatus "dq(13)" )
				)
				( pin "J6U1.21"
					( objectStatus "dq(14)" )
				)
				( pin "J6U1.166"
					( objectStatus "dq(15)" )
				)
				( pin "J6U1.27"
					( objectStatus "dq(16)" )
				)
				( pin "J6U1.172"
					( objectStatus "dq(17)" )
				)
				( pin "J6U1.34"
					( objectStatus "dq(18)" )
				)
				( pin "J6U1.179"
					( objectStatus "dq(19)" )
				)
				( pin "J6U1.25"
					( objectStatus "dq(20)" )
				)
				( pin "J6U1.170"
					( objectStatus "dq(21)" )
				)
				( pin "J6U1.32"
					( objectStatus "dq(22)" )
				)
				( pin "J6U1.177"
					( objectStatus "dq(23)" )
				)
				( pin "J6U1.38"
					( objectStatus "dq(24)" )
				)
				( pin "J6U1.183"
					( objectStatus "dq(25)" )
				)
				( pin "J6U1.45"
					( objectStatus "dq(26)" )
				)
				( pin "J6U1.190"
					( objectStatus "dq(27)" )
				)
				( pin "J6U1.36"
					( objectStatus "dq(28)" )
				)
				( pin "J6U1.181"
					( objectStatus "dq(29)" )
				)
				( pin "J6U1.43"
					( objectStatus "dq(30)" )
				)
				( pin "J6U1.188"
					( objectStatus "dq(31)" )
				)
				( pin "J6U1.97"
					( objectStatus "dq(32)" )
				)
				( pin "J6U1.242"
					( objectStatus "dq(33)" )
				)
				( pin "J6U1.104"
					( objectStatus "dq(34)" )
				)
				( pin "J6U1.249"
					( objectStatus "dq(35)" )
				)
				( pin "J6U1.95"
					( objectStatus "dq(36)" )
				)
				( pin "J6U1.240"
					( objectStatus "dq(37)" )
				)
				( pin "J6U1.102"
					( objectStatus "dq(38)" )
				)
				( pin "J6U1.247"
					( objectStatus "dq(39)" )
				)
				( pin "J6U1.108"
					( objectStatus "dq(40)" )
				)
				( pin "J6U1.253"
					( objectStatus "dq(41)" )
				)
				( pin "J6U1.115"
					( objectStatus "dq(42)" )
				)
				( pin "J6U1.260"
					( objectStatus "dq(43)" )
				)
				( pin "J6U1.106"
					( objectStatus "dq(44)" )
				)
				( pin "J6U1.251"
					( objectStatus "dq(45)" )
				)
				( pin "J6U1.113"
					( objectStatus "dq(46)" )
				)
				( pin "J6U1.258"
					( objectStatus "dq(47)" )
				)
				( pin "J6U1.119"
					( objectStatus "dq(48)" )
				)
				( pin "J6U1.264"
					( objectStatus "dq(49)" )
				)
				( pin "J6U1.126"
					( objectStatus "dq(50)" )
				)
				( pin "J6U1.271"
					( objectStatus "dq(51)" )
				)
				( pin "J6U1.117"
					( objectStatus "dq(52)" )
				)
				( pin "J6U1.262"
					( objectStatus "dq(53)" )
				)
				( pin "J6U1.124"
					( objectStatus "dq(54)" )
				)
				( pin "J6U1.269"
					( objectStatus "dq(55)" )
				)
				( pin "J6U1.130"
					( objectStatus "dq(56)" )
				)
				( pin "J6U1.275"
					( objectStatus "dq(57)" )
				)
				( pin "J6U1.137"
					( objectStatus "dq(58)" )
				)
				( pin "J6U1.282"
					( objectStatus "dq(59)" )
				)
				( pin "J6U1.128"
					( objectStatus "dq(60)" )
				)
				( pin "J6U1.273"
					( objectStatus "dq(61)" )
				)
				( pin "J6U1.135"
					( objectStatus "dq(62)" )
				)
				( pin "J6U1.280"
					( objectStatus "dq(63)" )
				)
				( pin "J6U1.78"
					( objectStatus "event_n" )
				)
				( pin "J6U1.87"
					( objectStatus "odt(0)" )
				)
				( pin "J6U1.91"
					( objectStatus "odt(1)" )
				)
				( pin "J6U1.222"
					( objectStatus "par" )
				)
				( pin "J6U1.58"
					( objectStatus "reset_n" )
				)
				( pin "J6U1.205"
					( objectStatus "rfu(0)" )
				)
				( pin "J6U1.227"
					( objectStatus "rfu(1)" )
				)
				( pin "J6U1.144"
					( objectStatus "rfu(2)" )
				)
				( pin "J6U1.84"
					( objectStatus "s0_n" )
				)
				( pin "J6U1.89"
					( objectStatus "s1_n" )
				)
				( pin "J6U1.93"
					( objectStatus "s2_n_c(0)" )
				)
				( pin "J6U1.237"
					( objectStatus "s3_n_c(1)" )
				)
				( pin "J6U1.139"
					( objectStatus "sa(0)" )
				)
				( pin "J6U1.140"
					( objectStatus "sa(1)" )
				)
				( pin "J6U1.238"
					( objectStatus "sa(2)" )
				)
				( pin "J6U1.230"
					( objectStatus "save_n_nc" )
				)
				( pin "J6U1.141"
					( objectStatus "scl" )
				)
				( pin "J6U1.285"
					( objectStatus "sda" )
				)
				( pin "J6U1.284"
					( objectStatus "vddspd" )
				)
				( pin "J6U1.146"
					( objectStatus "vrefca" )
				)
			)
			( gate "J6U1"
				( objectStatus "@baseboard_fab2_lib.baseboard_fab2(sch_1):page46_i67" )
				( pin "J6U1.145"
					( objectStatus "\12v\(0)" )
				)
				( pin "J6U1.1"
					( objectStatus "\12v\(1)" )
				)
				( pin "J6U1.236"
					( objectStatus "vdd(0)" )
				)
				( pin "J6U1.233"
					( objectStatus "vdd(1)" )
				)
				( pin "J6U1.231"
					( objectStatus "vdd(2)" )
				)
				( pin "J6U1.229"
					( objectStatus "vdd(3)" )
				)
				( pin "J6U1.226"
					( objectStatus "vdd(4)" )
				)
				( pin "J6U1.223"
					( objectStatus "vdd(5)" )
				)
				( pin "J6U1.220"
					( objectStatus "vdd(6)" )
				)
				( pin "J6U1.217"
					( objectStatus "vdd(7)" )
				)
				( pin "J6U1.215"
					( objectStatus "vdd(8)" )
				)
				( pin "J6U1.212"
					( objectStatus "vdd(9)" )
				)
				( pin "J6U1.209"
					( objectStatus "vdd(10)" )
				)
				( pin "J6U1.206"
					( objectStatus "vdd(11)" )
				)
				( pin "J6U1.204"
					( objectStatus "vdd(12)" )
				)
				( pin "J6U1.92"
					( objectStatus "vdd(13)" )
				)
				( pin "J6U1.90"
					( objectStatus "vdd(14)" )
				)
				( pin "J6U1.88"
					( objectStatus "vdd(15)" )
				)
				( pin "J6U1.85"
					( objectStatus "vdd(16)" )
				)
				( pin "J6U1.83"
					( objectStatus "vdd(17)" )
				)
				( pin "J6U1.80"
					( objectStatus "vdd(18)" )
				)
				( pin "J6U1.76"
					( objectStatus "vdd(19)" )
				)
				( pin "J6U1.73"
					( objectStatus "vdd(20)" )
				)
				( pin "J6U1.70"
					( objectStatus "vdd(21)" )
				)
				( pin "J6U1.67"
					( objectStatus "vdd(22)" )
				)
				( pin "J6U1.64"
					( objectStatus "vdd(23)" )
				)
				( pin "J6U1.61"
					( objectStatus "vdd(24)" )
				)
				( pin "J6U1.59"
					( objectStatus "vdd(25)" )
				)
				( pin "J6U1.287"
					( objectStatus "vpp(0)" )
				)
				( pin "J6U1.286"
					( objectStatus "vpp(1)" )
				)
				( pin "J6U1.288"
					( objectStatus "vpp(2)" )
				)
				( pin "J6U1.143"
					( objectStatus "vpp(3)" )
				)
				( pin "J6U1.142"
					( objectStatus "vpp(4)" )
				)
				( pin "J6U1.221"
					( objectStatus "vtt(0)" )
				)
				( pin "J6U1.77"
					( objectStatus "vtt(1)" )
				)
			)
			( gate "J6U1"
				( objectStatus "@baseboard_fab2_lib.baseboard_fab2(sch_1):page46_i112" )
				( pin "J6U1.152"
					( objectStatus "dqs0n" )
				)
				( pin "J6U1.153"
					( objectStatus "dqs0p" )
				)
				( pin "J6U1.163"
					( objectStatus "dqs1n" )
				)
				( pin "J6U1.164"
					( objectStatus "dqs1p" )
				)
				( pin "J6U1.174"
					( objectStatus "dqs2n" )
				)
				( pin "J6U1.175"
					( objectStatus "dqs2p" )
				)
				( pin "J6U1.185"
					( objectStatus "dqs3n" )
				)
				( pin "J6U1.186"
					( objectStatus "dqs3p" )
				)
				( pin "J6U1.244"
					( objectStatus "dqs4n" )
				)
				( pin "J6U1.245"
					( objectStatus "dqs4p" )
				)
				( pin "J6U1.255"
					( objectStatus "dqs5n" )
				)
				( pin "J6U1.256"
					( objectStatus "dqs5p" )
				)
				( pin "J6U1.266"
					( objectStatus "dqs6n" )
				)
				( pin "J6U1.267"
					( objectStatus "dqs6p" )
				)
				( pin "J6U1.277"
					( objectStatus "dqs7n" )
				)
				( pin "J6U1.278"
					( objectStatus "dqs7p" )
				)
				( pin "J6U1.196"
					( objectStatus "dqs8n" )
				)
				( pin "J6U1.197"
					( objectStatus "dqs8p" )
				)
				( pin "J6U1.8"
					( objectStatus "dqs9n" )
				)
				( pin "J6U1.7"
					( objectStatus "dqs9p" )
				)
				( pin "J6U1.19"
					( objectStatus "dqs10n" )
				)
				( pin "J6U1.18"
					( objectStatus "dqs10p" )
				)
				( pin "J6U1.30"
					( objectStatus "dqs11n" )
				)
				( pin "J6U1.29"
					( objectStatus "dqs11p" )
				)
				( pin "J6U1.41"
					( objectStatus "dqs12n" )
				)
				( pin "J6U1.40"
					( objectStatus "dqs12p" )
				)
				( pin "J6U1.100"
					( objectStatus "dqs13n" )
				)
				( pin "J6U1.99"
					( objectStatus "dqs13p" )
				)
				( pin "J6U1.111"
					( objectStatus "dqs14n" )
				)
				( pin "J6U1.110"
					( objectStatus "dqs14p" )
				)
				( pin "J6U1.122"
					( objectStatus "dqs15n" )
				)
				( pin "J6U1.121"
					( objectStatus "dqs15p" )
				)
				( pin "J6U1.133"
					( objectStatus "dqs16n" )
				)
				( pin "J6U1.132"
					( objectStatus "dqs16p" )
				)
				( pin "J6U1.52"
					( objectStatus "dqs17n" )
				)
				( pin "J6U1.51"
					( objectStatus "dqs17p" )
				)
			)
			( gate "J6U1"
				( objectStatus "@baseboard_fab2_lib.baseboard_fab2(sch_1):page46_i138" )
				( pin "J6U1.283"
					( objectStatus "vss(0)" )
				)
				( pin "J6U1.281"
					( objectStatus "vss(1)" )
				)
				( pin "J6U1.279"
					( objectStatus "vss(2)" )
				)
				( pin "J6U1.276"
					( objectStatus "vss(3)" )
				)
				( pin "J6U1.274"
					( objectStatus "vss(4)" )
				)
				( pin "J6U1.272"
					( objectStatus "vss(5)" )
				)
				( pin "J6U1.270"
					( objectStatus "vss(6)" )
				)
				( pin "J6U1.268"
					( objectStatus "vss(7)" )
				)
				( pin "J6U1.265"
					( objectStatus "vss(8)" )
				)
				( pin "J6U1.263"
					( objectStatus "vss(9)" )
				)
				( pin "J6U1.261"
					( objectStatus "vss(10)" )
				)
				( pin "J6U1.259"
					( objectStatus "vss(11)" )
				)
				( pin "J6U1.257"
					( objectStatus "vss(12)" )
				)
				( pin "J6U1.254"
					( objectStatus "vss(13)" )
				)
				( pin "J6U1.252"
					( objectStatus "vss(14)" )
				)
				( pin "J6U1.250"
					( objectStatus "vss(15)" )
				)
				( pin "J6U1.248"
					( objectStatus "vss(16)" )
				)
				( pin "J6U1.246"
					( objectStatus "vss(17)" )
				)
				( pin "J6U1.243"
					( objectStatus "vss(18)" )
				)
				( pin "J6U1.241"
					( objectStatus "vss(19)" )
				)
				( pin "J6U1.239"
					( objectStatus "vss(20)" )
				)
				( pin "J6U1.202"
					( objectStatus "vss(21)" )
				)
				( pin "J6U1.200"
					( objectStatus "vss(22)" )
				)
				( pin "J6U1.198"
					( objectStatus "vss(23)" )
				)
				( pin "J6U1.195"
					( objectStatus "vss(24)" )
				)
				( pin "J6U1.193"
					( objectStatus "vss(25)" )
				)
				( pin "J6U1.191"
					( objectStatus "vss(26)" )
				)
				( pin "J6U1.189"
					( objectStatus "vss(27)" )
				)
				( pin "J6U1.187"
					( objectStatus "vss(28)" )
				)
				( pin "J6U1.184"
					( objectStatus "vss(29)" )
				)
				( pin "J6U1.182"
					( objectStatus "vss(30)" )
				)
				( pin "J6U1.180"
					( objectStatus "vss(31)" )
				)
				( pin "J6U1.178"
					( objectStatus "vss(32)" )
				)
				( pin "J6U1.176"
					( objectStatus "vss(33)" )
				)
				( pin "J6U1.173"
					( objectStatus "vss(34)" )
				)
				( pin "J6U1.171"
					( objectStatus "vss(35)" )
				)
				( pin "J6U1.169"
					( objectStatus "vss(36)" )
				)
				( pin "J6U1.167"
					( objectStatus "vss(37)" )
				)
				( pin "J6U1.165"
					( objectStatus "vss(38)" )
				)
				( pin "J6U1.162"
					( objectStatus "vss(39)" )
				)
				( pin "J6U1.160"
					( objectStatus "vss(40)" )
				)
				( pin "J6U1.158"
					( objectStatus "vss(41)" )
				)
				( pin "J6U1.156"
					( objectStatus "vss(42)" )
				)
				( pin "J6U1.154"
					( objectStatus "vss(43)" )
				)
				( pin "J6U1.151"
					( objectStatus "vss(44)" )
				)
				( pin "J6U1.149"
					( objectStatus "vss(45)" )
				)
				( pin "J6U1.147"
					( objectStatus "vss(46)" )
				)
				( pin "J6U1.138"
					( objectStatus "vss(47)" )
				)
				( pin "J6U1.136"
					( objectStatus "vss(48)" )
				)
				( pin "J6U1.134"
					( objectStatus "vss(49)" )
				)
				( pin "J6U1.131"
					( objectStatus "vss(50)" )
				)
				( pin "J6U1.129"
					( objectStatus "vss(51)" )
				)
				( pin "J6U1.127"
					( objectStatus "vss(52)" )
				)
				( pin "J6U1.125"
					( objectStatus "vss(53)" )
				)
				( pin "J6U1.123"
					( objectStatus "vss(54)" )
				)
				( pin "J6U1.120"
					( objectStatus "vss(55)" )
				)
				( pin "J6U1.118"
					( objectStatus "vss(56)" )
				)
				( pin "J6U1.116"
					( objectStatus "vss(57)" )
				)
				( pin "J6U1.114"
					( objectStatus "vss(58)" )
				)
				( pin "J6U1.112"
					( objectStatus "vss(59)" )
				)
				( pin "J6U1.109"
					( objectStatus "vss(60)" )
				)
				( pin "J6U1.107"
					( objectStatus "vss(61)" )
				)
				( pin "J6U1.105"
					( objectStatus "vss(62)" )
				)
				( pin "J6U1.103"
					( objectStatus "vss(63)" )
				)
				( pin "J6U1.101"
					( objectStatus "vss(64)" )
				)
				( pin "J6U1.98"
					( objectStatus "vss(65)" )
				)
				( pin "J6U1.96"
					( objectStatus "vss(66)" )
				)
				( pin "J6U1.94"
					( objectStatus "vss(67)" )
				)
				( pin "J6U1.57"
					( objectStatus "vss(68)" )
				)
				( pin "J6U1.55"
					( objectStatus "vss(69)" )
				)
				( pin "J6U1.53"
					( objectStatus "vss(70)" )
				)
				( pin "J6U1.50"
					( objectStatus "vss(71)" )
				)
				( pin "J6U1.48"
					( objectStatus "vss(72)" )
				)
				( pin "J6U1.46"
					( objectStatus "vss(73)" )
				)
				( pin "J6U1.44"
					( objectStatus "vss(74)" )
				)
				( pin "J6U1.42"
					( objectStatus "vss(75)" )
				)
				( pin "J6U1.39"
					( objectStatus "vss(76)" )
				)
				( pin "J6U1.37"
					( objectStatus "vss(77)" )
				)
				( pin "J6U1.35"
					( objectStatus "vss(78)" )
				)
				( pin "J6U1.33"
					( objectStatus "vss(79)" )
				)
				( pin "J6U1.31"
					( objectStatus "vss(80)" )
				)
				( pin "J6U1.28"
					( objectStatus "vss(81)" )
				)
				( pin "J6U1.26"
					( objectStatus "vss(82)" )
				)
				( pin "J6U1.24"
					( objectStatus "vss(83)" )
				)
				( pin "J6U1.22"
					( objectStatus "vss(84)" )
				)
				( pin "J6U1.20"
					( objectStatus "vss(85)" )
				)
				( pin "J6U1.17"
					( objectStatus "vss(86)" )
				)
				( pin "J6U1.15"
					( objectStatus "vss(87)" )
				)
				( pin "J6U1.13"
					( objectStatus "vss(88)" )
				)
				( pin "J6U1.11"
					( objectStatus "vss(89)" )
				)
				( pin "J6U1.9"
					( objectStatus "vss(90)" )
				)
				( pin "J6U1.6"
					( objectStatus "vss(91)" )
				)
				( pin "J6U1.4"
					( objectStatus "vss(92)" )
				)
				( pin "J6U1.2"
					( objectStatus "vss(93)" )
				)
			)
			( gate "J4G3"
				( objectStatus "@baseboard_fab2_lib.baseboard_fab2(sch_1):page47_i43" )
				( pin "J4G3.283"
					( objectStatus "vss(0)" )
				)
				( pin "J4G3.281"
					( objectStatus "vss(1)" )
				)
				( pin "J4G3.279"
					( objectStatus "vss(2)" )
				)
				( pin "J4G3.276"
					( objectStatus "vss(3)" )
				)
				( pin "J4G3.274"
					( objectStatus "vss(4)" )
				)
				( pin "J4G3.272"
					( objectStatus "vss(5)" )
				)
				( pin "J4G3.270"
					( objectStatus "vss(6)" )
				)
				( pin "J4G3.268"
					( objectStatus "vss(7)" )
				)
				( pin "J4G3.265"
					( objectStatus "vss(8)" )
				)
				( pin "J4G3.263"
					( objectStatus "vss(9)" )
				)
				( pin "J4G3.261"
					( objectStatus "vss(10)" )
				)
				( pin "J4G3.259"
					( objectStatus "vss(11)" )
				)
				( pin "J4G3.257"
					( objectStatus "vss(12)" )
				)
				( pin "J4G3.254"
					( objectStatus "vss(13)" )
				)
				( pin "J4G3.252"
					( objectStatus "vss(14)" )
				)
				( pin "J4G3.250"
					( objectStatus "vss(15)" )
				)
				( pin "J4G3.248"
					( objectStatus "vss(16)" )
				)
				( pin "J4G3.246"
					( objectStatus "vss(17)" )
				)
				( pin "J4G3.243"
					( objectStatus "vss(18)" )
				)
				( pin "J4G3.241"
					( objectStatus "vss(19)" )
				)
				( pin "J4G3.239"
					( objectStatus "vss(20)" )
				)
				( pin "J4G3.202"
					( objectStatus "vss(21)" )
				)
				( pin "J4G3.200"
					( objectStatus "vss(22)" )
				)
				( pin "J4G3.198"
					( objectStatus "vss(23)" )
				)
				( pin "J4G3.195"
					( objectStatus "vss(24)" )
				)
				( pin "J4G3.193"
					( objectStatus "vss(25)" )
				)
				( pin "J4G3.191"
					( objectStatus "vss(26)" )
				)
				( pin "J4G3.189"
					( objectStatus "vss(27)" )
				)
				( pin "J4G3.187"
					( objectStatus "vss(28)" )
				)
				( pin "J4G3.184"
					( objectStatus "vss(29)" )
				)
				( pin "J4G3.182"
					( objectStatus "vss(30)" )
				)
				( pin "J4G3.180"
					( objectStatus "vss(31)" )
				)
				( pin "J4G3.178"
					( objectStatus "vss(32)" )
				)
				( pin "J4G3.176"
					( objectStatus "vss(33)" )
				)
				( pin "J4G3.173"
					( objectStatus "vss(34)" )
				)
				( pin "J4G3.171"
					( objectStatus "vss(35)" )
				)
				( pin "J4G3.169"
					( objectStatus "vss(36)" )
				)
				( pin "J4G3.167"
					( objectStatus "vss(37)" )
				)
				( pin "J4G3.165"
					( objectStatus "vss(38)" )
				)
				( pin "J4G3.162"
					( objectStatus "vss(39)" )
				)
				( pin "J4G3.160"
					( objectStatus "vss(40)" )
				)
				( pin "J4G3.158"
					( objectStatus "vss(41)" )
				)
				( pin "J4G3.156"
					( objectStatus "vss(42)" )
				)
				( pin "J4G3.154"
					( objectStatus "vss(43)" )
				)
				( pin "J4G3.151"
					( objectStatus "vss(44)" )
				)
				( pin "J4G3.149"
					( objectStatus "vss(45)" )
				)
				( pin "J4G3.147"
					( objectStatus "vss(46)" )
				)
				( pin "J4G3.138"
					( objectStatus "vss(47)" )
				)
				( pin "J4G3.136"
					( objectStatus "vss(48)" )
				)
				( pin "J4G3.134"
					( objectStatus "vss(49)" )
				)
				( pin "J4G3.131"
					( objectStatus "vss(50)" )
				)
				( pin "J4G3.129"
					( objectStatus "vss(51)" )
				)
				( pin "J4G3.127"
					( objectStatus "vss(52)" )
				)
				( pin "J4G3.125"
					( objectStatus "vss(53)" )
				)
				( pin "J4G3.123"
					( objectStatus "vss(54)" )
				)
				( pin "J4G3.120"
					( objectStatus "vss(55)" )
				)
				( pin "J4G3.118"
					( objectStatus "vss(56)" )
				)
				( pin "J4G3.116"
					( objectStatus "vss(57)" )
				)
				( pin "J4G3.114"
					( objectStatus "vss(58)" )
				)
				( pin "J4G3.112"
					( objectStatus "vss(59)" )
				)
				( pin "J4G3.109"
					( objectStatus "vss(60)" )
				)
				( pin "J4G3.107"
					( objectStatus "vss(61)" )
				)
				( pin "J4G3.105"
					( objectStatus "vss(62)" )
				)
				( pin "J4G3.103"
					( objectStatus "vss(63)" )
				)
				( pin "J4G3.101"
					( objectStatus "vss(64)" )
				)
				( pin "J4G3.98"
					( objectStatus "vss(65)" )
				)
				( pin "J4G3.96"
					( objectStatus "vss(66)" )
				)
				( pin "J4G3.94"
					( objectStatus "vss(67)" )
				)
				( pin "J4G3.57"
					( objectStatus "vss(68)" )
				)
				( pin "J4G3.55"
					( objectStatus "vss(69)" )
				)
				( pin "J4G3.53"
					( objectStatus "vss(70)" )
				)
				( pin "J4G3.50"
					( objectStatus "vss(71)" )
				)
				( pin "J4G3.48"
					( objectStatus "vss(72)" )
				)
				( pin "J4G3.46"
					( objectStatus "vss(73)" )
				)
				( pin "J4G3.44"
					( objectStatus "vss(74)" )
				)
				( pin "J4G3.42"
					( objectStatus "vss(75)" )
				)
				( pin "J4G3.39"
					( objectStatus "vss(76)" )
				)
				( pin "J4G3.37"
					( objectStatus "vss(77)" )
				)
				( pin "J4G3.35"
					( objectStatus "vss(78)" )
				)
				( pin "J4G3.33"
					( objectStatus "vss(79)" )
				)
				( pin "J4G3.31"
					( objectStatus "vss(80)" )
				)
				( pin "J4G3.28"
					( objectStatus "vss(81)" )
				)
				( pin "J4G3.26"
					( objectStatus "vss(82)" )
				)
				( pin "J4G3.24"
					( objectStatus "vss(83)" )
				)
				( pin "J4G3.22"
					( objectStatus "vss(84)" )
				)
				( pin "J4G3.20"
					( objectStatus "vss(85)" )
				)
				( pin "J4G3.17"
					( objectStatus "vss(86)" )
				)
				( pin "J4G3.15"
					( objectStatus "vss(87)" )
				)
				( pin "J4G3.13"
					( objectStatus "vss(88)" )
				)
				( pin "J4G3.11"
					( objectStatus "vss(89)" )
				)
				( pin "J4G3.9"
					( objectStatus "vss(90)" )
				)
				( pin "J4G3.6"
					( objectStatus "vss(91)" )
				)
				( pin "J4G3.4"
					( objectStatus "vss(92)" )
				)
				( pin "J4G3.2"
					( objectStatus "vss(93)" )
				)
			)
			( gate "J4G3"
				( objectStatus "@baseboard_fab2_lib.baseboard_fab2(sch_1):page47_i61" )
				( pin "J4G3.152"
					( objectStatus "dqs0n" )
				)
				( pin "J4G3.153"
					( objectStatus "dqs0p" )
				)
				( pin "J4G3.163"
					( objectStatus "dqs1n" )
				)
				( pin "J4G3.164"
					( objectStatus "dqs1p" )
				)
				( pin "J4G3.174"
					( objectStatus "dqs2n" )
				)
				( pin "J4G3.175"
					( objectStatus "dqs2p" )
				)
				( pin "J4G3.185"
					( objectStatus "dqs3n" )
				)
				( pin "J4G3.186"
					( objectStatus "dqs3p" )
				)
				( pin "J4G3.244"
					( objectStatus "dqs4n" )
				)
				( pin "J4G3.245"
					( objectStatus "dqs4p" )
				)
				( pin "J4G3.255"
					( objectStatus "dqs5n" )
				)
				( pin "J4G3.256"
					( objectStatus "dqs5p" )
				)
				( pin "J4G3.266"
					( objectStatus "dqs6n" )
				)
				( pin "J4G3.267"
					( objectStatus "dqs6p" )
				)
				( pin "J4G3.277"
					( objectStatus "dqs7n" )
				)
				( pin "J4G3.278"
					( objectStatus "dqs7p" )
				)
				( pin "J4G3.196"
					( objectStatus "dqs8n" )
				)
				( pin "J4G3.197"
					( objectStatus "dqs8p" )
				)
				( pin "J4G3.8"
					( objectStatus "dqs9n" )
				)
				( pin "J4G3.7"
					( objectStatus "dqs9p" )
				)
				( pin "J4G3.19"
					( objectStatus "dqs10n" )
				)
				( pin "J4G3.18"
					( objectStatus "dqs10p" )
				)
				( pin "J4G3.30"
					( objectStatus "dqs11n" )
				)
				( pin "J4G3.29"
					( objectStatus "dqs11p" )
				)
				( pin "J4G3.41"
					( objectStatus "dqs12n" )
				)
				( pin "J4G3.40"
					( objectStatus "dqs12p" )
				)
				( pin "J4G3.100"
					( objectStatus "dqs13n" )
				)
				( pin "J4G3.99"
					( objectStatus "dqs13p" )
				)
				( pin "J4G3.111"
					( objectStatus "dqs14n" )
				)
				( pin "J4G3.110"
					( objectStatus "dqs14p" )
				)
				( pin "J4G3.122"
					( objectStatus "dqs15n" )
				)
				( pin "J4G3.121"
					( objectStatus "dqs15p" )
				)
				( pin "J4G3.133"
					( objectStatus "dqs16n" )
				)
				( pin "J4G3.132"
					( objectStatus "dqs16p" )
				)
				( pin "J4G3.52"
					( objectStatus "dqs17n" )
				)
				( pin "J4G3.51"
					( objectStatus "dqs17p" )
				)
			)
			( gate "J4G3"
				( objectStatus "@baseboard_fab2_lib.baseboard_fab2(sch_1):page47_i111" )
				( pin "J4G3.79"
					( objectStatus "a0" )
				)
				( pin "J4G3.72"
					( objectStatus "a1" )
				)
				( pin "J4G3.216"
					( objectStatus "a2" )
				)
				( pin "J4G3.71"
					( objectStatus "a3" )
				)
				( pin "J4G3.214"
					( objectStatus "a4" )
				)
				( pin "J4G3.213"
					( objectStatus "a5" )
				)
				( pin "J4G3.69"
					( objectStatus "a6" )
				)
				( pin "J4G3.211"
					( objectStatus "a7" )
				)
				( pin "J4G3.68"
					( objectStatus "a8" )
				)
				( pin "J4G3.66"
					( objectStatus "a9" )
				)
				( pin "J4G3.225"
					( objectStatus "a10" )
				)
				( pin "J4G3.210"
					( objectStatus "a11" )
				)
				( pin "J4G3.65"
					( objectStatus "a12" )
				)
				( pin "J4G3.232"
					( objectStatus "a13" )
				)
				( pin "J4G3.228"
					( objectStatus "a14_we_n" )
				)
				( pin "J4G3.86"
					( objectStatus "a15_cas_n" )
				)
				( pin "J4G3.82"
					( objectStatus "a16_ras_n" )
				)
				( pin "J4G3.234"
					( objectStatus "a17" )
				)
				( pin "J4G3.62"
					( objectStatus "act_n" )
				)
				( pin "J4G3.208"
					( objectStatus "alert_n" )
				)
				( pin "J4G3.81"
					( objectStatus "ba(0)" )
				)
				( pin "J4G3.224"
					( objectStatus "ba(1)" )
				)
				( pin "J4G3.63"
					( objectStatus "bg(0)" )
				)
				( pin "J4G3.207"
					( objectStatus "bg(1)" )
				)
				( pin "J4G3.235"
					( objectStatus "c(2)" )
				)
				( pin "J4G3.49"
					( objectStatus "cb(0)" )
				)
				( pin "J4G3.194"
					( objectStatus "cb(1)" )
				)
				( pin "J4G3.56"
					( objectStatus "cb(2)" )
				)
				( pin "J4G3.201"
					( objectStatus "cb(3)" )
				)
				( pin "J4G3.47"
					( objectStatus "cb(4)" )
				)
				( pin "J4G3.192"
					( objectStatus "cb(5)" )
				)
				( pin "J4G3.54"
					( objectStatus "cb(6)" )
				)
				( pin "J4G3.199"
					( objectStatus "cb(7)" )
				)
				( pin "J4G3.75"
					( objectStatus "ck0n" )
				)
				( pin "J4G3.74"
					( objectStatus "ck0p" )
				)
				( pin "J4G3.219"
					( objectStatus "ck1n" )
				)
				( pin "J4G3.218"
					( objectStatus "ck1p" )
				)
				( pin "J4G3.60"
					( objectStatus "cke(0)" )
				)
				( pin "J4G3.203"
					( objectStatus "cke(1)" )
				)
				( pin "J4G3.5"
					( objectStatus "dq(0)" )
				)
				( pin "J4G3.150"
					( objectStatus "dq(1)" )
				)
				( pin "J4G3.12"
					( objectStatus "dq(2)" )
				)
				( pin "J4G3.157"
					( objectStatus "dq(3)" )
				)
				( pin "J4G3.3"
					( objectStatus "dq(4)" )
				)
				( pin "J4G3.148"
					( objectStatus "dq(5)" )
				)
				( pin "J4G3.10"
					( objectStatus "dq(6)" )
				)
				( pin "J4G3.155"
					( objectStatus "dq(7)" )
				)
				( pin "J4G3.16"
					( objectStatus "dq(8)" )
				)
				( pin "J4G3.161"
					( objectStatus "dq(9)" )
				)
				( pin "J4G3.23"
					( objectStatus "dq(10)" )
				)
				( pin "J4G3.168"
					( objectStatus "dq(11)" )
				)
				( pin "J4G3.14"
					( objectStatus "dq(12)" )
				)
				( pin "J4G3.159"
					( objectStatus "dq(13)" )
				)
				( pin "J4G3.21"
					( objectStatus "dq(14)" )
				)
				( pin "J4G3.166"
					( objectStatus "dq(15)" )
				)
				( pin "J4G3.27"
					( objectStatus "dq(16)" )
				)
				( pin "J4G3.172"
					( objectStatus "dq(17)" )
				)
				( pin "J4G3.34"
					( objectStatus "dq(18)" )
				)
				( pin "J4G3.179"
					( objectStatus "dq(19)" )
				)
				( pin "J4G3.25"
					( objectStatus "dq(20)" )
				)
				( pin "J4G3.170"
					( objectStatus "dq(21)" )
				)
				( pin "J4G3.32"
					( objectStatus "dq(22)" )
				)
				( pin "J4G3.177"
					( objectStatus "dq(23)" )
				)
				( pin "J4G3.38"
					( objectStatus "dq(24)" )
				)
				( pin "J4G3.183"
					( objectStatus "dq(25)" )
				)
				( pin "J4G3.45"
					( objectStatus "dq(26)" )
				)
				( pin "J4G3.190"
					( objectStatus "dq(27)" )
				)
				( pin "J4G3.36"
					( objectStatus "dq(28)" )
				)
				( pin "J4G3.181"
					( objectStatus "dq(29)" )
				)
				( pin "J4G3.43"
					( objectStatus "dq(30)" )
				)
				( pin "J4G3.188"
					( objectStatus "dq(31)" )
				)
				( pin "J4G3.97"
					( objectStatus "dq(32)" )
				)
				( pin "J4G3.242"
					( objectStatus "dq(33)" )
				)
				( pin "J4G3.104"
					( objectStatus "dq(34)" )
				)
				( pin "J4G3.249"
					( objectStatus "dq(35)" )
				)
				( pin "J4G3.95"
					( objectStatus "dq(36)" )
				)
				( pin "J4G3.240"
					( objectStatus "dq(37)" )
				)
				( pin "J4G3.102"
					( objectStatus "dq(38)" )
				)
				( pin "J4G3.247"
					( objectStatus "dq(39)" )
				)
				( pin "J4G3.108"
					( objectStatus "dq(40)" )
				)
				( pin "J4G3.253"
					( objectStatus "dq(41)" )
				)
				( pin "J4G3.115"
					( objectStatus "dq(42)" )
				)
				( pin "J4G3.260"
					( objectStatus "dq(43)" )
				)
				( pin "J4G3.106"
					( objectStatus "dq(44)" )
				)
				( pin "J4G3.251"
					( objectStatus "dq(45)" )
				)
				( pin "J4G3.113"
					( objectStatus "dq(46)" )
				)
				( pin "J4G3.258"
					( objectStatus "dq(47)" )
				)
				( pin "J4G3.119"
					( objectStatus "dq(48)" )
				)
				( pin "J4G3.264"
					( objectStatus "dq(49)" )
				)
				( pin "J4G3.126"
					( objectStatus "dq(50)" )
				)
				( pin "J4G3.271"
					( objectStatus "dq(51)" )
				)
				( pin "J4G3.117"
					( objectStatus "dq(52)" )
				)
				( pin "J4G3.262"
					( objectStatus "dq(53)" )
				)
				( pin "J4G3.124"
					( objectStatus "dq(54)" )
				)
				( pin "J4G3.269"
					( objectStatus "dq(55)" )
				)
				( pin "J4G3.130"
					( objectStatus "dq(56)" )
				)
				( pin "J4G3.275"
					( objectStatus "dq(57)" )
				)
				( pin "J4G3.137"
					( objectStatus "dq(58)" )
				)
				( pin "J4G3.282"
					( objectStatus "dq(59)" )
				)
				( pin "J4G3.128"
					( objectStatus "dq(60)" )
				)
				( pin "J4G3.273"
					( objectStatus "dq(61)" )
				)
				( pin "J4G3.135"
					( objectStatus "dq(62)" )
				)
				( pin "J4G3.280"
					( objectStatus "dq(63)" )
				)
				( pin "J4G3.78"
					( objectStatus "event_n" )
				)
				( pin "J4G3.87"
					( objectStatus "odt(0)" )
				)
				( pin "J4G3.91"
					( objectStatus "odt(1)" )
				)
				( pin "J4G3.222"
					( objectStatus "par" )
				)
				( pin "J4G3.58"
					( objectStatus "reset_n" )
				)
				( pin "J4G3.205"
					( objectStatus "rfu(0)" )
				)
				( pin "J4G3.227"
					( objectStatus "rfu(1)" )
				)
				( pin "J4G3.144"
					( objectStatus "rfu(2)" )
				)
				( pin "J4G3.84"
					( objectStatus "s0_n" )
				)
				( pin "J4G3.89"
					( objectStatus "s1_n" )
				)
				( pin "J4G3.93"
					( objectStatus "s2_n_c(0)" )
				)
				( pin "J4G3.237"
					( objectStatus "s3_n_c(1)" )
				)
				( pin "J4G3.139"
					( objectStatus "sa(0)" )
				)
				( pin "J4G3.140"
					( objectStatus "sa(1)" )
				)
				( pin "J4G3.238"
					( objectStatus "sa(2)" )
				)
				( pin "J4G3.230"
					( objectStatus "save_n_nc" )
				)
				( pin "J4G3.141"
					( objectStatus "scl" )
				)
				( pin "J4G3.285"
					( objectStatus "sda" )
				)
				( pin "J4G3.284"
					( objectStatus "vddspd" )
				)
				( pin "J4G3.146"
					( objectStatus "vrefca" )
				)
			)
			( gate "J4G3"
				( objectStatus "@baseboard_fab2_lib.baseboard_fab2(sch_1):page47_i179" )
				( pin "J4G3.145"
					( objectStatus "\12v\(0)" )
				)
				( pin "J4G3.1"
					( objectStatus "\12v\(1)" )
				)
				( pin "J4G3.236"
					( objectStatus "vdd(0)" )
				)
				( pin "J4G3.233"
					( objectStatus "vdd(1)" )
				)
				( pin "J4G3.231"
					( objectStatus "vdd(2)" )
				)
				( pin "J4G3.229"
					( objectStatus "vdd(3)" )
				)
				( pin "J4G3.226"
					( objectStatus "vdd(4)" )
				)
				( pin "J4G3.223"
					( objectStatus "vdd(5)" )
				)
				( pin "J4G3.220"
					( objectStatus "vdd(6)" )
				)
				( pin "J4G3.217"
					( objectStatus "vdd(7)" )
				)
				( pin "J4G3.215"
					( objectStatus "vdd(8)" )
				)
				( pin "J4G3.212"
					( objectStatus "vdd(9)" )
				)
				( pin "J4G3.209"
					( objectStatus "vdd(10)" )
				)
				( pin "J4G3.206"
					( objectStatus "vdd(11)" )
				)
				( pin "J4G3.204"
					( objectStatus "vdd(12)" )
				)
				( pin "J4G3.92"
					( objectStatus "vdd(13)" )
				)
				( pin "J4G3.90"
					( objectStatus "vdd(14)" )
				)
				( pin "J4G3.88"
					( objectStatus "vdd(15)" )
				)
				( pin "J4G3.85"
					( objectStatus "vdd(16)" )
				)
				( pin "J4G3.83"
					( objectStatus "vdd(17)" )
				)
				( pin "J4G3.80"
					( objectStatus "vdd(18)" )
				)
				( pin "J4G3.76"
					( objectStatus "vdd(19)" )
				)
				( pin "J4G3.73"
					( objectStatus "vdd(20)" )
				)
				( pin "J4G3.70"
					( objectStatus "vdd(21)" )
				)
				( pin "J4G3.67"
					( objectStatus "vdd(22)" )
				)
				( pin "J4G3.64"
					( objectStatus "vdd(23)" )
				)
				( pin "J4G3.61"
					( objectStatus "vdd(24)" )
				)
				( pin "J4G3.59"
					( objectStatus "vdd(25)" )
				)
				( pin "J4G3.287"
					( objectStatus "vpp(0)" )
				)
				( pin "J4G3.286"
					( objectStatus "vpp(1)" )
				)
				( pin "J4G3.288"
					( objectStatus "vpp(2)" )
				)
				( pin "J4G3.143"
					( objectStatus "vpp(3)" )
				)
				( pin "J4G3.142"
					( objectStatus "vpp(4)" )
				)
				( pin "J4G3.221"
					( objectStatus "vtt(0)" )
				)
				( pin "J4G3.77"
					( objectStatus "vtt(1)" )
				)
			)
			( gate "C4G19"
				( objectStatus "@baseboard_fab2_lib.baseboard_fab2(sch_1):page47_i188" )
				( pin "C4G19.1"
					( objectStatus "a" )
				)
				( pin "C4G19.2"
					( objectStatus "b" )
				)
			)
			( gate "J6U2"
				( objectStatus "@baseboard_fab2_lib.baseboard_fab2(sch_1):page48_i43" )
				( pin "J6U2.283"
					( objectStatus "vss(0)" )
				)
				( pin "J6U2.281"
					( objectStatus "vss(1)" )
				)
				( pin "J6U2.279"
					( objectStatus "vss(2)" )
				)
				( pin "J6U2.276"
					( objectStatus "vss(3)" )
				)
				( pin "J6U2.274"
					( objectStatus "vss(4)" )
				)
				( pin "J6U2.272"
					( objectStatus "vss(5)" )
				)
				( pin "J6U2.270"
					( objectStatus "vss(6)" )
				)
				( pin "J6U2.268"
					( objectStatus "vss(7)" )
				)
				( pin "J6U2.265"
					( objectStatus "vss(8)" )
				)
				( pin "J6U2.263"
					( objectStatus "vss(9)" )
				)
				( pin "J6U2.261"
					( objectStatus "vss(10)" )
				)
				( pin "J6U2.259"
					( objectStatus "vss(11)" )
				)
				( pin "J6U2.257"
					( objectStatus "vss(12)" )
				)
				( pin "J6U2.254"
					( objectStatus "vss(13)" )
				)
				( pin "J6U2.252"
					( objectStatus "vss(14)" )
				)
				( pin "J6U2.250"
					( objectStatus "vss(15)" )
				)
				( pin "J6U2.248"
					( objectStatus "vss(16)" )
				)
				( pin "J6U2.246"
					( objectStatus "vss(17)" )
				)
				( pin "J6U2.243"
					( objectStatus "vss(18)" )
				)
				( pin "J6U2.241"
					( objectStatus "vss(19)" )
				)
				( pin "J6U2.239"
					( objectStatus "vss(20)" )
				)
				( pin "J6U2.202"
					( objectStatus "vss(21)" )
				)
				( pin "J6U2.200"
					( objectStatus "vss(22)" )
				)
				( pin "J6U2.198"
					( objectStatus "vss(23)" )
				)
				( pin "J6U2.195"
					( objectStatus "vss(24)" )
				)
				( pin "J6U2.193"
					( objectStatus "vss(25)" )
				)
				( pin "J6U2.191"
					( objectStatus "vss(26)" )
				)
				( pin "J6U2.189"
					( objectStatus "vss(27)" )
				)
				( pin "J6U2.187"
					( objectStatus "vss(28)" )
				)
				( pin "J6U2.184"
					( objectStatus "vss(29)" )
				)
				( pin "J6U2.182"
					( objectStatus "vss(30)" )
				)
				( pin "J6U2.180"
					( objectStatus "vss(31)" )
				)
				( pin "J6U2.178"
					( objectStatus "vss(32)" )
				)
				( pin "J6U2.176"
					( objectStatus "vss(33)" )
				)
				( pin "J6U2.173"
					( objectStatus "vss(34)" )
				)
				( pin "J6U2.171"
					( objectStatus "vss(35)" )
				)
				( pin "J6U2.169"
					( objectStatus "vss(36)" )
				)
				( pin "J6U2.167"
					( objectStatus "vss(37)" )
				)
				( pin "J6U2.165"
					( objectStatus "vss(38)" )
				)
				( pin "J6U2.162"
					( objectStatus "vss(39)" )
				)
				( pin "J6U2.160"
					( objectStatus "vss(40)" )
				)
				( pin "J6U2.158"
					( objectStatus "vss(41)" )
				)
				( pin "J6U2.156"
					( objectStatus "vss(42)" )
				)
				( pin "J6U2.154"
					( objectStatus "vss(43)" )
				)
				( pin "J6U2.151"
					( objectStatus "vss(44)" )
				)
				( pin "J6U2.149"
					( objectStatus "vss(45)" )
				)
				( pin "J6U2.147"
					( objectStatus "vss(46)" )
				)
				( pin "J6U2.138"
					( objectStatus "vss(47)" )
				)
				( pin "J6U2.136"
					( objectStatus "vss(48)" )
				)
				( pin "J6U2.134"
					( objectStatus "vss(49)" )
				)
				( pin "J6U2.131"
					( objectStatus "vss(50)" )
				)
				( pin "J6U2.129"
					( objectStatus "vss(51)" )
				)
				( pin "J6U2.127"
					( objectStatus "vss(52)" )
				)
				( pin "J6U2.125"
					( objectStatus "vss(53)" )
				)
				( pin "J6U2.123"
					( objectStatus "vss(54)" )
				)
				( pin "J6U2.120"
					( objectStatus "vss(55)" )
				)
				( pin "J6U2.118"
					( objectStatus "vss(56)" )
				)
				( pin "J6U2.116"
					( objectStatus "vss(57)" )
				)
				( pin "J6U2.114"
					( objectStatus "vss(58)" )
				)
				( pin "J6U2.112"
					( objectStatus "vss(59)" )
				)
				( pin "J6U2.109"
					( objectStatus "vss(60)" )
				)
				( pin "J6U2.107"
					( objectStatus "vss(61)" )
				)
				( pin "J6U2.105"
					( objectStatus "vss(62)" )
				)
				( pin "J6U2.103"
					( objectStatus "vss(63)" )
				)
				( pin "J6U2.101"
					( objectStatus "vss(64)" )
				)
				( pin "J6U2.98"
					( objectStatus "vss(65)" )
				)
				( pin "J6U2.96"
					( objectStatus "vss(66)" )
				)
				( pin "J6U2.94"
					( objectStatus "vss(67)" )
				)
				( pin "J6U2.57"
					( objectStatus "vss(68)" )
				)
				( pin "J6U2.55"
					( objectStatus "vss(69)" )
				)
				( pin "J6U2.53"
					( objectStatus "vss(70)" )
				)
				( pin "J6U2.50"
					( objectStatus "vss(71)" )
				)
				( pin "J6U2.48"
					( objectStatus "vss(72)" )
				)
				( pin "J6U2.46"
					( objectStatus "vss(73)" )
				)
				( pin "J6U2.44"
					( objectStatus "vss(74)" )
				)
				( pin "J6U2.42"
					( objectStatus "vss(75)" )
				)
				( pin "J6U2.39"
					( objectStatus "vss(76)" )
				)
				( pin "J6U2.37"
					( objectStatus "vss(77)" )
				)
				( pin "J6U2.35"
					( objectStatus "vss(78)" )
				)
				( pin "J6U2.33"
					( objectStatus "vss(79)" )
				)
				( pin "J6U2.31"
					( objectStatus "vss(80)" )
				)
				( pin "J6U2.28"
					( objectStatus "vss(81)" )
				)
				( pin "J6U2.26"
					( objectStatus "vss(82)" )
				)
				( pin "J6U2.24"
					( objectStatus "vss(83)" )
				)
				( pin "J6U2.22"
					( objectStatus "vss(84)" )
				)
				( pin "J6U2.20"
					( objectStatus "vss(85)" )
				)
				( pin "J6U2.17"
					( objectStatus "vss(86)" )
				)
				( pin "J6U2.15"
					( objectStatus "vss(87)" )
				)
				( pin "J6U2.13"
					( objectStatus "vss(88)" )
				)
				( pin "J6U2.11"
					( objectStatus "vss(89)" )
				)
				( pin "J6U2.9"
					( objectStatus "vss(90)" )
				)
				( pin "J6U2.6"
					( objectStatus "vss(91)" )
				)
				( pin "J6U2.4"
					( objectStatus "vss(92)" )
				)
				( pin "J6U2.2"
					( objectStatus "vss(93)" )
				)
			)
			( gate "J6U2"
				( objectStatus "@baseboard_fab2_lib.baseboard_fab2(sch_1):page48_i61" )
				( pin "J6U2.152"
					( objectStatus "dqs0n" )
				)
				( pin "J6U2.153"
					( objectStatus "dqs0p" )
				)
				( pin "J6U2.163"
					( objectStatus "dqs1n" )
				)
				( pin "J6U2.164"
					( objectStatus "dqs1p" )
				)
				( pin "J6U2.174"
					( objectStatus "dqs2n" )
				)
				( pin "J6U2.175"
					( objectStatus "dqs2p" )
				)
				( pin "J6U2.185"
					( objectStatus "dqs3n" )
				)
				( pin "J6U2.186"
					( objectStatus "dqs3p" )
				)
				( pin "J6U2.244"
					( objectStatus "dqs4n" )
				)
				( pin "J6U2.245"
					( objectStatus "dqs4p" )
				)
				( pin "J6U2.255"
					( objectStatus "dqs5n" )
				)
				( pin "J6U2.256"
					( objectStatus "dqs5p" )
				)
				( pin "J6U2.266"
					( objectStatus "dqs6n" )
				)
				( pin "J6U2.267"
					( objectStatus "dqs6p" )
				)
				( pin "J6U2.277"
					( objectStatus "dqs7n" )
				)
				( pin "J6U2.278"
					( objectStatus "dqs7p" )
				)
				( pin "J6U2.196"
					( objectStatus "dqs8n" )
				)
				( pin "J6U2.197"
					( objectStatus "dqs8p" )
				)
				( pin "J6U2.8"
					( objectStatus "dqs9n" )
				)
				( pin "J6U2.7"
					( objectStatus "dqs9p" )
				)
				( pin "J6U2.19"
					( objectStatus "dqs10n" )
				)
				( pin "J6U2.18"
					( objectStatus "dqs10p" )
				)
				( pin "J6U2.30"
					( objectStatus "dqs11n" )
				)
				( pin "J6U2.29"
					( objectStatus "dqs11p" )
				)
				( pin "J6U2.41"
					( objectStatus "dqs12n" )
				)
				( pin "J6U2.40"
					( objectStatus "dqs12p" )
				)
				( pin "J6U2.100"
					( objectStatus "dqs13n" )
				)
				( pin "J6U2.99"
					( objectStatus "dqs13p" )
				)
				( pin "J6U2.111"
					( objectStatus "dqs14n" )
				)
				( pin "J6U2.110"
					( objectStatus "dqs14p" )
				)
				( pin "J6U2.122"
					( objectStatus "dqs15n" )
				)
				( pin "J6U2.121"
					( objectStatus "dqs15p" )
				)
				( pin "J6U2.133"
					( objectStatus "dqs16n" )
				)
				( pin "J6U2.132"
					( objectStatus "dqs16p" )
				)
				( pin "J6U2.52"
					( objectStatus "dqs17n" )
				)
				( pin "J6U2.51"
					( objectStatus "dqs17p" )
				)
			)
			( gate "J6U2"
				( objectStatus "@baseboard_fab2_lib.baseboard_fab2(sch_1):page48_i111" )
				( pin "J6U2.79"
					( objectStatus "a0" )
				)
				( pin "J6U2.72"
					( objectStatus "a1" )
				)
				( pin "J6U2.216"
					( objectStatus "a2" )
				)
				( pin "J6U2.71"
					( objectStatus "a3" )
				)
				( pin "J6U2.214"
					( objectStatus "a4" )
				)
				( pin "J6U2.213"
					( objectStatus "a5" )
				)
				( pin "J6U2.69"
					( objectStatus "a6" )
				)
				( pin "J6U2.211"
					( objectStatus "a7" )
				)
				( pin "J6U2.68"
					( objectStatus "a8" )
				)
				( pin "J6U2.66"
					( objectStatus "a9" )
				)
				( pin "J6U2.225"
					( objectStatus "a10" )
				)
				( pin "J6U2.210"
					( objectStatus "a11" )
				)
				( pin "J6U2.65"
					( objectStatus "a12" )
				)
				( pin "J6U2.232"
					( objectStatus "a13" )
				)
				( pin "J6U2.228"
					( objectStatus "a14_we_n" )
				)
				( pin "J6U2.86"
					( objectStatus "a15_cas_n" )
				)
				( pin "J6U2.82"
					( objectStatus "a16_ras_n" )
				)
				( pin "J6U2.234"
					( objectStatus "a17" )
				)
				( pin "J6U2.62"
					( objectStatus "act_n" )
				)
				( pin "J6U2.208"
					( objectStatus "alert_n" )
				)
				( pin "J6U2.81"
					( objectStatus "ba(0)" )
				)
				( pin "J6U2.224"
					( objectStatus "ba(1)" )
				)
				( pin "J6U2.63"
					( objectStatus "bg(0)" )
				)
				( pin "J6U2.207"
					( objectStatus "bg(1)" )
				)
				( pin "J6U2.235"
					( objectStatus "c(2)" )
				)
				( pin "J6U2.49"
					( objectStatus "cb(0)" )
				)
				( pin "J6U2.194"
					( objectStatus "cb(1)" )
				)
				( pin "J6U2.56"
					( objectStatus "cb(2)" )
				)
				( pin "J6U2.201"
					( objectStatus "cb(3)" )
				)
				( pin "J6U2.47"
					( objectStatus "cb(4)" )
				)
				( pin "J6U2.192"
					( objectStatus "cb(5)" )
				)
				( pin "J6U2.54"
					( objectStatus "cb(6)" )
				)
				( pin "J6U2.199"
					( objectStatus "cb(7)" )
				)
				( pin "J6U2.75"
					( objectStatus "ck0n" )
				)
				( pin "J6U2.74"
					( objectStatus "ck0p" )
				)
				( pin "J6U2.219"
					( objectStatus "ck1n" )
				)
				( pin "J6U2.218"
					( objectStatus "ck1p" )
				)
				( pin "J6U2.60"
					( objectStatus "cke(0)" )
				)
				( pin "J6U2.203"
					( objectStatus "cke(1)" )
				)
				( pin "J6U2.5"
					( objectStatus "dq(0)" )
				)
				( pin "J6U2.150"
					( objectStatus "dq(1)" )
				)
				( pin "J6U2.12"
					( objectStatus "dq(2)" )
				)
				( pin "J6U2.157"
					( objectStatus "dq(3)" )
				)
				( pin "J6U2.3"
					( objectStatus "dq(4)" )
				)
				( pin "J6U2.148"
					( objectStatus "dq(5)" )
				)
				( pin "J6U2.10"
					( objectStatus "dq(6)" )
				)
				( pin "J6U2.155"
					( objectStatus "dq(7)" )
				)
				( pin "J6U2.16"
					( objectStatus "dq(8)" )
				)
				( pin "J6U2.161"
					( objectStatus "dq(9)" )
				)
				( pin "J6U2.23"
					( objectStatus "dq(10)" )
				)
				( pin "J6U2.168"
					( objectStatus "dq(11)" )
				)
				( pin "J6U2.14"
					( objectStatus "dq(12)" )
				)
				( pin "J6U2.159"
					( objectStatus "dq(13)" )
				)
				( pin "J6U2.21"
					( objectStatus "dq(14)" )
				)
				( pin "J6U2.166"
					( objectStatus "dq(15)" )
				)
				( pin "J6U2.27"
					( objectStatus "dq(16)" )
				)
				( pin "J6U2.172"
					( objectStatus "dq(17)" )
				)
				( pin "J6U2.34"
					( objectStatus "dq(18)" )
				)
				( pin "J6U2.179"
					( objectStatus "dq(19)" )
				)
				( pin "J6U2.25"
					( objectStatus "dq(20)" )
				)
				( pin "J6U2.170"
					( objectStatus "dq(21)" )
				)
				( pin "J6U2.32"
					( objectStatus "dq(22)" )
				)
				( pin "J6U2.177"
					( objectStatus "dq(23)" )
				)
				( pin "J6U2.38"
					( objectStatus "dq(24)" )
				)
				( pin "J6U2.183"
					( objectStatus "dq(25)" )
				)
				( pin "J6U2.45"
					( objectStatus "dq(26)" )
				)
				( pin "J6U2.190"
					( objectStatus "dq(27)" )
				)
				( pin "J6U2.36"
					( objectStatus "dq(28)" )
				)
				( pin "J6U2.181"
					( objectStatus "dq(29)" )
				)
				( pin "J6U2.43"
					( objectStatus "dq(30)" )
				)
				( pin "J6U2.188"
					( objectStatus "dq(31)" )
				)
				( pin "J6U2.97"
					( objectStatus "dq(32)" )
				)
				( pin "J6U2.242"
					( objectStatus "dq(33)" )
				)
				( pin "J6U2.104"
					( objectStatus "dq(34)" )
				)
				( pin "J6U2.249"
					( objectStatus "dq(35)" )
				)
				( pin "J6U2.95"
					( objectStatus "dq(36)" )
				)
				( pin "J6U2.240"
					( objectStatus "dq(37)" )
				)
				( pin "J6U2.102"
					( objectStatus "dq(38)" )
				)
				( pin "J6U2.247"
					( objectStatus "dq(39)" )
				)
				( pin "J6U2.108"
					( objectStatus "dq(40)" )
				)
				( pin "J6U2.253"
					( objectStatus "dq(41)" )
				)
				( pin "J6U2.115"
					( objectStatus "dq(42)" )
				)
				( pin "J6U2.260"
					( objectStatus "dq(43)" )
				)
				( pin "J6U2.106"
					( objectStatus "dq(44)" )
				)
				( pin "J6U2.251"
					( objectStatus "dq(45)" )
				)
				( pin "J6U2.113"
					( objectStatus "dq(46)" )
				)
				( pin "J6U2.258"
					( objectStatus "dq(47)" )
				)
				( pin "J6U2.119"
					( objectStatus "dq(48)" )
				)
				( pin "J6U2.264"
					( objectStatus "dq(49)" )
				)
				( pin "J6U2.126"
					( objectStatus "dq(50)" )
				)
				( pin "J6U2.271"
					( objectStatus "dq(51)" )
				)
				( pin "J6U2.117"
					( objectStatus "dq(52)" )
				)
				( pin "J6U2.262"
					( objectStatus "dq(53)" )
				)
				( pin "J6U2.124"
					( objectStatus "dq(54)" )
				)
				( pin "J6U2.269"
					( objectStatus "dq(55)" )
				)
				( pin "J6U2.130"
					( objectStatus "dq(56)" )
				)
				( pin "J6U2.275"
					( objectStatus "dq(57)" )
				)
				( pin "J6U2.137"
					( objectStatus "dq(58)" )
				)
				( pin "J6U2.282"
					( objectStatus "dq(59)" )
				)
				( pin "J6U2.128"
					( objectStatus "dq(60)" )
				)
				( pin "J6U2.273"
					( objectStatus "dq(61)" )
				)
				( pin "J6U2.135"
					( objectStatus "dq(62)" )
				)
				( pin "J6U2.280"
					( objectStatus "dq(63)" )
				)
				( pin "J6U2.78"
					( objectStatus "event_n" )
				)
				( pin "J6U2.87"
					( objectStatus "odt(0)" )
				)
				( pin "J6U2.91"
					( objectStatus "odt(1)" )
				)
				( pin "J6U2.222"
					( objectStatus "par" )
				)
				( pin "J6U2.58"
					( objectStatus "reset_n" )
				)
				( pin "J6U2.205"
					( objectStatus "rfu(0)" )
				)
				( pin "J6U2.227"
					( objectStatus "rfu(1)" )
				)
				( pin "J6U2.144"
					( objectStatus "rfu(2)" )
				)
				( pin "J6U2.84"
					( objectStatus "s0_n" )
				)
				( pin "J6U2.89"
					( objectStatus "s1_n" )
				)
				( pin "J6U2.93"
					( objectStatus "s2_n_c(0)" )
				)
				( pin "J6U2.237"
					( objectStatus "s3_n_c(1)" )
				)
				( pin "J6U2.139"
					( objectStatus "sa(0)" )
				)
				( pin "J6U2.140"
					( objectStatus "sa(1)" )
				)
				( pin "J6U2.238"
					( objectStatus "sa(2)" )
				)
				( pin "J6U2.230"
					( objectStatus "save_n_nc" )
				)
				( pin "J6U2.141"
					( objectStatus "scl" )
				)
				( pin "J6U2.285"
					( objectStatus "sda" )
				)
				( pin "J6U2.284"
					( objectStatus "vddspd" )
				)
				( pin "J6U2.146"
					( objectStatus "vrefca" )
				)
			)
			( gate "J6U2"
				( objectStatus "@baseboard_fab2_lib.baseboard_fab2(sch_1):page48_i171" )
				( pin "J6U2.145"
					( objectStatus "\12v\(0)" )
				)
				( pin "J6U2.1"
					( objectStatus "\12v\(1)" )
				)
				( pin "J6U2.236"
					( objectStatus "vdd(0)" )
				)
				( pin "J6U2.233"
					( objectStatus "vdd(1)" )
				)
				( pin "J6U2.231"
					( objectStatus "vdd(2)" )
				)
				( pin "J6U2.229"
					( objectStatus "vdd(3)" )
				)
				( pin "J6U2.226"
					( objectStatus "vdd(4)" )
				)
				( pin "J6U2.223"
					( objectStatus "vdd(5)" )
				)
				( pin "J6U2.220"
					( objectStatus "vdd(6)" )
				)
				( pin "J6U2.217"
					( objectStatus "vdd(7)" )
				)
				( pin "J6U2.215"
					( objectStatus "vdd(8)" )
				)
				( pin "J6U2.212"
					( objectStatus "vdd(9)" )
				)
				( pin "J6U2.209"
					( objectStatus "vdd(10)" )
				)
				( pin "J6U2.206"
					( objectStatus "vdd(11)" )
				)
				( pin "J6U2.204"
					( objectStatus "vdd(12)" )
				)
				( pin "J6U2.92"
					( objectStatus "vdd(13)" )
				)
				( pin "J6U2.90"
					( objectStatus "vdd(14)" )
				)
				( pin "J6U2.88"
					( objectStatus "vdd(15)" )
				)
				( pin "J6U2.85"
					( objectStatus "vdd(16)" )
				)
				( pin "J6U2.83"
					( objectStatus "vdd(17)" )
				)
				( pin "J6U2.80"
					( objectStatus "vdd(18)" )
				)
				( pin "J6U2.76"
					( objectStatus "vdd(19)" )
				)
				( pin "J6U2.73"
					( objectStatus "vdd(20)" )
				)
				( pin "J6U2.70"
					( objectStatus "vdd(21)" )
				)
				( pin "J6U2.67"
					( objectStatus "vdd(22)" )
				)
				( pin "J6U2.64"
					( objectStatus "vdd(23)" )
				)
				( pin "J6U2.61"
					( objectStatus "vdd(24)" )
				)
				( pin "J6U2.59"
					( objectStatus "vdd(25)" )
				)
				( pin "J6U2.287"
					( objectStatus "vpp(0)" )
				)
				( pin "J6U2.286"
					( objectStatus "vpp(1)" )
				)
				( pin "J6U2.288"
					( objectStatus "vpp(2)" )
				)
				( pin "J6U2.143"
					( objectStatus "vpp(3)" )
				)
				( pin "J6U2.142"
					( objectStatus "vpp(4)" )
				)
				( pin "J6U2.221"
					( objectStatus "vtt(0)" )
				)
				( pin "J6U2.77"
					( objectStatus "vtt(1)" )
				)
			)
			( gate "C6U17"
				( objectStatus "@baseboard_fab2_lib.baseboard_fab2(sch_1):page48_i176" )
				( pin "C6U17.1"
					( objectStatus "a" )
				)
				( pin "C6U17.2"
					( objectStatus "b" )
				)
			)
			( gate "J4B1"
				( objectStatus "@baseboard_fab2_lib.baseboard_fab2(sch_1):page49_i43" )
				( pin "J4B1.283"
					( objectStatus "vss(0)" )
				)
				( pin "J4B1.281"
					( objectStatus "vss(1)" )
				)
				( pin "J4B1.279"
					( objectStatus "vss(2)" )
				)
				( pin "J4B1.276"
					( objectStatus "vss(3)" )
				)
				( pin "J4B1.274"
					( objectStatus "vss(4)" )
				)
				( pin "J4B1.272"
					( objectStatus "vss(5)" )
				)
				( pin "J4B1.270"
					( objectStatus "vss(6)" )
				)
				( pin "J4B1.268"
					( objectStatus "vss(7)" )
				)
				( pin "J4B1.265"
					( objectStatus "vss(8)" )
				)
				( pin "J4B1.263"
					( objectStatus "vss(9)" )
				)
				( pin "J4B1.261"
					( objectStatus "vss(10)" )
				)
				( pin "J4B1.259"
					( objectStatus "vss(11)" )
				)
				( pin "J4B1.257"
					( objectStatus "vss(12)" )
				)
				( pin "J4B1.254"
					( objectStatus "vss(13)" )
				)
				( pin "J4B1.252"
					( objectStatus "vss(14)" )
				)
				( pin "J4B1.250"
					( objectStatus "vss(15)" )
				)
				( pin "J4B1.248"
					( objectStatus "vss(16)" )
				)
				( pin "J4B1.246"
					( objectStatus "vss(17)" )
				)
				( pin "J4B1.243"
					( objectStatus "vss(18)" )
				)
				( pin "J4B1.241"
					( objectStatus "vss(19)" )
				)
				( pin "J4B1.239"
					( objectStatus "vss(20)" )
				)
				( pin "J4B1.202"
					( objectStatus "vss(21)" )
				)
				( pin "J4B1.200"
					( objectStatus "vss(22)" )
				)
				( pin "J4B1.198"
					( objectStatus "vss(23)" )
				)
				( pin "J4B1.195"
					( objectStatus "vss(24)" )
				)
				( pin "J4B1.193"
					( objectStatus "vss(25)" )
				)
				( pin "J4B1.191"
					( objectStatus "vss(26)" )
				)
				( pin "J4B1.189"
					( objectStatus "vss(27)" )
				)
				( pin "J4B1.187"
					( objectStatus "vss(28)" )
				)
				( pin "J4B1.184"
					( objectStatus "vss(29)" )
				)
				( pin "J4B1.182"
					( objectStatus "vss(30)" )
				)
				( pin "J4B1.180"
					( objectStatus "vss(31)" )
				)
				( pin "J4B1.178"
					( objectStatus "vss(32)" )
				)
				( pin "J4B1.176"
					( objectStatus "vss(33)" )
				)
				( pin "J4B1.173"
					( objectStatus "vss(34)" )
				)
				( pin "J4B1.171"
					( objectStatus "vss(35)" )
				)
				( pin "J4B1.169"
					( objectStatus "vss(36)" )
				)
				( pin "J4B1.167"
					( objectStatus "vss(37)" )
				)
				( pin "J4B1.165"
					( objectStatus "vss(38)" )
				)
				( pin "J4B1.162"
					( objectStatus "vss(39)" )
				)
				( pin "J4B1.160"
					( objectStatus "vss(40)" )
				)
				( pin "J4B1.158"
					( objectStatus "vss(41)" )
				)
				( pin "J4B1.156"
					( objectStatus "vss(42)" )
				)
				( pin "J4B1.154"
					( objectStatus "vss(43)" )
				)
				( pin "J4B1.151"
					( objectStatus "vss(44)" )
				)
				( pin "J4B1.149"
					( objectStatus "vss(45)" )
				)
				( pin "J4B1.147"
					( objectStatus "vss(46)" )
				)
				( pin "J4B1.138"
					( objectStatus "vss(47)" )
				)
				( pin "J4B1.136"
					( objectStatus "vss(48)" )
				)
				( pin "J4B1.134"
					( objectStatus "vss(49)" )
				)
				( pin "J4B1.131"
					( objectStatus "vss(50)" )
				)
				( pin "J4B1.129"
					( objectStatus "vss(51)" )
				)
				( pin "J4B1.127"
					( objectStatus "vss(52)" )
				)
				( pin "J4B1.125"
					( objectStatus "vss(53)" )
				)
				( pin "J4B1.123"
					( objectStatus "vss(54)" )
				)
				( pin "J4B1.120"
					( objectStatus "vss(55)" )
				)
				( pin "J4B1.118"
					( objectStatus "vss(56)" )
				)
				( pin "J4B1.116"
					( objectStatus "vss(57)" )
				)
				( pin "J4B1.114"
					( objectStatus "vss(58)" )
				)
				( pin "J4B1.112"
					( objectStatus "vss(59)" )
				)
				( pin "J4B1.109"
					( objectStatus "vss(60)" )
				)
				( pin "J4B1.107"
					( objectStatus "vss(61)" )
				)
				( pin "J4B1.105"
					( objectStatus "vss(62)" )
				)
				( pin "J4B1.103"
					( objectStatus "vss(63)" )
				)
				( pin "J4B1.101"
					( objectStatus "vss(64)" )
				)
				( pin "J4B1.98"
					( objectStatus "vss(65)" )
				)
				( pin "J4B1.96"
					( objectStatus "vss(66)" )
				)
				( pin "J4B1.94"
					( objectStatus "vss(67)" )
				)
				( pin "J4B1.57"
					( objectStatus "vss(68)" )
				)
				( pin "J4B1.55"
					( objectStatus "vss(69)" )
				)
				( pin "J4B1.53"
					( objectStatus "vss(70)" )
				)
				( pin "J4B1.50"
					( objectStatus "vss(71)" )
				)
				( pin "J4B1.48"
					( objectStatus "vss(72)" )
				)
				( pin "J4B1.46"
					( objectStatus "vss(73)" )
				)
				( pin "J4B1.44"
					( objectStatus "vss(74)" )
				)
				( pin "J4B1.42"
					( objectStatus "vss(75)" )
				)
				( pin "J4B1.39"
					( objectStatus "vss(76)" )
				)
				( pin "J4B1.37"
					( objectStatus "vss(77)" )
				)
				( pin "J4B1.35"
					( objectStatus "vss(78)" )
				)
				( pin "J4B1.33"
					( objectStatus "vss(79)" )
				)
				( pin "J4B1.31"
					( objectStatus "vss(80)" )
				)
				( pin "J4B1.28"
					( objectStatus "vss(81)" )
				)
				( pin "J4B1.26"
					( objectStatus "vss(82)" )
				)
				( pin "J4B1.24"
					( objectStatus "vss(83)" )
				)
				( pin "J4B1.22"
					( objectStatus "vss(84)" )
				)
				( pin "J4B1.20"
					( objectStatus "vss(85)" )
				)
				( pin "J4B1.17"
					( objectStatus "vss(86)" )
				)
				( pin "J4B1.15"
					( objectStatus "vss(87)" )
				)
				( pin "J4B1.13"
					( objectStatus "vss(88)" )
				)
				( pin "J4B1.11"
					( objectStatus "vss(89)" )
				)
				( pin "J4B1.9"
					( objectStatus "vss(90)" )
				)
				( pin "J4B1.6"
					( objectStatus "vss(91)" )
				)
				( pin "J4B1.4"
					( objectStatus "vss(92)" )
				)
				( pin "J4B1.2"
					( objectStatus "vss(93)" )
				)
			)
			( gate "J4B1"
				( objectStatus "@baseboard_fab2_lib.baseboard_fab2(sch_1):page49_i66" )
				( pin "J4B1.152"
					( objectStatus "dqs0n" )
				)
				( pin "J4B1.153"
					( objectStatus "dqs0p" )
				)
				( pin "J4B1.163"
					( objectStatus "dqs1n" )
				)
				( pin "J4B1.164"
					( objectStatus "dqs1p" )
				)
				( pin "J4B1.174"
					( objectStatus "dqs2n" )
				)
				( pin "J4B1.175"
					( objectStatus "dqs2p" )
				)
				( pin "J4B1.185"
					( objectStatus "dqs3n" )
				)
				( pin "J4B1.186"
					( objectStatus "dqs3p" )
				)
				( pin "J4B1.244"
					( objectStatus "dqs4n" )
				)
				( pin "J4B1.245"
					( objectStatus "dqs4p" )
				)
				( pin "J4B1.255"
					( objectStatus "dqs5n" )
				)
				( pin "J4B1.256"
					( objectStatus "dqs5p" )
				)
				( pin "J4B1.266"
					( objectStatus "dqs6n" )
				)
				( pin "J4B1.267"
					( objectStatus "dqs6p" )
				)
				( pin "J4B1.277"
					( objectStatus "dqs7n" )
				)
				( pin "J4B1.278"
					( objectStatus "dqs7p" )
				)
				( pin "J4B1.196"
					( objectStatus "dqs8n" )
				)
				( pin "J4B1.197"
					( objectStatus "dqs8p" )
				)
				( pin "J4B1.8"
					( objectStatus "dqs9n" )
				)
				( pin "J4B1.7"
					( objectStatus "dqs9p" )
				)
				( pin "J4B1.19"
					( objectStatus "dqs10n" )
				)
				( pin "J4B1.18"
					( objectStatus "dqs10p" )
				)
				( pin "J4B1.30"
					( objectStatus "dqs11n" )
				)
				( pin "J4B1.29"
					( objectStatus "dqs11p" )
				)
				( pin "J4B1.41"
					( objectStatus "dqs12n" )
				)
				( pin "J4B1.40"
					( objectStatus "dqs12p" )
				)
				( pin "J4B1.100"
					( objectStatus "dqs13n" )
				)
				( pin "J4B1.99"
					( objectStatus "dqs13p" )
				)
				( pin "J4B1.111"
					( objectStatus "dqs14n" )
				)
				( pin "J4B1.110"
					( objectStatus "dqs14p" )
				)
				( pin "J4B1.122"
					( objectStatus "dqs15n" )
				)
				( pin "J4B1.121"
					( objectStatus "dqs15p" )
				)
				( pin "J4B1.133"
					( objectStatus "dqs16n" )
				)
				( pin "J4B1.132"
					( objectStatus "dqs16p" )
				)
				( pin "J4B1.52"
					( objectStatus "dqs17n" )
				)
				( pin "J4B1.51"
					( objectStatus "dqs17p" )
				)
			)
			( gate "J4B1"
				( objectStatus "@baseboard_fab2_lib.baseboard_fab2(sch_1):page49_i111" )
				( pin "J4B1.79"
					( objectStatus "a0" )
				)
				( pin "J4B1.72"
					( objectStatus "a1" )
				)
				( pin "J4B1.216"
					( objectStatus "a2" )
				)
				( pin "J4B1.71"
					( objectStatus "a3" )
				)
				( pin "J4B1.214"
					( objectStatus "a4" )
				)
				( pin "J4B1.213"
					( objectStatus "a5" )
				)
				( pin "J4B1.69"
					( objectStatus "a6" )
				)
				( pin "J4B1.211"
					( objectStatus "a7" )
				)
				( pin "J4B1.68"
					( objectStatus "a8" )
				)
				( pin "J4B1.66"
					( objectStatus "a9" )
				)
				( pin "J4B1.225"
					( objectStatus "a10" )
				)
				( pin "J4B1.210"
					( objectStatus "a11" )
				)
				( pin "J4B1.65"
					( objectStatus "a12" )
				)
				( pin "J4B1.232"
					( objectStatus "a13" )
				)
				( pin "J4B1.228"
					( objectStatus "a14_we_n" )
				)
				( pin "J4B1.86"
					( objectStatus "a15_cas_n" )
				)
				( pin "J4B1.82"
					( objectStatus "a16_ras_n" )
				)
				( pin "J4B1.234"
					( objectStatus "a17" )
				)
				( pin "J4B1.62"
					( objectStatus "act_n" )
				)
				( pin "J4B1.208"
					( objectStatus "alert_n" )
				)
				( pin "J4B1.81"
					( objectStatus "ba(0)" )
				)
				( pin "J4B1.224"
					( objectStatus "ba(1)" )
				)
				( pin "J4B1.63"
					( objectStatus "bg(0)" )
				)
				( pin "J4B1.207"
					( objectStatus "bg(1)" )
				)
				( pin "J4B1.235"
					( objectStatus "c(2)" )
				)
				( pin "J4B1.49"
					( objectStatus "cb(0)" )
				)
				( pin "J4B1.194"
					( objectStatus "cb(1)" )
				)
				( pin "J4B1.56"
					( objectStatus "cb(2)" )
				)
				( pin "J4B1.201"
					( objectStatus "cb(3)" )
				)
				( pin "J4B1.47"
					( objectStatus "cb(4)" )
				)
				( pin "J4B1.192"
					( objectStatus "cb(5)" )
				)
				( pin "J4B1.54"
					( objectStatus "cb(6)" )
				)
				( pin "J4B1.199"
					( objectStatus "cb(7)" )
				)
				( pin "J4B1.75"
					( objectStatus "ck0n" )
				)
				( pin "J4B1.74"
					( objectStatus "ck0p" )
				)
				( pin "J4B1.219"
					( objectStatus "ck1n" )
				)
				( pin "J4B1.218"
					( objectStatus "ck1p" )
				)
				( pin "J4B1.60"
					( objectStatus "cke(0)" )
				)
				( pin "J4B1.203"
					( objectStatus "cke(1)" )
				)
				( pin "J4B1.5"
					( objectStatus "dq(0)" )
				)
				( pin "J4B1.150"
					( objectStatus "dq(1)" )
				)
				( pin "J4B1.12"
					( objectStatus "dq(2)" )
				)
				( pin "J4B1.157"
					( objectStatus "dq(3)" )
				)
				( pin "J4B1.3"
					( objectStatus "dq(4)" )
				)
				( pin "J4B1.148"
					( objectStatus "dq(5)" )
				)
				( pin "J4B1.10"
					( objectStatus "dq(6)" )
				)
				( pin "J4B1.155"
					( objectStatus "dq(7)" )
				)
				( pin "J4B1.16"
					( objectStatus "dq(8)" )
				)
				( pin "J4B1.161"
					( objectStatus "dq(9)" )
				)
				( pin "J4B1.23"
					( objectStatus "dq(10)" )
				)
				( pin "J4B1.168"
					( objectStatus "dq(11)" )
				)
				( pin "J4B1.14"
					( objectStatus "dq(12)" )
				)
				( pin "J4B1.159"
					( objectStatus "dq(13)" )
				)
				( pin "J4B1.21"
					( objectStatus "dq(14)" )
				)
				( pin "J4B1.166"
					( objectStatus "dq(15)" )
				)
				( pin "J4B1.27"
					( objectStatus "dq(16)" )
				)
				( pin "J4B1.172"
					( objectStatus "dq(17)" )
				)
				( pin "J4B1.34"
					( objectStatus "dq(18)" )
				)
				( pin "J4B1.179"
					( objectStatus "dq(19)" )
				)
				( pin "J4B1.25"
					( objectStatus "dq(20)" )
				)
				( pin "J4B1.170"
					( objectStatus "dq(21)" )
				)
				( pin "J4B1.32"
					( objectStatus "dq(22)" )
				)
				( pin "J4B1.177"
					( objectStatus "dq(23)" )
				)
				( pin "J4B1.38"
					( objectStatus "dq(24)" )
				)
				( pin "J4B1.183"
					( objectStatus "dq(25)" )
				)
				( pin "J4B1.45"
					( objectStatus "dq(26)" )
				)
				( pin "J4B1.190"
					( objectStatus "dq(27)" )
				)
				( pin "J4B1.36"
					( objectStatus "dq(28)" )
				)
				( pin "J4B1.181"
					( objectStatus "dq(29)" )
				)
				( pin "J4B1.43"
					( objectStatus "dq(30)" )
				)
				( pin "J4B1.188"
					( objectStatus "dq(31)" )
				)
				( pin "J4B1.97"
					( objectStatus "dq(32)" )
				)
				( pin "J4B1.242"
					( objectStatus "dq(33)" )
				)
				( pin "J4B1.104"
					( objectStatus "dq(34)" )
				)
				( pin "J4B1.249"
					( objectStatus "dq(35)" )
				)
				( pin "J4B1.95"
					( objectStatus "dq(36)" )
				)
				( pin "J4B1.240"
					( objectStatus "dq(37)" )
				)
				( pin "J4B1.102"
					( objectStatus "dq(38)" )
				)
				( pin "J4B1.247"
					( objectStatus "dq(39)" )
				)
				( pin "J4B1.108"
					( objectStatus "dq(40)" )
				)
				( pin "J4B1.253"
					( objectStatus "dq(41)" )
				)
				( pin "J4B1.115"
					( objectStatus "dq(42)" )
				)
				( pin "J4B1.260"
					( objectStatus "dq(43)" )
				)
				( pin "J4B1.106"
					( objectStatus "dq(44)" )
				)
				( pin "J4B1.251"
					( objectStatus "dq(45)" )
				)
				( pin "J4B1.113"
					( objectStatus "dq(46)" )
				)
				( pin "J4B1.258"
					( objectStatus "dq(47)" )
				)
				( pin "J4B1.119"
					( objectStatus "dq(48)" )
				)
				( pin "J4B1.264"
					( objectStatus "dq(49)" )
				)
				( pin "J4B1.126"
					( objectStatus "dq(50)" )
				)
				( pin "J4B1.271"
					( objectStatus "dq(51)" )
				)
				( pin "J4B1.117"
					( objectStatus "dq(52)" )
				)
				( pin "J4B1.262"
					( objectStatus "dq(53)" )
				)
				( pin "J4B1.124"
					( objectStatus "dq(54)" )
				)
				( pin "J4B1.269"
					( objectStatus "dq(55)" )
				)
				( pin "J4B1.130"
					( objectStatus "dq(56)" )
				)
				( pin "J4B1.275"
					( objectStatus "dq(57)" )
				)
				( pin "J4B1.137"
					( objectStatus "dq(58)" )
				)
				( pin "J4B1.282"
					( objectStatus "dq(59)" )
				)
				( pin "J4B1.128"
					( objectStatus "dq(60)" )
				)
				( pin "J4B1.273"
					( objectStatus "dq(61)" )
				)
				( pin "J4B1.135"
					( objectStatus "dq(62)" )
				)
				( pin "J4B1.280"
					( objectStatus "dq(63)" )
				)
				( pin "J4B1.78"
					( objectStatus "event_n" )
				)
				( pin "J4B1.87"
					( objectStatus "odt(0)" )
				)
				( pin "J4B1.91"
					( objectStatus "odt(1)" )
				)
				( pin "J4B1.222"
					( objectStatus "par" )
				)
				( pin "J4B1.58"
					( objectStatus "reset_n" )
				)
				( pin "J4B1.205"
					( objectStatus "rfu(0)" )
				)
				( pin "J4B1.227"
					( objectStatus "rfu(1)" )
				)
				( pin "J4B1.144"
					( objectStatus "rfu(2)" )
				)
				( pin "J4B1.84"
					( objectStatus "s0_n" )
				)
				( pin "J4B1.89"
					( objectStatus "s1_n" )
				)
				( pin "J4B1.93"
					( objectStatus "s2_n_c(0)" )
				)
				( pin "J4B1.237"
					( objectStatus "s3_n_c(1)" )
				)
				( pin "J4B1.139"
					( objectStatus "sa(0)" )
				)
				( pin "J4B1.140"
					( objectStatus "sa(1)" )
				)
				( pin "J4B1.238"
					( objectStatus "sa(2)" )
				)
				( pin "J4B1.230"
					( objectStatus "save_n_nc" )
				)
				( pin "J4B1.141"
					( objectStatus "scl" )
				)
				( pin "J4B1.285"
					( objectStatus "sda" )
				)
				( pin "J4B1.284"
					( objectStatus "vddspd" )
				)
				( pin "J4B1.146"
					( objectStatus "vrefca" )
				)
			)
			( gate "J4B1"
				( objectStatus "@baseboard_fab2_lib.baseboard_fab2(sch_1):page49_i169" )
				( pin "J4B1.145"
					( objectStatus "\12v\(0)" )
				)
				( pin "J4B1.1"
					( objectStatus "\12v\(1)" )
				)
				( pin "J4B1.236"
					( objectStatus "vdd(0)" )
				)
				( pin "J4B1.233"
					( objectStatus "vdd(1)" )
				)
				( pin "J4B1.231"
					( objectStatus "vdd(2)" )
				)
				( pin "J4B1.229"
					( objectStatus "vdd(3)" )
				)
				( pin "J4B1.226"
					( objectStatus "vdd(4)" )
				)
				( pin "J4B1.223"
					( objectStatus "vdd(5)" )
				)
				( pin "J4B1.220"
					( objectStatus "vdd(6)" )
				)
				( pin "J4B1.217"
					( objectStatus "vdd(7)" )
				)
				( pin "J4B1.215"
					( objectStatus "vdd(8)" )
				)
				( pin "J4B1.212"
					( objectStatus "vdd(9)" )
				)
				( pin "J4B1.209"
					( objectStatus "vdd(10)" )
				)
				( pin "J4B1.206"
					( objectStatus "vdd(11)" )
				)
				( pin "J4B1.204"
					( objectStatus "vdd(12)" )
				)
				( pin "J4B1.92"
					( objectStatus "vdd(13)" )
				)
				( pin "J4B1.90"
					( objectStatus "vdd(14)" )
				)
				( pin "J4B1.88"
					( objectStatus "vdd(15)" )
				)
				( pin "J4B1.85"
					( objectStatus "vdd(16)" )
				)
				( pin "J4B1.83"
					( objectStatus "vdd(17)" )
				)
				( pin "J4B1.80"
					( objectStatus "vdd(18)" )
				)
				( pin "J4B1.76"
					( objectStatus "vdd(19)" )
				)
				( pin "J4B1.73"
					( objectStatus "vdd(20)" )
				)
				( pin "J4B1.70"
					( objectStatus "vdd(21)" )
				)
				( pin "J4B1.67"
					( objectStatus "vdd(22)" )
				)
				( pin "J4B1.64"
					( objectStatus "vdd(23)" )
				)
				( pin "J4B1.61"
					( objectStatus "vdd(24)" )
				)
				( pin "J4B1.59"
					( objectStatus "vdd(25)" )
				)
				( pin "J4B1.287"
					( objectStatus "vpp(0)" )
				)
				( pin "J4B1.286"
					( objectStatus "vpp(1)" )
				)
				( pin "J4B1.288"
					( objectStatus "vpp(2)" )
				)
				( pin "J4B1.143"
					( objectStatus "vpp(3)" )
				)
				( pin "J4B1.142"
					( objectStatus "vpp(4)" )
				)
				( pin "J4B1.221"
					( objectStatus "vtt(0)" )
				)
				( pin "J4B1.77"
					( objectStatus "vtt(1)" )
				)
			)
			( gate "C4B12"
				( objectStatus "@baseboard_fab2_lib.baseboard_fab2(sch_1):page49_i179" )
				( pin "C4B12.1"
					( objectStatus "a" )
				)
				( pin "C4B12.2"
					( objectStatus "b" )
				)
			)
			( gate "J6M1"
				( objectStatus "@baseboard_fab2_lib.baseboard_fab2(sch_1):page50_i44" )
				( pin "J6M1.283"
					( objectStatus "vss(0)" )
				)
				( pin "J6M1.281"
					( objectStatus "vss(1)" )
				)
				( pin "J6M1.279"
					( objectStatus "vss(2)" )
				)
				( pin "J6M1.276"
					( objectStatus "vss(3)" )
				)
				( pin "J6M1.274"
					( objectStatus "vss(4)" )
				)
				( pin "J6M1.272"
					( objectStatus "vss(5)" )
				)
				( pin "J6M1.270"
					( objectStatus "vss(6)" )
				)
				( pin "J6M1.268"
					( objectStatus "vss(7)" )
				)
				( pin "J6M1.265"
					( objectStatus "vss(8)" )
				)
				( pin "J6M1.263"
					( objectStatus "vss(9)" )
				)
				( pin "J6M1.261"
					( objectStatus "vss(10)" )
				)
				( pin "J6M1.259"
					( objectStatus "vss(11)" )
				)
				( pin "J6M1.257"
					( objectStatus "vss(12)" )
				)
				( pin "J6M1.254"
					( objectStatus "vss(13)" )
				)
				( pin "J6M1.252"
					( objectStatus "vss(14)" )
				)
				( pin "J6M1.250"
					( objectStatus "vss(15)" )
				)
				( pin "J6M1.248"
					( objectStatus "vss(16)" )
				)
				( pin "J6M1.246"
					( objectStatus "vss(17)" )
				)
				( pin "J6M1.243"
					( objectStatus "vss(18)" )
				)
				( pin "J6M1.241"
					( objectStatus "vss(19)" )
				)
				( pin "J6M1.239"
					( objectStatus "vss(20)" )
				)
				( pin "J6M1.202"
					( objectStatus "vss(21)" )
				)
				( pin "J6M1.200"
					( objectStatus "vss(22)" )
				)
				( pin "J6M1.198"
					( objectStatus "vss(23)" )
				)
				( pin "J6M1.195"
					( objectStatus "vss(24)" )
				)
				( pin "J6M1.193"
					( objectStatus "vss(25)" )
				)
				( pin "J6M1.191"
					( objectStatus "vss(26)" )
				)
				( pin "J6M1.189"
					( objectStatus "vss(27)" )
				)
				( pin "J6M1.187"
					( objectStatus "vss(28)" )
				)
				( pin "J6M1.184"
					( objectStatus "vss(29)" )
				)
				( pin "J6M1.182"
					( objectStatus "vss(30)" )
				)
				( pin "J6M1.180"
					( objectStatus "vss(31)" )
				)
				( pin "J6M1.178"
					( objectStatus "vss(32)" )
				)
				( pin "J6M1.176"
					( objectStatus "vss(33)" )
				)
				( pin "J6M1.173"
					( objectStatus "vss(34)" )
				)
				( pin "J6M1.171"
					( objectStatus "vss(35)" )
				)
				( pin "J6M1.169"
					( objectStatus "vss(36)" )
				)
				( pin "J6M1.167"
					( objectStatus "vss(37)" )
				)
				( pin "J6M1.165"
					( objectStatus "vss(38)" )
				)
				( pin "J6M1.162"
					( objectStatus "vss(39)" )
				)
				( pin "J6M1.160"
					( objectStatus "vss(40)" )
				)
				( pin "J6M1.158"
					( objectStatus "vss(41)" )
				)
				( pin "J6M1.156"
					( objectStatus "vss(42)" )
				)
				( pin "J6M1.154"
					( objectStatus "vss(43)" )
				)
				( pin "J6M1.151"
					( objectStatus "vss(44)" )
				)
				( pin "J6M1.149"
					( objectStatus "vss(45)" )
				)
				( pin "J6M1.147"
					( objectStatus "vss(46)" )
				)
				( pin "J6M1.138"
					( objectStatus "vss(47)" )
				)
				( pin "J6M1.136"
					( objectStatus "vss(48)" )
				)
				( pin "J6M1.134"
					( objectStatus "vss(49)" )
				)
				( pin "J6M1.131"
					( objectStatus "vss(50)" )
				)
				( pin "J6M1.129"
					( objectStatus "vss(51)" )
				)
				( pin "J6M1.127"
					( objectStatus "vss(52)" )
				)
				( pin "J6M1.125"
					( objectStatus "vss(53)" )
				)
				( pin "J6M1.123"
					( objectStatus "vss(54)" )
				)
				( pin "J6M1.120"
					( objectStatus "vss(55)" )
				)
				( pin "J6M1.118"
					( objectStatus "vss(56)" )
				)
				( pin "J6M1.116"
					( objectStatus "vss(57)" )
				)
				( pin "J6M1.114"
					( objectStatus "vss(58)" )
				)
				( pin "J6M1.112"
					( objectStatus "vss(59)" )
				)
				( pin "J6M1.109"
					( objectStatus "vss(60)" )
				)
				( pin "J6M1.107"
					( objectStatus "vss(61)" )
				)
				( pin "J6M1.105"
					( objectStatus "vss(62)" )
				)
				( pin "J6M1.103"
					( objectStatus "vss(63)" )
				)
				( pin "J6M1.101"
					( objectStatus "vss(64)" )
				)
				( pin "J6M1.98"
					( objectStatus "vss(65)" )
				)
				( pin "J6M1.96"
					( objectStatus "vss(66)" )
				)
				( pin "J6M1.94"
					( objectStatus "vss(67)" )
				)
				( pin "J6M1.57"
					( objectStatus "vss(68)" )
				)
				( pin "J6M1.55"
					( objectStatus "vss(69)" )
				)
				( pin "J6M1.53"
					( objectStatus "vss(70)" )
				)
				( pin "J6M1.50"
					( objectStatus "vss(71)" )
				)
				( pin "J6M1.48"
					( objectStatus "vss(72)" )
				)
				( pin "J6M1.46"
					( objectStatus "vss(73)" )
				)
				( pin "J6M1.44"
					( objectStatus "vss(74)" )
				)
				( pin "J6M1.42"
					( objectStatus "vss(75)" )
				)
				( pin "J6M1.39"
					( objectStatus "vss(76)" )
				)
				( pin "J6M1.37"
					( objectStatus "vss(77)" )
				)
				( pin "J6M1.35"
					( objectStatus "vss(78)" )
				)
				( pin "J6M1.33"
					( objectStatus "vss(79)" )
				)
				( pin "J6M1.31"
					( objectStatus "vss(80)" )
				)
				( pin "J6M1.28"
					( objectStatus "vss(81)" )
				)
				( pin "J6M1.26"
					( objectStatus "vss(82)" )
				)
				( pin "J6M1.24"
					( objectStatus "vss(83)" )
				)
				( pin "J6M1.22"
					( objectStatus "vss(84)" )
				)
				( pin "J6M1.20"
					( objectStatus "vss(85)" )
				)
				( pin "J6M1.17"
					( objectStatus "vss(86)" )
				)
				( pin "J6M1.15"
					( objectStatus "vss(87)" )
				)
				( pin "J6M1.13"
					( objectStatus "vss(88)" )
				)
				( pin "J6M1.11"
					( objectStatus "vss(89)" )
				)
				( pin "J6M1.9"
					( objectStatus "vss(90)" )
				)
				( pin "J6M1.6"
					( objectStatus "vss(91)" )
				)
				( pin "J6M1.4"
					( objectStatus "vss(92)" )
				)
				( pin "J6M1.2"
					( objectStatus "vss(93)" )
				)
			)
			( gate "J6M1"
				( objectStatus "@baseboard_fab2_lib.baseboard_fab2(sch_1):page50_i46" )
				( pin "J6M1.152"
					( objectStatus "dqs0n" )
				)
				( pin "J6M1.153"
					( objectStatus "dqs0p" )
				)
				( pin "J6M1.163"
					( objectStatus "dqs1n" )
				)
				( pin "J6M1.164"
					( objectStatus "dqs1p" )
				)
				( pin "J6M1.174"
					( objectStatus "dqs2n" )
				)
				( pin "J6M1.175"
					( objectStatus "dqs2p" )
				)
				( pin "J6M1.185"
					( objectStatus "dqs3n" )
				)
				( pin "J6M1.186"
					( objectStatus "dqs3p" )
				)
				( pin "J6M1.244"
					( objectStatus "dqs4n" )
				)
				( pin "J6M1.245"
					( objectStatus "dqs4p" )
				)
				( pin "J6M1.255"
					( objectStatus "dqs5n" )
				)
				( pin "J6M1.256"
					( objectStatus "dqs5p" )
				)
				( pin "J6M1.266"
					( objectStatus "dqs6n" )
				)
				( pin "J6M1.267"
					( objectStatus "dqs6p" )
				)
				( pin "J6M1.277"
					( objectStatus "dqs7n" )
				)
				( pin "J6M1.278"
					( objectStatus "dqs7p" )
				)
				( pin "J6M1.196"
					( objectStatus "dqs8n" )
				)
				( pin "J6M1.197"
					( objectStatus "dqs8p" )
				)
				( pin "J6M1.8"
					( objectStatus "dqs9n" )
				)
				( pin "J6M1.7"
					( objectStatus "dqs9p" )
				)
				( pin "J6M1.19"
					( objectStatus "dqs10n" )
				)
				( pin "J6M1.18"
					( objectStatus "dqs10p" )
				)
				( pin "J6M1.30"
					( objectStatus "dqs11n" )
				)
				( pin "J6M1.29"
					( objectStatus "dqs11p" )
				)
				( pin "J6M1.41"
					( objectStatus "dqs12n" )
				)
				( pin "J6M1.40"
					( objectStatus "dqs12p" )
				)
				( pin "J6M1.100"
					( objectStatus "dqs13n" )
				)
				( pin "J6M1.99"
					( objectStatus "dqs13p" )
				)
				( pin "J6M1.111"
					( objectStatus "dqs14n" )
				)
				( pin "J6M1.110"
					( objectStatus "dqs14p" )
				)
				( pin "J6M1.122"
					( objectStatus "dqs15n" )
				)
				( pin "J6M1.121"
					( objectStatus "dqs15p" )
				)
				( pin "J6M1.133"
					( objectStatus "dqs16n" )
				)
				( pin "J6M1.132"
					( objectStatus "dqs16p" )
				)
				( pin "J6M1.52"
					( objectStatus "dqs17n" )
				)
				( pin "J6M1.51"
					( objectStatus "dqs17p" )
				)
			)
			( gate "J6M1"
				( objectStatus "@baseboard_fab2_lib.baseboard_fab2(sch_1):page50_i50" )
				( pin "J6M1.145"
					( objectStatus "\12v\(0)" )
				)
				( pin "J6M1.1"
					( objectStatus "\12v\(1)" )
				)
				( pin "J6M1.236"
					( objectStatus "vdd(0)" )
				)
				( pin "J6M1.233"
					( objectStatus "vdd(1)" )
				)
				( pin "J6M1.231"
					( objectStatus "vdd(2)" )
				)
				( pin "J6M1.229"
					( objectStatus "vdd(3)" )
				)
				( pin "J6M1.226"
					( objectStatus "vdd(4)" )
				)
				( pin "J6M1.223"
					( objectStatus "vdd(5)" )
				)
				( pin "J6M1.220"
					( objectStatus "vdd(6)" )
				)
				( pin "J6M1.217"
					( objectStatus "vdd(7)" )
				)
				( pin "J6M1.215"
					( objectStatus "vdd(8)" )
				)
				( pin "J6M1.212"
					( objectStatus "vdd(9)" )
				)
				( pin "J6M1.209"
					( objectStatus "vdd(10)" )
				)
				( pin "J6M1.206"
					( objectStatus "vdd(11)" )
				)
				( pin "J6M1.204"
					( objectStatus "vdd(12)" )
				)
				( pin "J6M1.92"
					( objectStatus "vdd(13)" )
				)
				( pin "J6M1.90"
					( objectStatus "vdd(14)" )
				)
				( pin "J6M1.88"
					( objectStatus "vdd(15)" )
				)
				( pin "J6M1.85"
					( objectStatus "vdd(16)" )
				)
				( pin "J6M1.83"
					( objectStatus "vdd(17)" )
				)
				( pin "J6M1.80"
					( objectStatus "vdd(18)" )
				)
				( pin "J6M1.76"
					( objectStatus "vdd(19)" )
				)
				( pin "J6M1.73"
					( objectStatus "vdd(20)" )
				)
				( pin "J6M1.70"
					( objectStatus "vdd(21)" )
				)
				( pin "J6M1.67"
					( objectStatus "vdd(22)" )
				)
				( pin "J6M1.64"
					( objectStatus "vdd(23)" )
				)
				( pin "J6M1.61"
					( objectStatus "vdd(24)" )
				)
				( pin "J6M1.59"
					( objectStatus "vdd(25)" )
				)
				( pin "J6M1.287"
					( objectStatus "vpp(0)" )
				)
				( pin "J6M1.286"
					( objectStatus "vpp(1)" )
				)
				( pin "J6M1.288"
					( objectStatus "vpp(2)" )
				)
				( pin "J6M1.143"
					( objectStatus "vpp(3)" )
				)
				( pin "J6M1.142"
					( objectStatus "vpp(4)" )
				)
				( pin "J6M1.221"
					( objectStatus "vtt(0)" )
				)
				( pin "J6M1.77"
					( objectStatus "vtt(1)" )
				)
			)
			( gate "J6M1"
				( objectStatus "@baseboard_fab2_lib.baseboard_fab2(sch_1):page50_i158" )
				( pin "J6M1.79"
					( objectStatus "a0" )
				)
				( pin "J6M1.72"
					( objectStatus "a1" )
				)
				( pin "J6M1.216"
					( objectStatus "a2" )
				)
				( pin "J6M1.71"
					( objectStatus "a3" )
				)
				( pin "J6M1.214"
					( objectStatus "a4" )
				)
				( pin "J6M1.213"
					( objectStatus "a5" )
				)
				( pin "J6M1.69"
					( objectStatus "a6" )
				)
				( pin "J6M1.211"
					( objectStatus "a7" )
				)
				( pin "J6M1.68"
					( objectStatus "a8" )
				)
				( pin "J6M1.66"
					( objectStatus "a9" )
				)
				( pin "J6M1.225"
					( objectStatus "a10" )
				)
				( pin "J6M1.210"
					( objectStatus "a11" )
				)
				( pin "J6M1.65"
					( objectStatus "a12" )
				)
				( pin "J6M1.232"
					( objectStatus "a13" )
				)
				( pin "J6M1.228"
					( objectStatus "a14_we_n" )
				)
				( pin "J6M1.86"
					( objectStatus "a15_cas_n" )
				)
				( pin "J6M1.82"
					( objectStatus "a16_ras_n" )
				)
				( pin "J6M1.234"
					( objectStatus "a17" )
				)
				( pin "J6M1.62"
					( objectStatus "act_n" )
				)
				( pin "J6M1.208"
					( objectStatus "alert_n" )
				)
				( pin "J6M1.81"
					( objectStatus "ba(0)" )
				)
				( pin "J6M1.224"
					( objectStatus "ba(1)" )
				)
				( pin "J6M1.63"
					( objectStatus "bg(0)" )
				)
				( pin "J6M1.207"
					( objectStatus "bg(1)" )
				)
				( pin "J6M1.235"
					( objectStatus "c(2)" )
				)
				( pin "J6M1.49"
					( objectStatus "cb(0)" )
				)
				( pin "J6M1.194"
					( objectStatus "cb(1)" )
				)
				( pin "J6M1.56"
					( objectStatus "cb(2)" )
				)
				( pin "J6M1.201"
					( objectStatus "cb(3)" )
				)
				( pin "J6M1.47"
					( objectStatus "cb(4)" )
				)
				( pin "J6M1.192"
					( objectStatus "cb(5)" )
				)
				( pin "J6M1.54"
					( objectStatus "cb(6)" )
				)
				( pin "J6M1.199"
					( objectStatus "cb(7)" )
				)
				( pin "J6M1.75"
					( objectStatus "ck0n" )
				)
				( pin "J6M1.74"
					( objectStatus "ck0p" )
				)
				( pin "J6M1.219"
					( objectStatus "ck1n" )
				)
				( pin "J6M1.218"
					( objectStatus "ck1p" )
				)
				( pin "J6M1.60"
					( objectStatus "cke(0)" )
				)
				( pin "J6M1.203"
					( objectStatus "cke(1)" )
				)
				( pin "J6M1.5"
					( objectStatus "dq(0)" )
				)
				( pin "J6M1.150"
					( objectStatus "dq(1)" )
				)
				( pin "J6M1.12"
					( objectStatus "dq(2)" )
				)
				( pin "J6M1.157"
					( objectStatus "dq(3)" )
				)
				( pin "J6M1.3"
					( objectStatus "dq(4)" )
				)
				( pin "J6M1.148"
					( objectStatus "dq(5)" )
				)
				( pin "J6M1.10"
					( objectStatus "dq(6)" )
				)
				( pin "J6M1.155"
					( objectStatus "dq(7)" )
				)
				( pin "J6M1.16"
					( objectStatus "dq(8)" )
				)
				( pin "J6M1.161"
					( objectStatus "dq(9)" )
				)
				( pin "J6M1.23"
					( objectStatus "dq(10)" )
				)
				( pin "J6M1.168"
					( objectStatus "dq(11)" )
				)
				( pin "J6M1.14"
					( objectStatus "dq(12)" )
				)
				( pin "J6M1.159"
					( objectStatus "dq(13)" )
				)
				( pin "J6M1.21"
					( objectStatus "dq(14)" )
				)
				( pin "J6M1.166"
					( objectStatus "dq(15)" )
				)
				( pin "J6M1.27"
					( objectStatus "dq(16)" )
				)
				( pin "J6M1.172"
					( objectStatus "dq(17)" )
				)
				( pin "J6M1.34"
					( objectStatus "dq(18)" )
				)
				( pin "J6M1.179"
					( objectStatus "dq(19)" )
				)
				( pin "J6M1.25"
					( objectStatus "dq(20)" )
				)
				( pin "J6M1.170"
					( objectStatus "dq(21)" )
				)
				( pin "J6M1.32"
					( objectStatus "dq(22)" )
				)
				( pin "J6M1.177"
					( objectStatus "dq(23)" )
				)
				( pin "J6M1.38"
					( objectStatus "dq(24)" )
				)
				( pin "J6M1.183"
					( objectStatus "dq(25)" )
				)
				( pin "J6M1.45"
					( objectStatus "dq(26)" )
				)
				( pin "J6M1.190"
					( objectStatus "dq(27)" )
				)
				( pin "J6M1.36"
					( objectStatus "dq(28)" )
				)
				( pin "J6M1.181"
					( objectStatus "dq(29)" )
				)
				( pin "J6M1.43"
					( objectStatus "dq(30)" )
				)
				( pin "J6M1.188"
					( objectStatus "dq(31)" )
				)
				( pin "J6M1.97"
					( objectStatus "dq(32)" )
				)
				( pin "J6M1.242"
					( objectStatus "dq(33)" )
				)
				( pin "J6M1.104"
					( objectStatus "dq(34)" )
				)
				( pin "J6M1.249"
					( objectStatus "dq(35)" )
				)
				( pin "J6M1.95"
					( objectStatus "dq(36)" )
				)
				( pin "J6M1.240"
					( objectStatus "dq(37)" )
				)
				( pin "J6M1.102"
					( objectStatus "dq(38)" )
				)
				( pin "J6M1.247"
					( objectStatus "dq(39)" )
				)
				( pin "J6M1.108"
					( objectStatus "dq(40)" )
				)
				( pin "J6M1.253"
					( objectStatus "dq(41)" )
				)
				( pin "J6M1.115"
					( objectStatus "dq(42)" )
				)
				( pin "J6M1.260"
					( objectStatus "dq(43)" )
				)
				( pin "J6M1.106"
					( objectStatus "dq(44)" )
				)
				( pin "J6M1.251"
					( objectStatus "dq(45)" )
				)
				( pin "J6M1.113"
					( objectStatus "dq(46)" )
				)
				( pin "J6M1.258"
					( objectStatus "dq(47)" )
				)
				( pin "J6M1.119"
					( objectStatus "dq(48)" )
				)
				( pin "J6M1.264"
					( objectStatus "dq(49)" )
				)
				( pin "J6M1.126"
					( objectStatus "dq(50)" )
				)
				( pin "J6M1.271"
					( objectStatus "dq(51)" )
				)
				( pin "J6M1.117"
					( objectStatus "dq(52)" )
				)
				( pin "J6M1.262"
					( objectStatus "dq(53)" )
				)
				( pin "J6M1.124"
					( objectStatus "dq(54)" )
				)
				( pin "J6M1.269"
					( objectStatus "dq(55)" )
				)
				( pin "J6M1.130"
					( objectStatus "dq(56)" )
				)
				( pin "J6M1.275"
					( objectStatus "dq(57)" )
				)
				( pin "J6M1.137"
					( objectStatus "dq(58)" )
				)
				( pin "J6M1.282"
					( objectStatus "dq(59)" )
				)
				( pin "J6M1.128"
					( objectStatus "dq(60)" )
				)
				( pin "J6M1.273"
					( objectStatus "dq(61)" )
				)
				( pin "J6M1.135"
					( objectStatus "dq(62)" )
				)
				( pin "J6M1.280"
					( objectStatus "dq(63)" )
				)
				( pin "J6M1.78"
					( objectStatus "event_n" )
				)
				( pin "J6M1.87"
					( objectStatus "odt(0)" )
				)
				( pin "J6M1.91"
					( objectStatus "odt(1)" )
				)
				( pin "J6M1.222"
					( objectStatus "par" )
				)
				( pin "J6M1.58"
					( objectStatus "reset_n" )
				)
				( pin "J6M1.205"
					( objectStatus "rfu(0)" )
				)
				( pin "J6M1.227"
					( objectStatus "rfu(1)" )
				)
				( pin "J6M1.144"
					( objectStatus "rfu(2)" )
				)
				( pin "J6M1.84"
					( objectStatus "s0_n" )
				)
				( pin "J6M1.89"
					( objectStatus "s1_n" )
				)
				( pin "J6M1.93"
					( objectStatus "s2_n_c(0)" )
				)
				( pin "J6M1.237"
					( objectStatus "s3_n_c(1)" )
				)
				( pin "J6M1.139"
					( objectStatus "sa(0)" )
				)
				( pin "J6M1.140"
					( objectStatus "sa(1)" )
				)
				( pin "J6M1.238"
					( objectStatus "sa(2)" )
				)
				( pin "J6M1.230"
					( objectStatus "save_n_nc" )
				)
				( pin "J6M1.141"
					( objectStatus "scl" )
				)
				( pin "J6M1.285"
					( objectStatus "sda" )
				)
				( pin "J6M1.284"
					( objectStatus "vddspd" )
				)
				( pin "J6M1.146"
					( objectStatus "vrefca" )
				)
			)
			( gate "C6M1"
				( objectStatus "@baseboard_fab2_lib.baseboard_fab2(sch_1):page50_i177" )
				( pin "C6M1.1"
					( objectStatus "a" )
				)
				( pin "C6M1.2"
					( objectStatus "b" )
				)
			)
			( gate "J4A2"
				( objectStatus "@baseboard_fab2_lib.baseboard_fab2(sch_1):page51_i43" )
				( pin "J4A2.283"
					( objectStatus "vss(0)" )
				)
				( pin "J4A2.281"
					( objectStatus "vss(1)" )
				)
				( pin "J4A2.279"
					( objectStatus "vss(2)" )
				)
				( pin "J4A2.276"
					( objectStatus "vss(3)" )
				)
				( pin "J4A2.274"
					( objectStatus "vss(4)" )
				)
				( pin "J4A2.272"
					( objectStatus "vss(5)" )
				)
				( pin "J4A2.270"
					( objectStatus "vss(6)" )
				)
				( pin "J4A2.268"
					( objectStatus "vss(7)" )
				)
				( pin "J4A2.265"
					( objectStatus "vss(8)" )
				)
				( pin "J4A2.263"
					( objectStatus "vss(9)" )
				)
				( pin "J4A2.261"
					( objectStatus "vss(10)" )
				)
				( pin "J4A2.259"
					( objectStatus "vss(11)" )
				)
				( pin "J4A2.257"
					( objectStatus "vss(12)" )
				)
				( pin "J4A2.254"
					( objectStatus "vss(13)" )
				)
				( pin "J4A2.252"
					( objectStatus "vss(14)" )
				)
				( pin "J4A2.250"
					( objectStatus "vss(15)" )
				)
				( pin "J4A2.248"
					( objectStatus "vss(16)" )
				)
				( pin "J4A2.246"
					( objectStatus "vss(17)" )
				)
				( pin "J4A2.243"
					( objectStatus "vss(18)" )
				)
				( pin "J4A2.241"
					( objectStatus "vss(19)" )
				)
				( pin "J4A2.239"
					( objectStatus "vss(20)" )
				)
				( pin "J4A2.202"
					( objectStatus "vss(21)" )
				)
				( pin "J4A2.200"
					( objectStatus "vss(22)" )
				)
				( pin "J4A2.198"
					( objectStatus "vss(23)" )
				)
				( pin "J4A2.195"
					( objectStatus "vss(24)" )
				)
				( pin "J4A2.193"
					( objectStatus "vss(25)" )
				)
				( pin "J4A2.191"
					( objectStatus "vss(26)" )
				)
				( pin "J4A2.189"
					( objectStatus "vss(27)" )
				)
				( pin "J4A2.187"
					( objectStatus "vss(28)" )
				)
				( pin "J4A2.184"
					( objectStatus "vss(29)" )
				)
				( pin "J4A2.182"
					( objectStatus "vss(30)" )
				)
				( pin "J4A2.180"
					( objectStatus "vss(31)" )
				)
				( pin "J4A2.178"
					( objectStatus "vss(32)" )
				)
				( pin "J4A2.176"
					( objectStatus "vss(33)" )
				)
				( pin "J4A2.173"
					( objectStatus "vss(34)" )
				)
				( pin "J4A2.171"
					( objectStatus "vss(35)" )
				)
				( pin "J4A2.169"
					( objectStatus "vss(36)" )
				)
				( pin "J4A2.167"
					( objectStatus "vss(37)" )
				)
				( pin "J4A2.165"
					( objectStatus "vss(38)" )
				)
				( pin "J4A2.162"
					( objectStatus "vss(39)" )
				)
				( pin "J4A2.160"
					( objectStatus "vss(40)" )
				)
				( pin "J4A2.158"
					( objectStatus "vss(41)" )
				)
				( pin "J4A2.156"
					( objectStatus "vss(42)" )
				)
				( pin "J4A2.154"
					( objectStatus "vss(43)" )
				)
				( pin "J4A2.151"
					( objectStatus "vss(44)" )
				)
				( pin "J4A2.149"
					( objectStatus "vss(45)" )
				)
				( pin "J4A2.147"
					( objectStatus "vss(46)" )
				)
				( pin "J4A2.138"
					( objectStatus "vss(47)" )
				)
				( pin "J4A2.136"
					( objectStatus "vss(48)" )
				)
				( pin "J4A2.134"
					( objectStatus "vss(49)" )
				)
				( pin "J4A2.131"
					( objectStatus "vss(50)" )
				)
				( pin "J4A2.129"
					( objectStatus "vss(51)" )
				)
				( pin "J4A2.127"
					( objectStatus "vss(52)" )
				)
				( pin "J4A2.125"
					( objectStatus "vss(53)" )
				)
				( pin "J4A2.123"
					( objectStatus "vss(54)" )
				)
				( pin "J4A2.120"
					( objectStatus "vss(55)" )
				)
				( pin "J4A2.118"
					( objectStatus "vss(56)" )
				)
				( pin "J4A2.116"
					( objectStatus "vss(57)" )
				)
				( pin "J4A2.114"
					( objectStatus "vss(58)" )
				)
				( pin "J4A2.112"
					( objectStatus "vss(59)" )
				)
				( pin "J4A2.109"
					( objectStatus "vss(60)" )
				)
				( pin "J4A2.107"
					( objectStatus "vss(61)" )
				)
				( pin "J4A2.105"
					( objectStatus "vss(62)" )
				)
				( pin "J4A2.103"
					( objectStatus "vss(63)" )
				)
				( pin "J4A2.101"
					( objectStatus "vss(64)" )
				)
				( pin "J4A2.98"
					( objectStatus "vss(65)" )
				)
				( pin "J4A2.96"
					( objectStatus "vss(66)" )
				)
				( pin "J4A2.94"
					( objectStatus "vss(67)" )
				)
				( pin "J4A2.57"
					( objectStatus "vss(68)" )
				)
				( pin "J4A2.55"
					( objectStatus "vss(69)" )
				)
				( pin "J4A2.53"
					( objectStatus "vss(70)" )
				)
				( pin "J4A2.50"
					( objectStatus "vss(71)" )
				)
				( pin "J4A2.48"
					( objectStatus "vss(72)" )
				)
				( pin "J4A2.46"
					( objectStatus "vss(73)" )
				)
				( pin "J4A2.44"
					( objectStatus "vss(74)" )
				)
				( pin "J4A2.42"
					( objectStatus "vss(75)" )
				)
				( pin "J4A2.39"
					( objectStatus "vss(76)" )
				)
				( pin "J4A2.37"
					( objectStatus "vss(77)" )
				)
				( pin "J4A2.35"
					( objectStatus "vss(78)" )
				)
				( pin "J4A2.33"
					( objectStatus "vss(79)" )
				)
				( pin "J4A2.31"
					( objectStatus "vss(80)" )
				)
				( pin "J4A2.28"
					( objectStatus "vss(81)" )
				)
				( pin "J4A2.26"
					( objectStatus "vss(82)" )
				)
				( pin "J4A2.24"
					( objectStatus "vss(83)" )
				)
				( pin "J4A2.22"
					( objectStatus "vss(84)" )
				)
				( pin "J4A2.20"
					( objectStatus "vss(85)" )
				)
				( pin "J4A2.17"
					( objectStatus "vss(86)" )
				)
				( pin "J4A2.15"
					( objectStatus "vss(87)" )
				)
				( pin "J4A2.13"
					( objectStatus "vss(88)" )
				)
				( pin "J4A2.11"
					( objectStatus "vss(89)" )
				)
				( pin "J4A2.9"
					( objectStatus "vss(90)" )
				)
				( pin "J4A2.6"
					( objectStatus "vss(91)" )
				)
				( pin "J4A2.4"
					( objectStatus "vss(92)" )
				)
				( pin "J4A2.2"
					( objectStatus "vss(93)" )
				)
			)
			( gate "J4A2"
				( objectStatus "@baseboard_fab2_lib.baseboard_fab2(sch_1):page51_i66" )
				( pin "J4A2.152"
					( objectStatus "dqs0n" )
				)
				( pin "J4A2.153"
					( objectStatus "dqs0p" )
				)
				( pin "J4A2.163"
					( objectStatus "dqs1n" )
				)
				( pin "J4A2.164"
					( objectStatus "dqs1p" )
				)
				( pin "J4A2.174"
					( objectStatus "dqs2n" )
				)
				( pin "J4A2.175"
					( objectStatus "dqs2p" )
				)
				( pin "J4A2.185"
					( objectStatus "dqs3n" )
				)
				( pin "J4A2.186"
					( objectStatus "dqs3p" )
				)
				( pin "J4A2.244"
					( objectStatus "dqs4n" )
				)
				( pin "J4A2.245"
					( objectStatus "dqs4p" )
				)
				( pin "J4A2.255"
					( objectStatus "dqs5n" )
				)
				( pin "J4A2.256"
					( objectStatus "dqs5p" )
				)
				( pin "J4A2.266"
					( objectStatus "dqs6n" )
				)
				( pin "J4A2.267"
					( objectStatus "dqs6p" )
				)
				( pin "J4A2.277"
					( objectStatus "dqs7n" )
				)
				( pin "J4A2.278"
					( objectStatus "dqs7p" )
				)
				( pin "J4A2.196"
					( objectStatus "dqs8n" )
				)
				( pin "J4A2.197"
					( objectStatus "dqs8p" )
				)
				( pin "J4A2.8"
					( objectStatus "dqs9n" )
				)
				( pin "J4A2.7"
					( objectStatus "dqs9p" )
				)
				( pin "J4A2.19"
					( objectStatus "dqs10n" )
				)
				( pin "J4A2.18"
					( objectStatus "dqs10p" )
				)
				( pin "J4A2.30"
					( objectStatus "dqs11n" )
				)
				( pin "J4A2.29"
					( objectStatus "dqs11p" )
				)
				( pin "J4A2.41"
					( objectStatus "dqs12n" )
				)
				( pin "J4A2.40"
					( objectStatus "dqs12p" )
				)
				( pin "J4A2.100"
					( objectStatus "dqs13n" )
				)
				( pin "J4A2.99"
					( objectStatus "dqs13p" )
				)
				( pin "J4A2.111"
					( objectStatus "dqs14n" )
				)
				( pin "J4A2.110"
					( objectStatus "dqs14p" )
				)
				( pin "J4A2.122"
					( objectStatus "dqs15n" )
				)
				( pin "J4A2.121"
					( objectStatus "dqs15p" )
				)
				( pin "J4A2.133"
					( objectStatus "dqs16n" )
				)
				( pin "J4A2.132"
					( objectStatus "dqs16p" )
				)
				( pin "J4A2.52"
					( objectStatus "dqs17n" )
				)
				( pin "J4A2.51"
					( objectStatus "dqs17p" )
				)
			)
			( gate "J4A2"
				( objectStatus "@baseboard_fab2_lib.baseboard_fab2(sch_1):page51_i111" )
				( pin "J4A2.79"
					( objectStatus "a0" )
				)
				( pin "J4A2.72"
					( objectStatus "a1" )
				)
				( pin "J4A2.216"
					( objectStatus "a2" )
				)
				( pin "J4A2.71"
					( objectStatus "a3" )
				)
				( pin "J4A2.214"
					( objectStatus "a4" )
				)
				( pin "J4A2.213"
					( objectStatus "a5" )
				)
				( pin "J4A2.69"
					( objectStatus "a6" )
				)
				( pin "J4A2.211"
					( objectStatus "a7" )
				)
				( pin "J4A2.68"
					( objectStatus "a8" )
				)
				( pin "J4A2.66"
					( objectStatus "a9" )
				)
				( pin "J4A2.225"
					( objectStatus "a10" )
				)
				( pin "J4A2.210"
					( objectStatus "a11" )
				)
				( pin "J4A2.65"
					( objectStatus "a12" )
				)
				( pin "J4A2.232"
					( objectStatus "a13" )
				)
				( pin "J4A2.228"
					( objectStatus "a14_we_n" )
				)
				( pin "J4A2.86"
					( objectStatus "a15_cas_n" )
				)
				( pin "J4A2.82"
					( objectStatus "a16_ras_n" )
				)
				( pin "J4A2.234"
					( objectStatus "a17" )
				)
				( pin "J4A2.62"
					( objectStatus "act_n" )
				)
				( pin "J4A2.208"
					( objectStatus "alert_n" )
				)
				( pin "J4A2.81"
					( objectStatus "ba(0)" )
				)
				( pin "J4A2.224"
					( objectStatus "ba(1)" )
				)
				( pin "J4A2.63"
					( objectStatus "bg(0)" )
				)
				( pin "J4A2.207"
					( objectStatus "bg(1)" )
				)
				( pin "J4A2.235"
					( objectStatus "c(2)" )
				)
				( pin "J4A2.49"
					( objectStatus "cb(0)" )
				)
				( pin "J4A2.194"
					( objectStatus "cb(1)" )
				)
				( pin "J4A2.56"
					( objectStatus "cb(2)" )
				)
				( pin "J4A2.201"
					( objectStatus "cb(3)" )
				)
				( pin "J4A2.47"
					( objectStatus "cb(4)" )
				)
				( pin "J4A2.192"
					( objectStatus "cb(5)" )
				)
				( pin "J4A2.54"
					( objectStatus "cb(6)" )
				)
				( pin "J4A2.199"
					( objectStatus "cb(7)" )
				)
				( pin "J4A2.75"
					( objectStatus "ck0n" )
				)
				( pin "J4A2.74"
					( objectStatus "ck0p" )
				)
				( pin "J4A2.219"
					( objectStatus "ck1n" )
				)
				( pin "J4A2.218"
					( objectStatus "ck1p" )
				)
				( pin "J4A2.60"
					( objectStatus "cke(0)" )
				)
				( pin "J4A2.203"
					( objectStatus "cke(1)" )
				)
				( pin "J4A2.5"
					( objectStatus "dq(0)" )
				)
				( pin "J4A2.150"
					( objectStatus "dq(1)" )
				)
				( pin "J4A2.12"
					( objectStatus "dq(2)" )
				)
				( pin "J4A2.157"
					( objectStatus "dq(3)" )
				)
				( pin "J4A2.3"
					( objectStatus "dq(4)" )
				)
				( pin "J4A2.148"
					( objectStatus "dq(5)" )
				)
				( pin "J4A2.10"
					( objectStatus "dq(6)" )
				)
				( pin "J4A2.155"
					( objectStatus "dq(7)" )
				)
				( pin "J4A2.16"
					( objectStatus "dq(8)" )
				)
				( pin "J4A2.161"
					( objectStatus "dq(9)" )
				)
				( pin "J4A2.23"
					( objectStatus "dq(10)" )
				)
				( pin "J4A2.168"
					( objectStatus "dq(11)" )
				)
				( pin "J4A2.14"
					( objectStatus "dq(12)" )
				)
				( pin "J4A2.159"
					( objectStatus "dq(13)" )
				)
				( pin "J4A2.21"
					( objectStatus "dq(14)" )
				)
				( pin "J4A2.166"
					( objectStatus "dq(15)" )
				)
				( pin "J4A2.27"
					( objectStatus "dq(16)" )
				)
				( pin "J4A2.172"
					( objectStatus "dq(17)" )
				)
				( pin "J4A2.34"
					( objectStatus "dq(18)" )
				)
				( pin "J4A2.179"
					( objectStatus "dq(19)" )
				)
				( pin "J4A2.25"
					( objectStatus "dq(20)" )
				)
				( pin "J4A2.170"
					( objectStatus "dq(21)" )
				)
				( pin "J4A2.32"
					( objectStatus "dq(22)" )
				)
				( pin "J4A2.177"
					( objectStatus "dq(23)" )
				)
				( pin "J4A2.38"
					( objectStatus "dq(24)" )
				)
				( pin "J4A2.183"
					( objectStatus "dq(25)" )
				)
				( pin "J4A2.45"
					( objectStatus "dq(26)" )
				)
				( pin "J4A2.190"
					( objectStatus "dq(27)" )
				)
				( pin "J4A2.36"
					( objectStatus "dq(28)" )
				)
				( pin "J4A2.181"
					( objectStatus "dq(29)" )
				)
				( pin "J4A2.43"
					( objectStatus "dq(30)" )
				)
				( pin "J4A2.188"
					( objectStatus "dq(31)" )
				)
				( pin "J4A2.97"
					( objectStatus "dq(32)" )
				)
				( pin "J4A2.242"
					( objectStatus "dq(33)" )
				)
				( pin "J4A2.104"
					( objectStatus "dq(34)" )
				)
				( pin "J4A2.249"
					( objectStatus "dq(35)" )
				)
				( pin "J4A2.95"
					( objectStatus "dq(36)" )
				)
				( pin "J4A2.240"
					( objectStatus "dq(37)" )
				)
				( pin "J4A2.102"
					( objectStatus "dq(38)" )
				)
				( pin "J4A2.247"
					( objectStatus "dq(39)" )
				)
				( pin "J4A2.108"
					( objectStatus "dq(40)" )
				)
				( pin "J4A2.253"
					( objectStatus "dq(41)" )
				)
				( pin "J4A2.115"
					( objectStatus "dq(42)" )
				)
				( pin "J4A2.260"
					( objectStatus "dq(43)" )
				)
				( pin "J4A2.106"
					( objectStatus "dq(44)" )
				)
				( pin "J4A2.251"
					( objectStatus "dq(45)" )
				)
				( pin "J4A2.113"
					( objectStatus "dq(46)" )
				)
				( pin "J4A2.258"
					( objectStatus "dq(47)" )
				)
				( pin "J4A2.119"
					( objectStatus "dq(48)" )
				)
				( pin "J4A2.264"
					( objectStatus "dq(49)" )
				)
				( pin "J4A2.126"
					( objectStatus "dq(50)" )
				)
				( pin "J4A2.271"
					( objectStatus "dq(51)" )
				)
				( pin "J4A2.117"
					( objectStatus "dq(52)" )
				)
				( pin "J4A2.262"
					( objectStatus "dq(53)" )
				)
				( pin "J4A2.124"
					( objectStatus "dq(54)" )
				)
				( pin "J4A2.269"
					( objectStatus "dq(55)" )
				)
				( pin "J4A2.130"
					( objectStatus "dq(56)" )
				)
				( pin "J4A2.275"
					( objectStatus "dq(57)" )
				)
				( pin "J4A2.137"
					( objectStatus "dq(58)" )
				)
				( pin "J4A2.282"
					( objectStatus "dq(59)" )
				)
				( pin "J4A2.128"
					( objectStatus "dq(60)" )
				)
				( pin "J4A2.273"
					( objectStatus "dq(61)" )
				)
				( pin "J4A2.135"
					( objectStatus "dq(62)" )
				)
				( pin "J4A2.280"
					( objectStatus "dq(63)" )
				)
				( pin "J4A2.78"
					( objectStatus "event_n" )
				)
				( pin "J4A2.87"
					( objectStatus "odt(0)" )
				)
				( pin "J4A2.91"
					( objectStatus "odt(1)" )
				)
				( pin "J4A2.222"
					( objectStatus "par" )
				)
				( pin "J4A2.58"
					( objectStatus "reset_n" )
				)
				( pin "J4A2.205"
					( objectStatus "rfu(0)" )
				)
				( pin "J4A2.227"
					( objectStatus "rfu(1)" )
				)
				( pin "J4A2.144"
					( objectStatus "rfu(2)" )
				)
				( pin "J4A2.84"
					( objectStatus "s0_n" )
				)
				( pin "J4A2.89"
					( objectStatus "s1_n" )
				)
				( pin "J4A2.93"
					( objectStatus "s2_n_c(0)" )
				)
				( pin "J4A2.237"
					( objectStatus "s3_n_c(1)" )
				)
				( pin "J4A2.139"
					( objectStatus "sa(0)" )
				)
				( pin "J4A2.140"
					( objectStatus "sa(1)" )
				)
				( pin "J4A2.238"
					( objectStatus "sa(2)" )
				)
				( pin "J4A2.230"
					( objectStatus "save_n_nc" )
				)
				( pin "J4A2.141"
					( objectStatus "scl" )
				)
				( pin "J4A2.285"
					( objectStatus "sda" )
				)
				( pin "J4A2.284"
					( objectStatus "vddspd" )
				)
				( pin "J4A2.146"
					( objectStatus "vrefca" )
				)
			)
			( gate "J4A2"
				( objectStatus "@baseboard_fab2_lib.baseboard_fab2(sch_1):page51_i167" )
				( pin "J4A2.145"
					( objectStatus "\12v\(0)" )
				)
				( pin "J4A2.1"
					( objectStatus "\12v\(1)" )
				)
				( pin "J4A2.236"
					( objectStatus "vdd(0)" )
				)
				( pin "J4A2.233"
					( objectStatus "vdd(1)" )
				)
				( pin "J4A2.231"
					( objectStatus "vdd(2)" )
				)
				( pin "J4A2.229"
					( objectStatus "vdd(3)" )
				)
				( pin "J4A2.226"
					( objectStatus "vdd(4)" )
				)
				( pin "J4A2.223"
					( objectStatus "vdd(5)" )
				)
				( pin "J4A2.220"
					( objectStatus "vdd(6)" )
				)
				( pin "J4A2.217"
					( objectStatus "vdd(7)" )
				)
				( pin "J4A2.215"
					( objectStatus "vdd(8)" )
				)
				( pin "J4A2.212"
					( objectStatus "vdd(9)" )
				)
				( pin "J4A2.209"
					( objectStatus "vdd(10)" )
				)
				( pin "J4A2.206"
					( objectStatus "vdd(11)" )
				)
				( pin "J4A2.204"
					( objectStatus "vdd(12)" )
				)
				( pin "J4A2.92"
					( objectStatus "vdd(13)" )
				)
				( pin "J4A2.90"
					( objectStatus "vdd(14)" )
				)
				( pin "J4A2.88"
					( objectStatus "vdd(15)" )
				)
				( pin "J4A2.85"
					( objectStatus "vdd(16)" )
				)
				( pin "J4A2.83"
					( objectStatus "vdd(17)" )
				)
				( pin "J4A2.80"
					( objectStatus "vdd(18)" )
				)
				( pin "J4A2.76"
					( objectStatus "vdd(19)" )
				)
				( pin "J4A2.73"
					( objectStatus "vdd(20)" )
				)
				( pin "J4A2.70"
					( objectStatus "vdd(21)" )
				)
				( pin "J4A2.67"
					( objectStatus "vdd(22)" )
				)
				( pin "J4A2.64"
					( objectStatus "vdd(23)" )
				)
				( pin "J4A2.61"
					( objectStatus "vdd(24)" )
				)
				( pin "J4A2.59"
					( objectStatus "vdd(25)" )
				)
				( pin "J4A2.287"
					( objectStatus "vpp(0)" )
				)
				( pin "J4A2.286"
					( objectStatus "vpp(1)" )
				)
				( pin "J4A2.288"
					( objectStatus "vpp(2)" )
				)
				( pin "J4A2.143"
					( objectStatus "vpp(3)" )
				)
				( pin "J4A2.142"
					( objectStatus "vpp(4)" )
				)
				( pin "J4A2.221"
					( objectStatus "vtt(0)" )
				)
				( pin "J4A2.77"
					( objectStatus "vtt(1)" )
				)
			)
			( gate "C6L6"
				( objectStatus "@baseboard_fab2_lib.baseboard_fab2(sch_1):page51_i175" )
				( pin "C6L6.1"
					( objectStatus "a" )
				)
				( pin "C6L6.2"
					( objectStatus "b" )
				)
			)
			( gate "C4A18"
				( objectStatus "@baseboard_fab2_lib.baseboard_fab2(sch_1):page52_i3" )
				( pin "C4A18.1"
					( objectStatus "a" )
				)
				( pin "C4A18.2"
					( objectStatus "b" )
				)
			)
			( gate "J6L2"
				( objectStatus "@baseboard_fab2_lib.baseboard_fab2(sch_1):page52_i12" )
				( pin "J6L2.79"
					( objectStatus "a0" )
				)
				( pin "J6L2.72"
					( objectStatus "a1" )
				)
				( pin "J6L2.216"
					( objectStatus "a2" )
				)
				( pin "J6L2.71"
					( objectStatus "a3" )
				)
				( pin "J6L2.214"
					( objectStatus "a4" )
				)
				( pin "J6L2.213"
					( objectStatus "a5" )
				)
				( pin "J6L2.69"
					( objectStatus "a6" )
				)
				( pin "J6L2.211"
					( objectStatus "a7" )
				)
				( pin "J6L2.68"
					( objectStatus "a8" )
				)
				( pin "J6L2.66"
					( objectStatus "a9" )
				)
				( pin "J6L2.225"
					( objectStatus "a10" )
				)
				( pin "J6L2.210"
					( objectStatus "a11" )
				)
				( pin "J6L2.65"
					( objectStatus "a12" )
				)
				( pin "J6L2.232"
					( objectStatus "a13" )
				)
				( pin "J6L2.228"
					( objectStatus "a14_we_n" )
				)
				( pin "J6L2.86"
					( objectStatus "a15_cas_n" )
				)
				( pin "J6L2.82"
					( objectStatus "a16_ras_n" )
				)
				( pin "J6L2.234"
					( objectStatus "a17" )
				)
				( pin "J6L2.62"
					( objectStatus "act_n" )
				)
				( pin "J6L2.208"
					( objectStatus "alert_n" )
				)
				( pin "J6L2.81"
					( objectStatus "ba(0)" )
				)
				( pin "J6L2.224"
					( objectStatus "ba(1)" )
				)
				( pin "J6L2.63"
					( objectStatus "bg(0)" )
				)
				( pin "J6L2.207"
					( objectStatus "bg(1)" )
				)
				( pin "J6L2.235"
					( objectStatus "c(2)" )
				)
				( pin "J6L2.49"
					( objectStatus "cb(0)" )
				)
				( pin "J6L2.194"
					( objectStatus "cb(1)" )
				)
				( pin "J6L2.56"
					( objectStatus "cb(2)" )
				)
				( pin "J6L2.201"
					( objectStatus "cb(3)" )
				)
				( pin "J6L2.47"
					( objectStatus "cb(4)" )
				)
				( pin "J6L2.192"
					( objectStatus "cb(5)" )
				)
				( pin "J6L2.54"
					( objectStatus "cb(6)" )
				)
				( pin "J6L2.199"
					( objectStatus "cb(7)" )
				)
				( pin "J6L2.75"
					( objectStatus "ck0n" )
				)
				( pin "J6L2.74"
					( objectStatus "ck0p" )
				)
				( pin "J6L2.219"
					( objectStatus "ck1n" )
				)
				( pin "J6L2.218"
					( objectStatus "ck1p" )
				)
				( pin "J6L2.60"
					( objectStatus "cke(0)" )
				)
				( pin "J6L2.203"
					( objectStatus "cke(1)" )
				)
				( pin "J6L2.5"
					( objectStatus "dq(0)" )
				)
				( pin "J6L2.150"
					( objectStatus "dq(1)" )
				)
				( pin "J6L2.12"
					( objectStatus "dq(2)" )
				)
				( pin "J6L2.157"
					( objectStatus "dq(3)" )
				)
				( pin "J6L2.3"
					( objectStatus "dq(4)" )
				)
				( pin "J6L2.148"
					( objectStatus "dq(5)" )
				)
				( pin "J6L2.10"
					( objectStatus "dq(6)" )
				)
				( pin "J6L2.155"
					( objectStatus "dq(7)" )
				)
				( pin "J6L2.16"
					( objectStatus "dq(8)" )
				)
				( pin "J6L2.161"
					( objectStatus "dq(9)" )
				)
				( pin "J6L2.23"
					( objectStatus "dq(10)" )
				)
				( pin "J6L2.168"
					( objectStatus "dq(11)" )
				)
				( pin "J6L2.14"
					( objectStatus "dq(12)" )
				)
				( pin "J6L2.159"
					( objectStatus "dq(13)" )
				)
				( pin "J6L2.21"
					( objectStatus "dq(14)" )
				)
				( pin "J6L2.166"
					( objectStatus "dq(15)" )
				)
				( pin "J6L2.27"
					( objectStatus "dq(16)" )
				)
				( pin "J6L2.172"
					( objectStatus "dq(17)" )
				)
				( pin "J6L2.34"
					( objectStatus "dq(18)" )
				)
				( pin "J6L2.179"
					( objectStatus "dq(19)" )
				)
				( pin "J6L2.25"
					( objectStatus "dq(20)" )
				)
				( pin "J6L2.170"
					( objectStatus "dq(21)" )
				)
				( pin "J6L2.32"
					( objectStatus "dq(22)" )
				)
				( pin "J6L2.177"
					( objectStatus "dq(23)" )
				)
				( pin "J6L2.38"
					( objectStatus "dq(24)" )
				)
				( pin "J6L2.183"
					( objectStatus "dq(25)" )
				)
				( pin "J6L2.45"
					( objectStatus "dq(26)" )
				)
				( pin "J6L2.190"
					( objectStatus "dq(27)" )
				)
				( pin "J6L2.36"
					( objectStatus "dq(28)" )
				)
				( pin "J6L2.181"
					( objectStatus "dq(29)" )
				)
				( pin "J6L2.43"
					( objectStatus "dq(30)" )
				)
				( pin "J6L2.188"
					( objectStatus "dq(31)" )
				)
				( pin "J6L2.97"
					( objectStatus "dq(32)" )
				)
				( pin "J6L2.242"
					( objectStatus "dq(33)" )
				)
				( pin "J6L2.104"
					( objectStatus "dq(34)" )
				)
				( pin "J6L2.249"
					( objectStatus "dq(35)" )
				)
				( pin "J6L2.95"
					( objectStatus "dq(36)" )
				)
				( pin "J6L2.240"
					( objectStatus "dq(37)" )
				)
				( pin "J6L2.102"
					( objectStatus "dq(38)" )
				)
				( pin "J6L2.247"
					( objectStatus "dq(39)" )
				)
				( pin "J6L2.108"
					( objectStatus "dq(40)" )
				)
				( pin "J6L2.253"
					( objectStatus "dq(41)" )
				)
				( pin "J6L2.115"
					( objectStatus "dq(42)" )
				)
				( pin "J6L2.260"
					( objectStatus "dq(43)" )
				)
				( pin "J6L2.106"
					( objectStatus "dq(44)" )
				)
				( pin "J6L2.251"
					( objectStatus "dq(45)" )
				)
				( pin "J6L2.113"
					( objectStatus "dq(46)" )
				)
				( pin "J6L2.258"
					( objectStatus "dq(47)" )
				)
				( pin "J6L2.119"
					( objectStatus "dq(48)" )
				)
				( pin "J6L2.264"
					( objectStatus "dq(49)" )
				)
				( pin "J6L2.126"
					( objectStatus "dq(50)" )
				)
				( pin "J6L2.271"
					( objectStatus "dq(51)" )
				)
				( pin "J6L2.117"
					( objectStatus "dq(52)" )
				)
				( pin "J6L2.262"
					( objectStatus "dq(53)" )
				)
				( pin "J6L2.124"
					( objectStatus "dq(54)" )
				)
				( pin "J6L2.269"
					( objectStatus "dq(55)" )
				)
				( pin "J6L2.130"
					( objectStatus "dq(56)" )
				)
				( pin "J6L2.275"
					( objectStatus "dq(57)" )
				)
				( pin "J6L2.137"
					( objectStatus "dq(58)" )
				)
				( pin "J6L2.282"
					( objectStatus "dq(59)" )
				)
				( pin "J6L2.128"
					( objectStatus "dq(60)" )
				)
				( pin "J6L2.273"
					( objectStatus "dq(61)" )
				)
				( pin "J6L2.135"
					( objectStatus "dq(62)" )
				)
				( pin "J6L2.280"
					( objectStatus "dq(63)" )
				)
				( pin "J6L2.78"
					( objectStatus "event_n" )
				)
				( pin "J6L2.87"
					( objectStatus "odt(0)" )
				)
				( pin "J6L2.91"
					( objectStatus "odt(1)" )
				)
				( pin "J6L2.222"
					( objectStatus "par" )
				)
				( pin "J6L2.58"
					( objectStatus "reset_n" )
				)
				( pin "J6L2.205"
					( objectStatus "rfu(0)" )
				)
				( pin "J6L2.227"
					( objectStatus "rfu(1)" )
				)
				( pin "J6L2.144"
					( objectStatus "rfu(2)" )
				)
				( pin "J6L2.84"
					( objectStatus "s0_n" )
				)
				( pin "J6L2.89"
					( objectStatus "s1_n" )
				)
				( pin "J6L2.93"
					( objectStatus "s2_n_c(0)" )
				)
				( pin "J6L2.237"
					( objectStatus "s3_n_c(1)" )
				)
				( pin "J6L2.139"
					( objectStatus "sa(0)" )
				)
				( pin "J6L2.140"
					( objectStatus "sa(1)" )
				)
				( pin "J6L2.238"
					( objectStatus "sa(2)" )
				)
				( pin "J6L2.230"
					( objectStatus "save_n_nc" )
				)
				( pin "J6L2.141"
					( objectStatus "scl" )
				)
				( pin "J6L2.285"
					( objectStatus "sda" )
				)
				( pin "J6L2.284"
					( objectStatus "vddspd" )
				)
				( pin "J6L2.146"
					( objectStatus "vrefca" )
				)
			)
			( gate "J6L2"
				( objectStatus "@baseboard_fab2_lib.baseboard_fab2(sch_1):page52_i55" )
				( pin "J6L2.145"
					( objectStatus "\12v\(0)" )
				)
				( pin "J6L2.1"
					( objectStatus "\12v\(1)" )
				)
				( pin "J6L2.236"
					( objectStatus "vdd(0)" )
				)
				( pin "J6L2.233"
					( objectStatus "vdd(1)" )
				)
				( pin "J6L2.231"
					( objectStatus "vdd(2)" )
				)
				( pin "J6L2.229"
					( objectStatus "vdd(3)" )
				)
				( pin "J6L2.226"
					( objectStatus "vdd(4)" )
				)
				( pin "J6L2.223"
					( objectStatus "vdd(5)" )
				)
				( pin "J6L2.220"
					( objectStatus "vdd(6)" )
				)
				( pin "J6L2.217"
					( objectStatus "vdd(7)" )
				)
				( pin "J6L2.215"
					( objectStatus "vdd(8)" )
				)
				( pin "J6L2.212"
					( objectStatus "vdd(9)" )
				)
				( pin "J6L2.209"
					( objectStatus "vdd(10)" )
				)
				( pin "J6L2.206"
					( objectStatus "vdd(11)" )
				)
				( pin "J6L2.204"
					( objectStatus "vdd(12)" )
				)
				( pin "J6L2.92"
					( objectStatus "vdd(13)" )
				)
				( pin "J6L2.90"
					( objectStatus "vdd(14)" )
				)
				( pin "J6L2.88"
					( objectStatus "vdd(15)" )
				)
				( pin "J6L2.85"
					( objectStatus "vdd(16)" )
				)
				( pin "J6L2.83"
					( objectStatus "vdd(17)" )
				)
				( pin "J6L2.80"
					( objectStatus "vdd(18)" )
				)
				( pin "J6L2.76"
					( objectStatus "vdd(19)" )
				)
				( pin "J6L2.73"
					( objectStatus "vdd(20)" )
				)
				( pin "J6L2.70"
					( objectStatus "vdd(21)" )
				)
				( pin "J6L2.67"
					( objectStatus "vdd(22)" )
				)
				( pin "J6L2.64"
					( objectStatus "vdd(23)" )
				)
				( pin "J6L2.61"
					( objectStatus "vdd(24)" )
				)
				( pin "J6L2.59"
					( objectStatus "vdd(25)" )
				)
				( pin "J6L2.287"
					( objectStatus "vpp(0)" )
				)
				( pin "J6L2.286"
					( objectStatus "vpp(1)" )
				)
				( pin "J6L2.288"
					( objectStatus "vpp(2)" )
				)
				( pin "J6L2.143"
					( objectStatus "vpp(3)" )
				)
				( pin "J6L2.142"
					( objectStatus "vpp(4)" )
				)
				( pin "J6L2.221"
					( objectStatus "vtt(0)" )
				)
				( pin "J6L2.77"
					( objectStatus "vtt(1)" )
				)
			)
			( gate "J6L2"
				( objectStatus "@baseboard_fab2_lib.baseboard_fab2(sch_1):page52_i100" )
				( pin "J6L2.152"
					( objectStatus "dqs0n" )
				)
				( pin "J6L2.153"
					( objectStatus "dqs0p" )
				)
				( pin "J6L2.163"
					( objectStatus "dqs1n" )
				)
				( pin "J6L2.164"
					( objectStatus "dqs1p" )
				)
				( pin "J6L2.174"
					( objectStatus "dqs2n" )
				)
				( pin "J6L2.175"
					( objectStatus "dqs2p" )
				)
				( pin "J6L2.185"
					( objectStatus "dqs3n" )
				)
				( pin "J6L2.186"
					( objectStatus "dqs3p" )
				)
				( pin "J6L2.244"
					( objectStatus "dqs4n" )
				)
				( pin "J6L2.245"
					( objectStatus "dqs4p" )
				)
				( pin "J6L2.255"
					( objectStatus "dqs5n" )
				)
				( pin "J6L2.256"
					( objectStatus "dqs5p" )
				)
				( pin "J6L2.266"
					( objectStatus "dqs6n" )
				)
				( pin "J6L2.267"
					( objectStatus "dqs6p" )
				)
				( pin "J6L2.277"
					( objectStatus "dqs7n" )
				)
				( pin "J6L2.278"
					( objectStatus "dqs7p" )
				)
				( pin "J6L2.196"
					( objectStatus "dqs8n" )
				)
				( pin "J6L2.197"
					( objectStatus "dqs8p" )
				)
				( pin "J6L2.8"
					( objectStatus "dqs9n" )
				)
				( pin "J6L2.7"
					( objectStatus "dqs9p" )
				)
				( pin "J6L2.19"
					( objectStatus "dqs10n" )
				)
				( pin "J6L2.18"
					( objectStatus "dqs10p" )
				)
				( pin "J6L2.30"
					( objectStatus "dqs11n" )
				)
				( pin "J6L2.29"
					( objectStatus "dqs11p" )
				)
				( pin "J6L2.41"
					( objectStatus "dqs12n" )
				)
				( pin "J6L2.40"
					( objectStatus "dqs12p" )
				)
				( pin "J6L2.100"
					( objectStatus "dqs13n" )
				)
				( pin "J6L2.99"
					( objectStatus "dqs13p" )
				)
				( pin "J6L2.111"
					( objectStatus "dqs14n" )
				)
				( pin "J6L2.110"
					( objectStatus "dqs14p" )
				)
				( pin "J6L2.122"
					( objectStatus "dqs15n" )
				)
				( pin "J6L2.121"
					( objectStatus "dqs15p" )
				)
				( pin "J6L2.133"
					( objectStatus "dqs16n" )
				)
				( pin "J6L2.132"
					( objectStatus "dqs16p" )
				)
				( pin "J6L2.52"
					( objectStatus "dqs17n" )
				)
				( pin "J6L2.51"
					( objectStatus "dqs17p" )
				)
			)
			( gate "J6L2"
				( objectStatus "@baseboard_fab2_lib.baseboard_fab2(sch_1):page52_i138" )
				( pin "J6L2.283"
					( objectStatus "vss(0)" )
				)
				( pin "J6L2.281"
					( objectStatus "vss(1)" )
				)
				( pin "J6L2.279"
					( objectStatus "vss(2)" )
				)
				( pin "J6L2.276"
					( objectStatus "vss(3)" )
				)
				( pin "J6L2.274"
					( objectStatus "vss(4)" )
				)
				( pin "J6L2.272"
					( objectStatus "vss(5)" )
				)
				( pin "J6L2.270"
					( objectStatus "vss(6)" )
				)
				( pin "J6L2.268"
					( objectStatus "vss(7)" )
				)
				( pin "J6L2.265"
					( objectStatus "vss(8)" )
				)
				( pin "J6L2.263"
					( objectStatus "vss(9)" )
				)
				( pin "J6L2.261"
					( objectStatus "vss(10)" )
				)
				( pin "J6L2.259"
					( objectStatus "vss(11)" )
				)
				( pin "J6L2.257"
					( objectStatus "vss(12)" )
				)
				( pin "J6L2.254"
					( objectStatus "vss(13)" )
				)
				( pin "J6L2.252"
					( objectStatus "vss(14)" )
				)
				( pin "J6L2.250"
					( objectStatus "vss(15)" )
				)
				( pin "J6L2.248"
					( objectStatus "vss(16)" )
				)
				( pin "J6L2.246"
					( objectStatus "vss(17)" )
				)
				( pin "J6L2.243"
					( objectStatus "vss(18)" )
				)
				( pin "J6L2.241"
					( objectStatus "vss(19)" )
				)
				( pin "J6L2.239"
					( objectStatus "vss(20)" )
				)
				( pin "J6L2.202"
					( objectStatus "vss(21)" )
				)
				( pin "J6L2.200"
					( objectStatus "vss(22)" )
				)
				( pin "J6L2.198"
					( objectStatus "vss(23)" )
				)
				( pin "J6L2.195"
					( objectStatus "vss(24)" )
				)
				( pin "J6L2.193"
					( objectStatus "vss(25)" )
				)
				( pin "J6L2.191"
					( objectStatus "vss(26)" )
				)
				( pin "J6L2.189"
					( objectStatus "vss(27)" )
				)
				( pin "J6L2.187"
					( objectStatus "vss(28)" )
				)
				( pin "J6L2.184"
					( objectStatus "vss(29)" )
				)
				( pin "J6L2.182"
					( objectStatus "vss(30)" )
				)
				( pin "J6L2.180"
					( objectStatus "vss(31)" )
				)
				( pin "J6L2.178"
					( objectStatus "vss(32)" )
				)
				( pin "J6L2.176"
					( objectStatus "vss(33)" )
				)
				( pin "J6L2.173"
					( objectStatus "vss(34)" )
				)
				( pin "J6L2.171"
					( objectStatus "vss(35)" )
				)
				( pin "J6L2.169"
					( objectStatus "vss(36)" )
				)
				( pin "J6L2.167"
					( objectStatus "vss(37)" )
				)
				( pin "J6L2.165"
					( objectStatus "vss(38)" )
				)
				( pin "J6L2.162"
					( objectStatus "vss(39)" )
				)
				( pin "J6L2.160"
					( objectStatus "vss(40)" )
				)
				( pin "J6L2.158"
					( objectStatus "vss(41)" )
				)
				( pin "J6L2.156"
					( objectStatus "vss(42)" )
				)
				( pin "J6L2.154"
					( objectStatus "vss(43)" )
				)
				( pin "J6L2.151"
					( objectStatus "vss(44)" )
				)
				( pin "J6L2.149"
					( objectStatus "vss(45)" )
				)
				( pin "J6L2.147"
					( objectStatus "vss(46)" )
				)
				( pin "J6L2.138"
					( objectStatus "vss(47)" )
				)
				( pin "J6L2.136"
					( objectStatus "vss(48)" )
				)
				( pin "J6L2.134"
					( objectStatus "vss(49)" )
				)
				( pin "J6L2.131"
					( objectStatus "vss(50)" )
				)
				( pin "J6L2.129"
					( objectStatus "vss(51)" )
				)
				( pin "J6L2.127"
					( objectStatus "vss(52)" )
				)
				( pin "J6L2.125"
					( objectStatus "vss(53)" )
				)
				( pin "J6L2.123"
					( objectStatus "vss(54)" )
				)
				( pin "J6L2.120"
					( objectStatus "vss(55)" )
				)
				( pin "J6L2.118"
					( objectStatus "vss(56)" )
				)
				( pin "J6L2.116"
					( objectStatus "vss(57)" )
				)
				( pin "J6L2.114"
					( objectStatus "vss(58)" )
				)
				( pin "J6L2.112"
					( objectStatus "vss(59)" )
				)
				( pin "J6L2.109"
					( objectStatus "vss(60)" )
				)
				( pin "J6L2.107"
					( objectStatus "vss(61)" )
				)
				( pin "J6L2.105"
					( objectStatus "vss(62)" )
				)
				( pin "J6L2.103"
					( objectStatus "vss(63)" )
				)
				( pin "J6L2.101"
					( objectStatus "vss(64)" )
				)
				( pin "J6L2.98"
					( objectStatus "vss(65)" )
				)
				( pin "J6L2.96"
					( objectStatus "vss(66)" )
				)
				( pin "J6L2.94"
					( objectStatus "vss(67)" )
				)
				( pin "J6L2.57"
					( objectStatus "vss(68)" )
				)
				( pin "J6L2.55"
					( objectStatus "vss(69)" )
				)
				( pin "J6L2.53"
					( objectStatus "vss(70)" )
				)
				( pin "J6L2.50"
					( objectStatus "vss(71)" )
				)
				( pin "J6L2.48"
					( objectStatus "vss(72)" )
				)
				( pin "J6L2.46"
					( objectStatus "vss(73)" )
				)
				( pin "J6L2.44"
					( objectStatus "vss(74)" )
				)
				( pin "J6L2.42"
					( objectStatus "vss(75)" )
				)
				( pin "J6L2.39"
					( objectStatus "vss(76)" )
				)
				( pin "J6L2.37"
					( objectStatus "vss(77)" )
				)
				( pin "J6L2.35"
					( objectStatus "vss(78)" )
				)
				( pin "J6L2.33"
					( objectStatus "vss(79)" )
				)
				( pin "J6L2.31"
					( objectStatus "vss(80)" )
				)
				( pin "J6L2.28"
					( objectStatus "vss(81)" )
				)
				( pin "J6L2.26"
					( objectStatus "vss(82)" )
				)
				( pin "J6L2.24"
					( objectStatus "vss(83)" )
				)
				( pin "J6L2.22"
					( objectStatus "vss(84)" )
				)
				( pin "J6L2.20"
					( objectStatus "vss(85)" )
				)
				( pin "J6L2.17"
					( objectStatus "vss(86)" )
				)
				( pin "J6L2.15"
					( objectStatus "vss(87)" )
				)
				( pin "J6L2.13"
					( objectStatus "vss(88)" )
				)
				( pin "J6L2.11"
					( objectStatus "vss(89)" )
				)
				( pin "J6L2.9"
					( objectStatus "vss(90)" )
				)
				( pin "J6L2.6"
					( objectStatus "vss(91)" )
				)
				( pin "J6L2.4"
					( objectStatus "vss(92)" )
				)
				( pin "J6L2.2"
					( objectStatus "vss(93)" )
				)
			)
			( gate "J4A1"
				( objectStatus "@baseboard_fab2_lib.baseboard_fab2(sch_1):page53_i43" )
				( pin "J4A1.283"
					( objectStatus "vss(0)" )
				)
				( pin "J4A1.281"
					( objectStatus "vss(1)" )
				)
				( pin "J4A1.279"
					( objectStatus "vss(2)" )
				)
				( pin "J4A1.276"
					( objectStatus "vss(3)" )
				)
				( pin "J4A1.274"
					( objectStatus "vss(4)" )
				)
				( pin "J4A1.272"
					( objectStatus "vss(5)" )
				)
				( pin "J4A1.270"
					( objectStatus "vss(6)" )
				)
				( pin "J4A1.268"
					( objectStatus "vss(7)" )
				)
				( pin "J4A1.265"
					( objectStatus "vss(8)" )
				)
				( pin "J4A1.263"
					( objectStatus "vss(9)" )
				)
				( pin "J4A1.261"
					( objectStatus "vss(10)" )
				)
				( pin "J4A1.259"
					( objectStatus "vss(11)" )
				)
				( pin "J4A1.257"
					( objectStatus "vss(12)" )
				)
				( pin "J4A1.254"
					( objectStatus "vss(13)" )
				)
				( pin "J4A1.252"
					( objectStatus "vss(14)" )
				)
				( pin "J4A1.250"
					( objectStatus "vss(15)" )
				)
				( pin "J4A1.248"
					( objectStatus "vss(16)" )
				)
				( pin "J4A1.246"
					( objectStatus "vss(17)" )
				)
				( pin "J4A1.243"
					( objectStatus "vss(18)" )
				)
				( pin "J4A1.241"
					( objectStatus "vss(19)" )
				)
				( pin "J4A1.239"
					( objectStatus "vss(20)" )
				)
				( pin "J4A1.202"
					( objectStatus "vss(21)" )
				)
				( pin "J4A1.200"
					( objectStatus "vss(22)" )
				)
				( pin "J4A1.198"
					( objectStatus "vss(23)" )
				)
				( pin "J4A1.195"
					( objectStatus "vss(24)" )
				)
				( pin "J4A1.193"
					( objectStatus "vss(25)" )
				)
				( pin "J4A1.191"
					( objectStatus "vss(26)" )
				)
				( pin "J4A1.189"
					( objectStatus "vss(27)" )
				)
				( pin "J4A1.187"
					( objectStatus "vss(28)" )
				)
				( pin "J4A1.184"
					( objectStatus "vss(29)" )
				)
				( pin "J4A1.182"
					( objectStatus "vss(30)" )
				)
				( pin "J4A1.180"
					( objectStatus "vss(31)" )
				)
				( pin "J4A1.178"
					( objectStatus "vss(32)" )
				)
				( pin "J4A1.176"
					( objectStatus "vss(33)" )
				)
				( pin "J4A1.173"
					( objectStatus "vss(34)" )
				)
				( pin "J4A1.171"
					( objectStatus "vss(35)" )
				)
				( pin "J4A1.169"
					( objectStatus "vss(36)" )
				)
				( pin "J4A1.167"
					( objectStatus "vss(37)" )
				)
				( pin "J4A1.165"
					( objectStatus "vss(38)" )
				)
				( pin "J4A1.162"
					( objectStatus "vss(39)" )
				)
				( pin "J4A1.160"
					( objectStatus "vss(40)" )
				)
				( pin "J4A1.158"
					( objectStatus "vss(41)" )
				)
				( pin "J4A1.156"
					( objectStatus "vss(42)" )
				)
				( pin "J4A1.154"
					( objectStatus "vss(43)" )
				)
				( pin "J4A1.151"
					( objectStatus "vss(44)" )
				)
				( pin "J4A1.149"
					( objectStatus "vss(45)" )
				)
				( pin "J4A1.147"
					( objectStatus "vss(46)" )
				)
				( pin "J4A1.138"
					( objectStatus "vss(47)" )
				)
				( pin "J4A1.136"
					( objectStatus "vss(48)" )
				)
				( pin "J4A1.134"
					( objectStatus "vss(49)" )
				)
				( pin "J4A1.131"
					( objectStatus "vss(50)" )
				)
				( pin "J4A1.129"
					( objectStatus "vss(51)" )
				)
				( pin "J4A1.127"
					( objectStatus "vss(52)" )
				)
				( pin "J4A1.125"
					( objectStatus "vss(53)" )
				)
				( pin "J4A1.123"
					( objectStatus "vss(54)" )
				)
				( pin "J4A1.120"
					( objectStatus "vss(55)" )
				)
				( pin "J4A1.118"
					( objectStatus "vss(56)" )
				)
				( pin "J4A1.116"
					( objectStatus "vss(57)" )
				)
				( pin "J4A1.114"
					( objectStatus "vss(58)" )
				)
				( pin "J4A1.112"
					( objectStatus "vss(59)" )
				)
				( pin "J4A1.109"
					( objectStatus "vss(60)" )
				)
				( pin "J4A1.107"
					( objectStatus "vss(61)" )
				)
				( pin "J4A1.105"
					( objectStatus "vss(62)" )
				)
				( pin "J4A1.103"
					( objectStatus "vss(63)" )
				)
				( pin "J4A1.101"
					( objectStatus "vss(64)" )
				)
				( pin "J4A1.98"
					( objectStatus "vss(65)" )
				)
				( pin "J4A1.96"
					( objectStatus "vss(66)" )
				)
				( pin "J4A1.94"
					( objectStatus "vss(67)" )
				)
				( pin "J4A1.57"
					( objectStatus "vss(68)" )
				)
				( pin "J4A1.55"
					( objectStatus "vss(69)" )
				)
				( pin "J4A1.53"
					( objectStatus "vss(70)" )
				)
				( pin "J4A1.50"
					( objectStatus "vss(71)" )
				)
				( pin "J4A1.48"
					( objectStatus "vss(72)" )
				)
				( pin "J4A1.46"
					( objectStatus "vss(73)" )
				)
				( pin "J4A1.44"
					( objectStatus "vss(74)" )
				)
				( pin "J4A1.42"
					( objectStatus "vss(75)" )
				)
				( pin "J4A1.39"
					( objectStatus "vss(76)" )
				)
				( pin "J4A1.37"
					( objectStatus "vss(77)" )
				)
				( pin "J4A1.35"
					( objectStatus "vss(78)" )
				)
				( pin "J4A1.33"
					( objectStatus "vss(79)" )
				)
				( pin "J4A1.31"
					( objectStatus "vss(80)" )
				)
				( pin "J4A1.28"
					( objectStatus "vss(81)" )
				)
				( pin "J4A1.26"
					( objectStatus "vss(82)" )
				)
				( pin "J4A1.24"
					( objectStatus "vss(83)" )
				)
				( pin "J4A1.22"
					( objectStatus "vss(84)" )
				)
				( pin "J4A1.20"
					( objectStatus "vss(85)" )
				)
				( pin "J4A1.17"
					( objectStatus "vss(86)" )
				)
				( pin "J4A1.15"
					( objectStatus "vss(87)" )
				)
				( pin "J4A1.13"
					( objectStatus "vss(88)" )
				)
				( pin "J4A1.11"
					( objectStatus "vss(89)" )
				)
				( pin "J4A1.9"
					( objectStatus "vss(90)" )
				)
				( pin "J4A1.6"
					( objectStatus "vss(91)" )
				)
				( pin "J4A1.4"
					( objectStatus "vss(92)" )
				)
				( pin "J4A1.2"
					( objectStatus "vss(93)" )
				)
			)
			( gate "J4A1"
				( objectStatus "@baseboard_fab2_lib.baseboard_fab2(sch_1):page53_i66" )
				( pin "J4A1.152"
					( objectStatus "dqs0n" )
				)
				( pin "J4A1.153"
					( objectStatus "dqs0p" )
				)
				( pin "J4A1.163"
					( objectStatus "dqs1n" )
				)
				( pin "J4A1.164"
					( objectStatus "dqs1p" )
				)
				( pin "J4A1.174"
					( objectStatus "dqs2n" )
				)
				( pin "J4A1.175"
					( objectStatus "dqs2p" )
				)
				( pin "J4A1.185"
					( objectStatus "dqs3n" )
				)
				( pin "J4A1.186"
					( objectStatus "dqs3p" )
				)
				( pin "J4A1.244"
					( objectStatus "dqs4n" )
				)
				( pin "J4A1.245"
					( objectStatus "dqs4p" )
				)
				( pin "J4A1.255"
					( objectStatus "dqs5n" )
				)
				( pin "J4A1.256"
					( objectStatus "dqs5p" )
				)
				( pin "J4A1.266"
					( objectStatus "dqs6n" )
				)
				( pin "J4A1.267"
					( objectStatus "dqs6p" )
				)
				( pin "J4A1.277"
					( objectStatus "dqs7n" )
				)
				( pin "J4A1.278"
					( objectStatus "dqs7p" )
				)
				( pin "J4A1.196"
					( objectStatus "dqs8n" )
				)
				( pin "J4A1.197"
					( objectStatus "dqs8p" )
				)
				( pin "J4A1.8"
					( objectStatus "dqs9n" )
				)
				( pin "J4A1.7"
					( objectStatus "dqs9p" )
				)
				( pin "J4A1.19"
					( objectStatus "dqs10n" )
				)
				( pin "J4A1.18"
					( objectStatus "dqs10p" )
				)
				( pin "J4A1.30"
					( objectStatus "dqs11n" )
				)
				( pin "J4A1.29"
					( objectStatus "dqs11p" )
				)
				( pin "J4A1.41"
					( objectStatus "dqs12n" )
				)
				( pin "J4A1.40"
					( objectStatus "dqs12p" )
				)
				( pin "J4A1.100"
					( objectStatus "dqs13n" )
				)
				( pin "J4A1.99"
					( objectStatus "dqs13p" )
				)
				( pin "J4A1.111"
					( objectStatus "dqs14n" )
				)
				( pin "J4A1.110"
					( objectStatus "dqs14p" )
				)
				( pin "J4A1.122"
					( objectStatus "dqs15n" )
				)
				( pin "J4A1.121"
					( objectStatus "dqs15p" )
				)
				( pin "J4A1.133"
					( objectStatus "dqs16n" )
				)
				( pin "J4A1.132"
					( objectStatus "dqs16p" )
				)
				( pin "J4A1.52"
					( objectStatus "dqs17n" )
				)
				( pin "J4A1.51"
					( objectStatus "dqs17p" )
				)
			)
			( gate "J4A1"
				( objectStatus "@baseboard_fab2_lib.baseboard_fab2(sch_1):page53_i111" )
				( pin "J4A1.79"
					( objectStatus "a0" )
				)
				( pin "J4A1.72"
					( objectStatus "a1" )
				)
				( pin "J4A1.216"
					( objectStatus "a2" )
				)
				( pin "J4A1.71"
					( objectStatus "a3" )
				)
				( pin "J4A1.214"
					( objectStatus "a4" )
				)
				( pin "J4A1.213"
					( objectStatus "a5" )
				)
				( pin "J4A1.69"
					( objectStatus "a6" )
				)
				( pin "J4A1.211"
					( objectStatus "a7" )
				)
				( pin "J4A1.68"
					( objectStatus "a8" )
				)
				( pin "J4A1.66"
					( objectStatus "a9" )
				)
				( pin "J4A1.225"
					( objectStatus "a10" )
				)
				( pin "J4A1.210"
					( objectStatus "a11" )
				)
				( pin "J4A1.65"
					( objectStatus "a12" )
				)
				( pin "J4A1.232"
					( objectStatus "a13" )
				)
				( pin "J4A1.228"
					( objectStatus "a14_we_n" )
				)
				( pin "J4A1.86"
					( objectStatus "a15_cas_n" )
				)
				( pin "J4A1.82"
					( objectStatus "a16_ras_n" )
				)
				( pin "J4A1.234"
					( objectStatus "a17" )
				)
				( pin "J4A1.62"
					( objectStatus "act_n" )
				)
				( pin "J4A1.208"
					( objectStatus "alert_n" )
				)
				( pin "J4A1.81"
					( objectStatus "ba(0)" )
				)
				( pin "J4A1.224"
					( objectStatus "ba(1)" )
				)
				( pin "J4A1.63"
					( objectStatus "bg(0)" )
				)
				( pin "J4A1.207"
					( objectStatus "bg(1)" )
				)
				( pin "J4A1.235"
					( objectStatus "c(2)" )
				)
				( pin "J4A1.49"
					( objectStatus "cb(0)" )
				)
				( pin "J4A1.194"
					( objectStatus "cb(1)" )
				)
				( pin "J4A1.56"
					( objectStatus "cb(2)" )
				)
				( pin "J4A1.201"
					( objectStatus "cb(3)" )
				)
				( pin "J4A1.47"
					( objectStatus "cb(4)" )
				)
				( pin "J4A1.192"
					( objectStatus "cb(5)" )
				)
				( pin "J4A1.54"
					( objectStatus "cb(6)" )
				)
				( pin "J4A1.199"
					( objectStatus "cb(7)" )
				)
				( pin "J4A1.75"
					( objectStatus "ck0n" )
				)
				( pin "J4A1.74"
					( objectStatus "ck0p" )
				)
				( pin "J4A1.219"
					( objectStatus "ck1n" )
				)
				( pin "J4A1.218"
					( objectStatus "ck1p" )
				)
				( pin "J4A1.60"
					( objectStatus "cke(0)" )
				)
				( pin "J4A1.203"
					( objectStatus "cke(1)" )
				)
				( pin "J4A1.5"
					( objectStatus "dq(0)" )
				)
				( pin "J4A1.150"
					( objectStatus "dq(1)" )
				)
				( pin "J4A1.12"
					( objectStatus "dq(2)" )
				)
				( pin "J4A1.157"
					( objectStatus "dq(3)" )
				)
				( pin "J4A1.3"
					( objectStatus "dq(4)" )
				)
				( pin "J4A1.148"
					( objectStatus "dq(5)" )
				)
				( pin "J4A1.10"
					( objectStatus "dq(6)" )
				)
				( pin "J4A1.155"
					( objectStatus "dq(7)" )
				)
				( pin "J4A1.16"
					( objectStatus "dq(8)" )
				)
				( pin "J4A1.161"
					( objectStatus "dq(9)" )
				)
				( pin "J4A1.23"
					( objectStatus "dq(10)" )
				)
				( pin "J4A1.168"
					( objectStatus "dq(11)" )
				)
				( pin "J4A1.14"
					( objectStatus "dq(12)" )
				)
				( pin "J4A1.159"
					( objectStatus "dq(13)" )
				)
				( pin "J4A1.21"
					( objectStatus "dq(14)" )
				)
				( pin "J4A1.166"
					( objectStatus "dq(15)" )
				)
				( pin "J4A1.27"
					( objectStatus "dq(16)" )
				)
				( pin "J4A1.172"
					( objectStatus "dq(17)" )
				)
				( pin "J4A1.34"
					( objectStatus "dq(18)" )
				)
				( pin "J4A1.179"
					( objectStatus "dq(19)" )
				)
				( pin "J4A1.25"
					( objectStatus "dq(20)" )
				)
				( pin "J4A1.170"
					( objectStatus "dq(21)" )
				)
				( pin "J4A1.32"
					( objectStatus "dq(22)" )
				)
				( pin "J4A1.177"
					( objectStatus "dq(23)" )
				)
				( pin "J4A1.38"
					( objectStatus "dq(24)" )
				)
				( pin "J4A1.183"
					( objectStatus "dq(25)" )
				)
				( pin "J4A1.45"
					( objectStatus "dq(26)" )
				)
				( pin "J4A1.190"
					( objectStatus "dq(27)" )
				)
				( pin "J4A1.36"
					( objectStatus "dq(28)" )
				)
				( pin "J4A1.181"
					( objectStatus "dq(29)" )
				)
				( pin "J4A1.43"
					( objectStatus "dq(30)" )
				)
				( pin "J4A1.188"
					( objectStatus "dq(31)" )
				)
				( pin "J4A1.97"
					( objectStatus "dq(32)" )
				)
				( pin "J4A1.242"
					( objectStatus "dq(33)" )
				)
				( pin "J4A1.104"
					( objectStatus "dq(34)" )
				)
				( pin "J4A1.249"
					( objectStatus "dq(35)" )
				)
				( pin "J4A1.95"
					( objectStatus "dq(36)" )
				)
				( pin "J4A1.240"
					( objectStatus "dq(37)" )
				)
				( pin "J4A1.102"
					( objectStatus "dq(38)" )
				)
				( pin "J4A1.247"
					( objectStatus "dq(39)" )
				)
				( pin "J4A1.108"
					( objectStatus "dq(40)" )
				)
				( pin "J4A1.253"
					( objectStatus "dq(41)" )
				)
				( pin "J4A1.115"
					( objectStatus "dq(42)" )
				)
				( pin "J4A1.260"
					( objectStatus "dq(43)" )
				)
				( pin "J4A1.106"
					( objectStatus "dq(44)" )
				)
				( pin "J4A1.251"
					( objectStatus "dq(45)" )
				)
				( pin "J4A1.113"
					( objectStatus "dq(46)" )
				)
				( pin "J4A1.258"
					( objectStatus "dq(47)" )
				)
				( pin "J4A1.119"
					( objectStatus "dq(48)" )
				)
				( pin "J4A1.264"
					( objectStatus "dq(49)" )
				)
				( pin "J4A1.126"
					( objectStatus "dq(50)" )
				)
				( pin "J4A1.271"
					( objectStatus "dq(51)" )
				)
				( pin "J4A1.117"
					( objectStatus "dq(52)" )
				)
				( pin "J4A1.262"
					( objectStatus "dq(53)" )
				)
				( pin "J4A1.124"
					( objectStatus "dq(54)" )
				)
				( pin "J4A1.269"
					( objectStatus "dq(55)" )
				)
				( pin "J4A1.130"
					( objectStatus "dq(56)" )
				)
				( pin "J4A1.275"
					( objectStatus "dq(57)" )
				)
				( pin "J4A1.137"
					( objectStatus "dq(58)" )
				)
				( pin "J4A1.282"
					( objectStatus "dq(59)" )
				)
				( pin "J4A1.128"
					( objectStatus "dq(60)" )
				)
				( pin "J4A1.273"
					( objectStatus "dq(61)" )
				)
				( pin "J4A1.135"
					( objectStatus "dq(62)" )
				)
				( pin "J4A1.280"
					( objectStatus "dq(63)" )
				)
				( pin "J4A1.78"
					( objectStatus "event_n" )
				)
				( pin "J4A1.87"
					( objectStatus "odt(0)" )
				)
				( pin "J4A1.91"
					( objectStatus "odt(1)" )
				)
				( pin "J4A1.222"
					( objectStatus "par" )
				)
				( pin "J4A1.58"
					( objectStatus "reset_n" )
				)
				( pin "J4A1.205"
					( objectStatus "rfu(0)" )
				)
				( pin "J4A1.227"
					( objectStatus "rfu(1)" )
				)
				( pin "J4A1.144"
					( objectStatus "rfu(2)" )
				)
				( pin "J4A1.84"
					( objectStatus "s0_n" )
				)
				( pin "J4A1.89"
					( objectStatus "s1_n" )
				)
				( pin "J4A1.93"
					( objectStatus "s2_n_c(0)" )
				)
				( pin "J4A1.237"
					( objectStatus "s3_n_c(1)" )
				)
				( pin "J4A1.139"
					( objectStatus "sa(0)" )
				)
				( pin "J4A1.140"
					( objectStatus "sa(1)" )
				)
				( pin "J4A1.238"
					( objectStatus "sa(2)" )
				)
				( pin "J4A1.230"
					( objectStatus "save_n_nc" )
				)
				( pin "J4A1.141"
					( objectStatus "scl" )
				)
				( pin "J4A1.285"
					( objectStatus "sda" )
				)
				( pin "J4A1.284"
					( objectStatus "vddspd" )
				)
				( pin "J4A1.146"
					( objectStatus "vrefca" )
				)
			)
			( gate "J4A1"
				( objectStatus "@baseboard_fab2_lib.baseboard_fab2(sch_1):page53_i171" )
				( pin "J4A1.145"
					( objectStatus "\12v\(0)" )
				)
				( pin "J4A1.1"
					( objectStatus "\12v\(1)" )
				)
				( pin "J4A1.236"
					( objectStatus "vdd(0)" )
				)
				( pin "J4A1.233"
					( objectStatus "vdd(1)" )
				)
				( pin "J4A1.231"
					( objectStatus "vdd(2)" )
				)
				( pin "J4A1.229"
					( objectStatus "vdd(3)" )
				)
				( pin "J4A1.226"
					( objectStatus "vdd(4)" )
				)
				( pin "J4A1.223"
					( objectStatus "vdd(5)" )
				)
				( pin "J4A1.220"
					( objectStatus "vdd(6)" )
				)
				( pin "J4A1.217"
					( objectStatus "vdd(7)" )
				)
				( pin "J4A1.215"
					( objectStatus "vdd(8)" )
				)
				( pin "J4A1.212"
					( objectStatus "vdd(9)" )
				)
				( pin "J4A1.209"
					( objectStatus "vdd(10)" )
				)
				( pin "J4A1.206"
					( objectStatus "vdd(11)" )
				)
				( pin "J4A1.204"
					( objectStatus "vdd(12)" )
				)
				( pin "J4A1.92"
					( objectStatus "vdd(13)" )
				)
				( pin "J4A1.90"
					( objectStatus "vdd(14)" )
				)
				( pin "J4A1.88"
					( objectStatus "vdd(15)" )
				)
				( pin "J4A1.85"
					( objectStatus "vdd(16)" )
				)
				( pin "J4A1.83"
					( objectStatus "vdd(17)" )
				)
				( pin "J4A1.80"
					( objectStatus "vdd(18)" )
				)
				( pin "J4A1.76"
					( objectStatus "vdd(19)" )
				)
				( pin "J4A1.73"
					( objectStatus "vdd(20)" )
				)
				( pin "J4A1.70"
					( objectStatus "vdd(21)" )
				)
				( pin "J4A1.67"
					( objectStatus "vdd(22)" )
				)
				( pin "J4A1.64"
					( objectStatus "vdd(23)" )
				)
				( pin "J4A1.61"
					( objectStatus "vdd(24)" )
				)
				( pin "J4A1.59"
					( objectStatus "vdd(25)" )
				)
				( pin "J4A1.287"
					( objectStatus "vpp(0)" )
				)
				( pin "J4A1.286"
					( objectStatus "vpp(1)" )
				)
				( pin "J4A1.288"
					( objectStatus "vpp(2)" )
				)
				( pin "J4A1.143"
					( objectStatus "vpp(3)" )
				)
				( pin "J4A1.142"
					( objectStatus "vpp(4)" )
				)
				( pin "J4A1.221"
					( objectStatus "vtt(0)" )
				)
				( pin "J4A1.77"
					( objectStatus "vtt(1)" )
				)
			)
			( gate "C6L1"
				( objectStatus "@baseboard_fab2_lib.baseboard_fab2(sch_1):page53_i178" )
				( pin "C6L1.1"
					( objectStatus "a" )
				)
				( pin "C6L1.2"
					( objectStatus "b" )
				)
			)
			( gate "J6L1"
				( objectStatus "@baseboard_fab2_lib.baseboard_fab2(sch_1):page54_i43" )
				( pin "J6L1.283"
					( objectStatus "vss(0)" )
				)
				( pin "J6L1.281"
					( objectStatus "vss(1)" )
				)
				( pin "J6L1.279"
					( objectStatus "vss(2)" )
				)
				( pin "J6L1.276"
					( objectStatus "vss(3)" )
				)
				( pin "J6L1.274"
					( objectStatus "vss(4)" )
				)
				( pin "J6L1.272"
					( objectStatus "vss(5)" )
				)
				( pin "J6L1.270"
					( objectStatus "vss(6)" )
				)
				( pin "J6L1.268"
					( objectStatus "vss(7)" )
				)
				( pin "J6L1.265"
					( objectStatus "vss(8)" )
				)
				( pin "J6L1.263"
					( objectStatus "vss(9)" )
				)
				( pin "J6L1.261"
					( objectStatus "vss(10)" )
				)
				( pin "J6L1.259"
					( objectStatus "vss(11)" )
				)
				( pin "J6L1.257"
					( objectStatus "vss(12)" )
				)
				( pin "J6L1.254"
					( objectStatus "vss(13)" )
				)
				( pin "J6L1.252"
					( objectStatus "vss(14)" )
				)
				( pin "J6L1.250"
					( objectStatus "vss(15)" )
				)
				( pin "J6L1.248"
					( objectStatus "vss(16)" )
				)
				( pin "J6L1.246"
					( objectStatus "vss(17)" )
				)
				( pin "J6L1.243"
					( objectStatus "vss(18)" )
				)
				( pin "J6L1.241"
					( objectStatus "vss(19)" )
				)
				( pin "J6L1.239"
					( objectStatus "vss(20)" )
				)
				( pin "J6L1.202"
					( objectStatus "vss(21)" )
				)
				( pin "J6L1.200"
					( objectStatus "vss(22)" )
				)
				( pin "J6L1.198"
					( objectStatus "vss(23)" )
				)
				( pin "J6L1.195"
					( objectStatus "vss(24)" )
				)
				( pin "J6L1.193"
					( objectStatus "vss(25)" )
				)
				( pin "J6L1.191"
					( objectStatus "vss(26)" )
				)
				( pin "J6L1.189"
					( objectStatus "vss(27)" )
				)
				( pin "J6L1.187"
					( objectStatus "vss(28)" )
				)
				( pin "J6L1.184"
					( objectStatus "vss(29)" )
				)
				( pin "J6L1.182"
					( objectStatus "vss(30)" )
				)
				( pin "J6L1.180"
					( objectStatus "vss(31)" )
				)
				( pin "J6L1.178"
					( objectStatus "vss(32)" )
				)
				( pin "J6L1.176"
					( objectStatus "vss(33)" )
				)
				( pin "J6L1.173"
					( objectStatus "vss(34)" )
				)
				( pin "J6L1.171"
					( objectStatus "vss(35)" )
				)
				( pin "J6L1.169"
					( objectStatus "vss(36)" )
				)
				( pin "J6L1.167"
					( objectStatus "vss(37)" )
				)
				( pin "J6L1.165"
					( objectStatus "vss(38)" )
				)
				( pin "J6L1.162"
					( objectStatus "vss(39)" )
				)
				( pin "J6L1.160"
					( objectStatus "vss(40)" )
				)
				( pin "J6L1.158"
					( objectStatus "vss(41)" )
				)
				( pin "J6L1.156"
					( objectStatus "vss(42)" )
				)
				( pin "J6L1.154"
					( objectStatus "vss(43)" )
				)
				( pin "J6L1.151"
					( objectStatus "vss(44)" )
				)
				( pin "J6L1.149"
					( objectStatus "vss(45)" )
				)
				( pin "J6L1.147"
					( objectStatus "vss(46)" )
				)
				( pin "J6L1.138"
					( objectStatus "vss(47)" )
				)
				( pin "J6L1.136"
					( objectStatus "vss(48)" )
				)
				( pin "J6L1.134"
					( objectStatus "vss(49)" )
				)
				( pin "J6L1.131"
					( objectStatus "vss(50)" )
				)
				( pin "J6L1.129"
					( objectStatus "vss(51)" )
				)
				( pin "J6L1.127"
					( objectStatus "vss(52)" )
				)
				( pin "J6L1.125"
					( objectStatus "vss(53)" )
				)
				( pin "J6L1.123"
					( objectStatus "vss(54)" )
				)
				( pin "J6L1.120"
					( objectStatus "vss(55)" )
				)
				( pin "J6L1.118"
					( objectStatus "vss(56)" )
				)
				( pin "J6L1.116"
					( objectStatus "vss(57)" )
				)
				( pin "J6L1.114"
					( objectStatus "vss(58)" )
				)
				( pin "J6L1.112"
					( objectStatus "vss(59)" )
				)
				( pin "J6L1.109"
					( objectStatus "vss(60)" )
				)
				( pin "J6L1.107"
					( objectStatus "vss(61)" )
				)
				( pin "J6L1.105"
					( objectStatus "vss(62)" )
				)
				( pin "J6L1.103"
					( objectStatus "vss(63)" )
				)
				( pin "J6L1.101"
					( objectStatus "vss(64)" )
				)
				( pin "J6L1.98"
					( objectStatus "vss(65)" )
				)
				( pin "J6L1.96"
					( objectStatus "vss(66)" )
				)
				( pin "J6L1.94"
					( objectStatus "vss(67)" )
				)
				( pin "J6L1.57"
					( objectStatus "vss(68)" )
				)
				( pin "J6L1.55"
					( objectStatus "vss(69)" )
				)
				( pin "J6L1.53"
					( objectStatus "vss(70)" )
				)
				( pin "J6L1.50"
					( objectStatus "vss(71)" )
				)
				( pin "J6L1.48"
					( objectStatus "vss(72)" )
				)
				( pin "J6L1.46"
					( objectStatus "vss(73)" )
				)
				( pin "J6L1.44"
					( objectStatus "vss(74)" )
				)
				( pin "J6L1.42"
					( objectStatus "vss(75)" )
				)
				( pin "J6L1.39"
					( objectStatus "vss(76)" )
				)
				( pin "J6L1.37"
					( objectStatus "vss(77)" )
				)
				( pin "J6L1.35"
					( objectStatus "vss(78)" )
				)
				( pin "J6L1.33"
					( objectStatus "vss(79)" )
				)
				( pin "J6L1.31"
					( objectStatus "vss(80)" )
				)
				( pin "J6L1.28"
					( objectStatus "vss(81)" )
				)
				( pin "J6L1.26"
					( objectStatus "vss(82)" )
				)
				( pin "J6L1.24"
					( objectStatus "vss(83)" )
				)
				( pin "J6L1.22"
					( objectStatus "vss(84)" )
				)
				( pin "J6L1.20"
					( objectStatus "vss(85)" )
				)
				( pin "J6L1.17"
					( objectStatus "vss(86)" )
				)
				( pin "J6L1.15"
					( objectStatus "vss(87)" )
				)
				( pin "J6L1.13"
					( objectStatus "vss(88)" )
				)
				( pin "J6L1.11"
					( objectStatus "vss(89)" )
				)
				( pin "J6L1.9"
					( objectStatus "vss(90)" )
				)
				( pin "J6L1.6"
					( objectStatus "vss(91)" )
				)
				( pin "J6L1.4"
					( objectStatus "vss(92)" )
				)
				( pin "J6L1.2"
					( objectStatus "vss(93)" )
				)
			)
			( gate "J6L1"
				( objectStatus "@baseboard_fab2_lib.baseboard_fab2(sch_1):page54_i66" )
				( pin "J6L1.152"
					( objectStatus "dqs0n" )
				)
				( pin "J6L1.153"
					( objectStatus "dqs0p" )
				)
				( pin "J6L1.163"
					( objectStatus "dqs1n" )
				)
				( pin "J6L1.164"
					( objectStatus "dqs1p" )
				)
				( pin "J6L1.174"
					( objectStatus "dqs2n" )
				)
				( pin "J6L1.175"
					( objectStatus "dqs2p" )
				)
				( pin "J6L1.185"
					( objectStatus "dqs3n" )
				)
				( pin "J6L1.186"
					( objectStatus "dqs3p" )
				)
				( pin "J6L1.244"
					( objectStatus "dqs4n" )
				)
				( pin "J6L1.245"
					( objectStatus "dqs4p" )
				)
				( pin "J6L1.255"
					( objectStatus "dqs5n" )
				)
				( pin "J6L1.256"
					( objectStatus "dqs5p" )
				)
				( pin "J6L1.266"
					( objectStatus "dqs6n" )
				)
				( pin "J6L1.267"
					( objectStatus "dqs6p" )
				)
				( pin "J6L1.277"
					( objectStatus "dqs7n" )
				)
				( pin "J6L1.278"
					( objectStatus "dqs7p" )
				)
				( pin "J6L1.196"
					( objectStatus "dqs8n" )
				)
				( pin "J6L1.197"
					( objectStatus "dqs8p" )
				)
				( pin "J6L1.8"
					( objectStatus "dqs9n" )
				)
				( pin "J6L1.7"
					( objectStatus "dqs9p" )
				)
				( pin "J6L1.19"
					( objectStatus "dqs10n" )
				)
				( pin "J6L1.18"
					( objectStatus "dqs10p" )
				)
				( pin "J6L1.30"
					( objectStatus "dqs11n" )
				)
				( pin "J6L1.29"
					( objectStatus "dqs11p" )
				)
				( pin "J6L1.41"
					( objectStatus "dqs12n" )
				)
				( pin "J6L1.40"
					( objectStatus "dqs12p" )
				)
				( pin "J6L1.100"
					( objectStatus "dqs13n" )
				)
				( pin "J6L1.99"
					( objectStatus "dqs13p" )
				)
				( pin "J6L1.111"
					( objectStatus "dqs14n" )
				)
				( pin "J6L1.110"
					( objectStatus "dqs14p" )
				)
				( pin "J6L1.122"
					( objectStatus "dqs15n" )
				)
				( pin "J6L1.121"
					( objectStatus "dqs15p" )
				)
				( pin "J6L1.133"
					( objectStatus "dqs16n" )
				)
				( pin "J6L1.132"
					( objectStatus "dqs16p" )
				)
				( pin "J6L1.52"
					( objectStatus "dqs17n" )
				)
				( pin "J6L1.51"
					( objectStatus "dqs17p" )
				)
			)
			( gate "J6L1"
				( objectStatus "@baseboard_fab2_lib.baseboard_fab2(sch_1):page54_i111" )
				( pin "J6L1.79"
					( objectStatus "a0" )
				)
				( pin "J6L1.72"
					( objectStatus "a1" )
				)
				( pin "J6L1.216"
					( objectStatus "a2" )
				)
				( pin "J6L1.71"
					( objectStatus "a3" )
				)
				( pin "J6L1.214"
					( objectStatus "a4" )
				)
				( pin "J6L1.213"
					( objectStatus "a5" )
				)
				( pin "J6L1.69"
					( objectStatus "a6" )
				)
				( pin "J6L1.211"
					( objectStatus "a7" )
				)
				( pin "J6L1.68"
					( objectStatus "a8" )
				)
				( pin "J6L1.66"
					( objectStatus "a9" )
				)
				( pin "J6L1.225"
					( objectStatus "a10" )
				)
				( pin "J6L1.210"
					( objectStatus "a11" )
				)
				( pin "J6L1.65"
					( objectStatus "a12" )
				)
				( pin "J6L1.232"
					( objectStatus "a13" )
				)
				( pin "J6L1.228"
					( objectStatus "a14_we_n" )
				)
				( pin "J6L1.86"
					( objectStatus "a15_cas_n" )
				)
				( pin "J6L1.82"
					( objectStatus "a16_ras_n" )
				)
				( pin "J6L1.234"
					( objectStatus "a17" )
				)
				( pin "J6L1.62"
					( objectStatus "act_n" )
				)
				( pin "J6L1.208"
					( objectStatus "alert_n" )
				)
				( pin "J6L1.81"
					( objectStatus "ba(0)" )
				)
				( pin "J6L1.224"
					( objectStatus "ba(1)" )
				)
				( pin "J6L1.63"
					( objectStatus "bg(0)" )
				)
				( pin "J6L1.207"
					( objectStatus "bg(1)" )
				)
				( pin "J6L1.235"
					( objectStatus "c(2)" )
				)
				( pin "J6L1.49"
					( objectStatus "cb(0)" )
				)
				( pin "J6L1.194"
					( objectStatus "cb(1)" )
				)
				( pin "J6L1.56"
					( objectStatus "cb(2)" )
				)
				( pin "J6L1.201"
					( objectStatus "cb(3)" )
				)
				( pin "J6L1.47"
					( objectStatus "cb(4)" )
				)
				( pin "J6L1.192"
					( objectStatus "cb(5)" )
				)
				( pin "J6L1.54"
					( objectStatus "cb(6)" )
				)
				( pin "J6L1.199"
					( objectStatus "cb(7)" )
				)
				( pin "J6L1.75"
					( objectStatus "ck0n" )
				)
				( pin "J6L1.74"
					( objectStatus "ck0p" )
				)
				( pin "J6L1.219"
					( objectStatus "ck1n" )
				)
				( pin "J6L1.218"
					( objectStatus "ck1p" )
				)
				( pin "J6L1.60"
					( objectStatus "cke(0)" )
				)
				( pin "J6L1.203"
					( objectStatus "cke(1)" )
				)
				( pin "J6L1.5"
					( objectStatus "dq(0)" )
				)
				( pin "J6L1.150"
					( objectStatus "dq(1)" )
				)
				( pin "J6L1.12"
					( objectStatus "dq(2)" )
				)
				( pin "J6L1.157"
					( objectStatus "dq(3)" )
				)
				( pin "J6L1.3"
					( objectStatus "dq(4)" )
				)
				( pin "J6L1.148"
					( objectStatus "dq(5)" )
				)
				( pin "J6L1.10"
					( objectStatus "dq(6)" )
				)
				( pin "J6L1.155"
					( objectStatus "dq(7)" )
				)
				( pin "J6L1.16"
					( objectStatus "dq(8)" )
				)
				( pin "J6L1.161"
					( objectStatus "dq(9)" )
				)
				( pin "J6L1.23"
					( objectStatus "dq(10)" )
				)
				( pin "J6L1.168"
					( objectStatus "dq(11)" )
				)
				( pin "J6L1.14"
					( objectStatus "dq(12)" )
				)
				( pin "J6L1.159"
					( objectStatus "dq(13)" )
				)
				( pin "J6L1.21"
					( objectStatus "dq(14)" )
				)
				( pin "J6L1.166"
					( objectStatus "dq(15)" )
				)
				( pin "J6L1.27"
					( objectStatus "dq(16)" )
				)
				( pin "J6L1.172"
					( objectStatus "dq(17)" )
				)
				( pin "J6L1.34"
					( objectStatus "dq(18)" )
				)
				( pin "J6L1.179"
					( objectStatus "dq(19)" )
				)
				( pin "J6L1.25"
					( objectStatus "dq(20)" )
				)
				( pin "J6L1.170"
					( objectStatus "dq(21)" )
				)
				( pin "J6L1.32"
					( objectStatus "dq(22)" )
				)
				( pin "J6L1.177"
					( objectStatus "dq(23)" )
				)
				( pin "J6L1.38"
					( objectStatus "dq(24)" )
				)
				( pin "J6L1.183"
					( objectStatus "dq(25)" )
				)
				( pin "J6L1.45"
					( objectStatus "dq(26)" )
				)
				( pin "J6L1.190"
					( objectStatus "dq(27)" )
				)
				( pin "J6L1.36"
					( objectStatus "dq(28)" )
				)
				( pin "J6L1.181"
					( objectStatus "dq(29)" )
				)
				( pin "J6L1.43"
					( objectStatus "dq(30)" )
				)
				( pin "J6L1.188"
					( objectStatus "dq(31)" )
				)
				( pin "J6L1.97"
					( objectStatus "dq(32)" )
				)
				( pin "J6L1.242"
					( objectStatus "dq(33)" )
				)
				( pin "J6L1.104"
					( objectStatus "dq(34)" )
				)
				( pin "J6L1.249"
					( objectStatus "dq(35)" )
				)
				( pin "J6L1.95"
					( objectStatus "dq(36)" )
				)
				( pin "J6L1.240"
					( objectStatus "dq(37)" )
				)
				( pin "J6L1.102"
					( objectStatus "dq(38)" )
				)
				( pin "J6L1.247"
					( objectStatus "dq(39)" )
				)
				( pin "J6L1.108"
					( objectStatus "dq(40)" )
				)
				( pin "J6L1.253"
					( objectStatus "dq(41)" )
				)
				( pin "J6L1.115"
					( objectStatus "dq(42)" )
				)
				( pin "J6L1.260"
					( objectStatus "dq(43)" )
				)
				( pin "J6L1.106"
					( objectStatus "dq(44)" )
				)
				( pin "J6L1.251"
					( objectStatus "dq(45)" )
				)
				( pin "J6L1.113"
					( objectStatus "dq(46)" )
				)
				( pin "J6L1.258"
					( objectStatus "dq(47)" )
				)
				( pin "J6L1.119"
					( objectStatus "dq(48)" )
				)
				( pin "J6L1.264"
					( objectStatus "dq(49)" )
				)
				( pin "J6L1.126"
					( objectStatus "dq(50)" )
				)
				( pin "J6L1.271"
					( objectStatus "dq(51)" )
				)
				( pin "J6L1.117"
					( objectStatus "dq(52)" )
				)
				( pin "J6L1.262"
					( objectStatus "dq(53)" )
				)
				( pin "J6L1.124"
					( objectStatus "dq(54)" )
				)
				( pin "J6L1.269"
					( objectStatus "dq(55)" )
				)
				( pin "J6L1.130"
					( objectStatus "dq(56)" )
				)
				( pin "J6L1.275"
					( objectStatus "dq(57)" )
				)
				( pin "J6L1.137"
					( objectStatus "dq(58)" )
				)
				( pin "J6L1.282"
					( objectStatus "dq(59)" )
				)
				( pin "J6L1.128"
					( objectStatus "dq(60)" )
				)
				( pin "J6L1.273"
					( objectStatus "dq(61)" )
				)
				( pin "J6L1.135"
					( objectStatus "dq(62)" )
				)
				( pin "J6L1.280"
					( objectStatus "dq(63)" )
				)
				( pin "J6L1.78"
					( objectStatus "event_n" )
				)
				( pin "J6L1.87"
					( objectStatus "odt(0)" )
				)
				( pin "J6L1.91"
					( objectStatus "odt(1)" )
				)
				( pin "J6L1.222"
					( objectStatus "par" )
				)
				( pin "J6L1.58"
					( objectStatus "reset_n" )
				)
				( pin "J6L1.205"
					( objectStatus "rfu(0)" )
				)
				( pin "J6L1.227"
					( objectStatus "rfu(1)" )
				)
				( pin "J6L1.144"
					( objectStatus "rfu(2)" )
				)
				( pin "J6L1.84"
					( objectStatus "s0_n" )
				)
				( pin "J6L1.89"
					( objectStatus "s1_n" )
				)
				( pin "J6L1.93"
					( objectStatus "s2_n_c(0)" )
				)
				( pin "J6L1.237"
					( objectStatus "s3_n_c(1)" )
				)
				( pin "J6L1.139"
					( objectStatus "sa(0)" )
				)
				( pin "J6L1.140"
					( objectStatus "sa(1)" )
				)
				( pin "J6L1.238"
					( objectStatus "sa(2)" )
				)
				( pin "J6L1.230"
					( objectStatus "save_n_nc" )
				)
				( pin "J6L1.141"
					( objectStatus "scl" )
				)
				( pin "J6L1.285"
					( objectStatus "sda" )
				)
				( pin "J6L1.284"
					( objectStatus "vddspd" )
				)
				( pin "J6L1.146"
					( objectStatus "vrefca" )
				)
			)
			( gate "J6L1"
				( objectStatus "@baseboard_fab2_lib.baseboard_fab2(sch_1):page54_i170" )
				( pin "J6L1.145"
					( objectStatus "\12v\(0)" )
				)
				( pin "J6L1.1"
					( objectStatus "\12v\(1)" )
				)
				( pin "J6L1.236"
					( objectStatus "vdd(0)" )
				)
				( pin "J6L1.233"
					( objectStatus "vdd(1)" )
				)
				( pin "J6L1.231"
					( objectStatus "vdd(2)" )
				)
				( pin "J6L1.229"
					( objectStatus "vdd(3)" )
				)
				( pin "J6L1.226"
					( objectStatus "vdd(4)" )
				)
				( pin "J6L1.223"
					( objectStatus "vdd(5)" )
				)
				( pin "J6L1.220"
					( objectStatus "vdd(6)" )
				)
				( pin "J6L1.217"
					( objectStatus "vdd(7)" )
				)
				( pin "J6L1.215"
					( objectStatus "vdd(8)" )
				)
				( pin "J6L1.212"
					( objectStatus "vdd(9)" )
				)
				( pin "J6L1.209"
					( objectStatus "vdd(10)" )
				)
				( pin "J6L1.206"
					( objectStatus "vdd(11)" )
				)
				( pin "J6L1.204"
					( objectStatus "vdd(12)" )
				)
				( pin "J6L1.92"
					( objectStatus "vdd(13)" )
				)
				( pin "J6L1.90"
					( objectStatus "vdd(14)" )
				)
				( pin "J6L1.88"
					( objectStatus "vdd(15)" )
				)
				( pin "J6L1.85"
					( objectStatus "vdd(16)" )
				)
				( pin "J6L1.83"
					( objectStatus "vdd(17)" )
				)
				( pin "J6L1.80"
					( objectStatus "vdd(18)" )
				)
				( pin "J6L1.76"
					( objectStatus "vdd(19)" )
				)
				( pin "J6L1.73"
					( objectStatus "vdd(20)" )
				)
				( pin "J6L1.70"
					( objectStatus "vdd(21)" )
				)
				( pin "J6L1.67"
					( objectStatus "vdd(22)" )
				)
				( pin "J6L1.64"
					( objectStatus "vdd(23)" )
				)
				( pin "J6L1.61"
					( objectStatus "vdd(24)" )
				)
				( pin "J6L1.59"
					( objectStatus "vdd(25)" )
				)
				( pin "J6L1.287"
					( objectStatus "vpp(0)" )
				)
				( pin "J6L1.286"
					( objectStatus "vpp(1)" )
				)
				( pin "J6L1.288"
					( objectStatus "vpp(2)" )
				)
				( pin "J6L1.143"
					( objectStatus "vpp(3)" )
				)
				( pin "J6L1.142"
					( objectStatus "vpp(4)" )
				)
				( pin "J6L1.221"
					( objectStatus "vtt(0)" )
				)
				( pin "J6L1.77"
					( objectStatus "vtt(1)" )
				)
			)
			( gate "C4A5"
				( objectStatus "@baseboard_fab2_lib.baseboard_fab2(sch_1):page54_i179" )
				( pin "C4A5.1"
					( objectStatus "a" )
				)
				( pin "C4A5.2"
					( objectStatus "b" )
				)
			)
			( gate "R9N1"
				( objectStatus "@baseboard_fab2_lib.baseboard_fab2(sch_1):page55_i4" )
				( pin "R9N1.1"
					( objectStatus "a" )
				)
				( pin "R9N1.2"
					( objectStatus "b" )
				)
			)
			( gate "R9N2"
				( objectStatus "@baseboard_fab2_lib.baseboard_fab2(sch_1):page55_i7" )
				( pin "R9N2.1"
					( objectStatus "a" )
				)
				( pin "R9N2.2"
					( objectStatus "b" )
				)
			)
			( gate "R3B2"
				( objectStatus "@baseboard_fab2_lib.baseboard_fab2(sch_1):page55_i19" )
				( pin "R3B2.1"
					( objectStatus "a" )
				)
				( pin "R3B2.2"
					( objectStatus "b" )
				)
			)
			( gate "R3B4"
				( objectStatus "@baseboard_fab2_lib.baseboard_fab2(sch_1):page55_i21" )
				( pin "R3B4.1"
					( objectStatus "a" )
				)
				( pin "R3B4.2"
					( objectStatus "b" )
				)
			)
			( gate "R1C2"
				( objectStatus "@baseboard_fab2_lib.baseboard_fab2(sch_1):page55_i24" )
				( pin "R1C2.1"
					( objectStatus "a" )
				)
				( pin "R1C2.2"
					( objectStatus "b" )
				)
			)
			( gate "R1C3"
				( objectStatus "@baseboard_fab2_lib.baseboard_fab2(sch_1):page55_i25" )
				( pin "R1C3.1"
					( objectStatus "a" )
				)
				( pin "R1C3.2"
					( objectStatus "b" )
				)
			)
			( gate "R1C1"
				( objectStatus "@baseboard_fab2_lib.baseboard_fab2(sch_1):page55_i26" )
				( pin "R1C1.1"
					( objectStatus "a" )
				)
				( pin "R1C1.2"
					( objectStatus "b" )
				)
			)
			( gate "R3B1"
				( objectStatus "@baseboard_fab2_lib.baseboard_fab2(sch_1):page55_i27" )
				( pin "R3B1.1"
					( objectStatus "a" )
				)
				( pin "R3B1.2"
					( objectStatus "b" )
				)
			)
			( gate "R3B5"
				( objectStatus "@baseboard_fab2_lib.baseboard_fab2(sch_1):page55_i28" )
				( pin "R3B5.1"
					( objectStatus "a" )
				)
				( pin "R3B5.2"
					( objectStatus "b" )
				)
			)
			( gate "R3B3"
				( objectStatus "@baseboard_fab2_lib.baseboard_fab2(sch_1):page55_i29" )
				( pin "R3B3.1"
					( objectStatus "a" )
				)
				( pin "R3B3.2"
					( objectStatus "b" )
				)
			)
			( gate "R7P19"
				( objectStatus "@baseboard_fab2_lib.baseboard_fab2(sch_1):page55_i115" )
				( pin "R7P19.1"
					( objectStatus "a" )
				)
				( pin "R7P19.2"
					( objectStatus "b" )
				)
			)
			( gate "R3D1"
				( objectStatus "@baseboard_fab2_lib.baseboard_fab2(sch_1):page55_i116" )
				( pin "R3D1.1"
					( objectStatus "a" )
				)
				( pin "R3D1.2"
					( objectStatus "b" )
				)
			)
			( gate "R3D2"
				( objectStatus "@baseboard_fab2_lib.baseboard_fab2(sch_1):page55_i117" )
				( pin "R3D2.1"
					( objectStatus "a" )
				)
				( pin "R3D2.2"
					( objectStatus "b" )
				)
			)
			( gate "R3D3"
				( objectStatus "@baseboard_fab2_lib.baseboard_fab2(sch_1):page55_i118" )
				( pin "R3D3.1"
					( objectStatus "a" )
				)
				( pin "R3D3.2"
					( objectStatus "b" )
				)
			)
			( gate "R7P16"
				( objectStatus "@baseboard_fab2_lib.baseboard_fab2(sch_1):page55_i119" )
				( pin "R7P16.1"
					( objectStatus "a" )
				)
				( pin "R7P16.2"
					( objectStatus "b" )
				)
			)
			( gate "R7P8"
				( objectStatus "@baseboard_fab2_lib.baseboard_fab2(sch_1):page55_i123" )
				( pin "R7P8.1"
					( objectStatus "a" )
				)
				( pin "R7P8.2"
					( objectStatus "b" )
				)
			)
			( gate "R7P10"
				( objectStatus "@baseboard_fab2_lib.baseboard_fab2(sch_1):page55_i124" )
				( pin "R7P10.1"
					( objectStatus "a" )
				)
				( pin "R7P10.2"
					( objectStatus "b" )
				)
			)
			( gate "R3D19"
				( objectStatus "@baseboard_fab2_lib.baseboard_fab2(sch_1):page55_i125" )
				( pin "R3D19.1"
					( objectStatus "a" )
				)
				( pin "R3D19.2"
					( objectStatus "b" )
				)
			)
			( gate "R7P11"
				( objectStatus "@baseboard_fab2_lib.baseboard_fab2(sch_1):page55_i126" )
				( pin "R7P11.1"
					( objectStatus "a" )
				)
				( pin "R7P11.2"
					( objectStatus "b" )
				)
			)
			( gate "R7P17"
				( objectStatus "@baseboard_fab2_lib.baseboard_fab2(sch_1):page55_i140" )
				( pin "R7P17.1"
					( objectStatus "a" )
				)
				( pin "R7P17.2"
					( objectStatus "b" )
				)
			)
			( gate "XRU2"
				( objectStatus "@baseboard_fab2_lib.baseboard_fab2(sch_1):page55_i152" )
			)
			( gate "XLU2"
				( objectStatus "@baseboard_fab2_lib.baseboard_fab2(sch_1):page55_i153" )
			)
			( gate "R3D4"
				( objectStatus "@baseboard_fab2_lib.baseboard_fab2(sch_1):page55_i155" )
				( pin "R3D4.1"
					( objectStatus "a" )
				)
				( pin "R3D4.2"
					( objectStatus "b" )
				)
			)
			( gate "R7P26"
				( objectStatus "@baseboard_fab2_lib.baseboard_fab2(sch_1):page55_i156" )
				( pin "R7P26.1"
					( objectStatus "a" )
				)
				( pin "R7P26.2"
					( objectStatus "b" )
				)
			)
			( gate "R8N1"
				( objectStatus "@baseboard_fab2_lib.baseboard_fab2(sch_1):page55_i157" )
				( pin "R8N1.1"
					( objectStatus "a" )
				)
				( pin "R8N1.2"
					( objectStatus "b" )
				)
			)
			( gate "R8N4"
				( objectStatus "@baseboard_fab2_lib.baseboard_fab2(sch_1):page55_i158" )
				( pin "R8N4.1"
					( objectStatus "a" )
				)
				( pin "R8N4.2"
					( objectStatus "b" )
				)
			)
			( gate "R8N3"
				( objectStatus "@baseboard_fab2_lib.baseboard_fab2(sch_1):page55_i159" )
				( pin "R8N3.1"
					( objectStatus "a" )
				)
				( pin "R8N3.2"
					( objectStatus "b" )
				)
			)
			( gate "R8N5"
				( objectStatus "@baseboard_fab2_lib.baseboard_fab2(sch_1):page55_i160" )
				( pin "R8N5.1"
					( objectStatus "a" )
				)
				( pin "R8N5.2"
					( objectStatus "b" )
				)
			)
			( gate "R8N2"
				( objectStatus "@baseboard_fab2_lib.baseboard_fab2(sch_1):page55_i161" )
				( pin "R8N2.1"
					( objectStatus "a" )
				)
				( pin "R8N2.2"
					( objectStatus "b" )
				)
			)
			( gate "R7P25"
				( objectStatus "@baseboard_fab2_lib.baseboard_fab2(sch_1):page55_i170" )
				( pin "R7P25.1"
					( objectStatus "a" )
				)
				( pin "R7P25.2"
					( objectStatus "b" )
				)
			)
			( gate "U2D1"
				( objectStatus "@baseboard_fab2_lib.baseboard_fab2(sch_1):page55_i172" )
				( pin "U2D1.AU24"
					( objectStatus "bclk0_dn" )
				)
				( pin "U2D1.AW24"
					( objectStatus "bclk0_dp" )
				)
				( pin "U2D1.CR26"
					( objectStatus "bclk1_dn" )
				)
				( pin "U2D1.CP27"
					( objectStatus "bclk1_dp" )
				)
				( pin "U2D1.CT25"
					( objectStatus "bclk2_dn" )
				)
				( pin "U2D1.CU26"
					( objectStatus "bclk2_dp" )
				)
				( pin "U2D1.BA20"
					( objectStatus "bist_enable" )
				)
				( pin "U2D1.BD23"
					( objectStatus "bmcinit" )
				)
				( pin "U2D1.AJ10"
					( objectStatus "bpm_n(0)" )
				)
				( pin "U2D1.AH11"
					( objectStatus "bpm_n(1)" )
				)
				( pin "U2D1.AG10"
					( objectStatus "bpm_n(2)" )
				)
				( pin "U2D1.AF11"
					( objectStatus "bpm_n(3)" )
				)
				( pin "U2D1.AA12"
					( objectStatus "bpm_n(4)" )
				)
				( pin "U2D1.Y11"
					( objectStatus "bpm_n(5)" )
				)
				( pin "U2D1.AE12"
					( objectStatus "bpm_n(6)" )
				)
				( pin "U2D1.AC12"
					( objectStatus "bpm_n(7)" )
				)
				( pin "U2D1.AL14"
					( objectStatus "caterr_n" )
				)
				( pin "U2D1.AJ64"
					( objectStatus "ddr0_cavref" )
				)
				( pin "U2D1.AK63"
					( objectStatus "ddr1_cavref" )
				)
				( pin "U2D1.AH63"
					( objectStatus "ddr2_cavref" )
				)
				( pin "U2D1.CP61"
					( objectStatus "ddr3_cavref" )
				)
				( pin "U2D1.CT61"
					( objectStatus "ddr4_cavref" )
				)
				( pin "U2D1.CV61"
					( objectStatus "ddr5_cavref" )
				)
				( pin "U2D1.AN30"
					( objectStatus "ddr012_dram_pwr_ok" )
				)
				( pin "U2D1.Y43"
					( objectStatus "ddr012_rcomp(0)" )
				)
				( pin "U2D1.AB43"
					( objectStatus "ddr012_rcomp(1)" )
				)
				( pin "U2D1.AC42"
					( objectStatus "ddr012_rcomp(2)" )
				)
				( pin "U2D1.U64"
					( objectStatus "ddr012_reset_n" )
				)
				( pin "U2D1.AJ18"
					( objectStatus "ddr012_spdscl" )
				)
				( pin "U2D1.AF17"
					( objectStatus "ddr012_spdsda" )
				)
				( pin "U2D1.CR28"
					( objectStatus "ddr345_dram_pwr_ok" )
				)
				( pin "U2D1.DC48"
					( objectStatus "ddr345_rcomp(0)" )
				)
				( pin "U2D1.DD47"
					( objectStatus "ddr345_rcomp(1)" )
				)
				( pin "U2D1.DD49"
					( objectStatus "ddr345_rcomp(2)" )
				)
				( pin "U2D1.DV63"
					( objectStatus "ddr345_reset_n" )
				)
				( pin "U2D1.AE18"
					( objectStatus "ddr345_spdscl" )
				)
				( pin "U2D1.AD17"
					( objectStatus "ddr345_spdsda" )
				)
				( pin "U2D1.AJ14"
					( objectStatus "ear_n" )
				)
				( pin "U2D1.AJ12"
					( objectStatus "error_n(0)" )
				)
				( pin "U2D1.AK11"
					( objectStatus "error_n(1)" )
				)
				( pin "U2D1.AL12"
					( objectStatus "error_n(2)" )
				)
				( pin "U2D1.AV17"
					( objectStatus "frmagent" )
				)
				( pin "U2D1.AE20"
					( objectStatus "legacy_skt" )
				)
				( pin "U2D1.CU32"
					( objectStatus "mcp01_rbias(0)" )
				)
				( pin "U2D1.CT31"
					( objectStatus "mcp01_rbias(1)" )
				)
				( pin "U2D1.AH13"
					( objectStatus "mem_hot_c012_n" )
				)
				( pin "U2D1.AF13"
					( objectStatus "mem_hot_c345_n" )
				)
				( pin "U2D1.AN20"
					( objectStatus "msmi_n" )
				)
				( pin "U2D1.AP11"
					( objectStatus "nmi" )
				)
				( pin "U2D1.CP29"
					( objectStatus "pe3_rbias(0)" )
				)
				( pin "U2D1.CR30"
					( objectStatus "pe3_rbias(1)" )
				)
				( pin "U2D1.CN30"
					( objectStatus "pe012_rbias(0)" )
				)
				( pin "U2D1.CL30"
					( objectStatus "pe012_rbias(1)" )
				)
				( pin "U2D1.AM19"
					( objectStatus "pe_hp_scl" )
				)
				( pin "U2D1.AL18"
					( objectStatus "pe_hp_sda" )
				)
				( pin "U2D1.AU12"
					( objectStatus "peci" )
				)
				( pin "U2D1.CU58"
					( objectStatus "pirom_addr(0)" )
				)
				( pin "U2D1.CV57"
					( objectStatus "pirom_addr(1)" )
				)
				( pin "U2D1.CW56"
					( objectStatus "pirom_addr(2)" )
				)
				( pin "U2D1.DC72"
					( objectStatus "pkgid(0)" )
				)
				( pin "U2D1.CW72"
					( objectStatus "pkgid(1)" )
				)
				( pin "U2D1.DA72"
					( objectStatus "pkgid(2)" )
				)
				( pin "U2D1.AF15"
					( objectStatus "pm_fast_wake_n" )
				)
				( pin "U2D1.AR14"
					( objectStatus "pmsync" )
				)
				( pin "U2D1.AT19"
					( objectStatus "pmsync_clk" )
				)
				( pin "U2D1.AG16"
					( objectStatus "prdy_n" )
				)
				( pin "U2D1.AR12"
					( objectStatus "preq_n" )
				)
				( pin "U2D1.CY71"
					( objectStatus "proc_id(0)" )
				)
				( pin "U2D1.DB71"
					( objectStatus "proc_id(1)" )
				)
				( pin "U2D1.AB17"
					( objectStatus "procdis_n" )
				)
				( pin "U2D1.AC16"
					( objectStatus "prochot_n" )
				)
				( pin "U2D1.BC24"
					( objectStatus "pwrgood" )
				)
				( pin "U2D1.AP21"
					( objectStatus "reset_n" )
				)
				( pin "U2D1.AR18"
					( objectStatus "safe_mode_boot" )
				)
				( pin "U2D1.AB13"
					( objectStatus "sktocc_n" )
				)
				( pin "U2D1.CV59"
					( objectStatus "sm_wp" )
				)
				( pin "U2D1.CT59"
					( objectStatus "smbclk" )
				)
				( pin "U2D1.CW58"
					( objectStatus "smbdat" )
				)
				( pin "U2D1.AU22"
					( objectStatus "socket_id(0)" )
				)
				( pin "U2D1.AU16"
					( objectStatus "socket_id(1)" )
				)
				( pin "U2D1.AU20"
					( objectStatus "socket_id(2)" )
				)
				( pin "U2D1.DE44"
					( objectStatus "svidalert_n(0)" )
				)
				( pin "U2D1.DL44"
					( objectStatus "svidalert_n(1)" )
				)
				( pin "U2D1.DC44"
					( objectStatus "svidclk(0)" )
				)
				( pin "U2D1.DG44"
					( objectStatus "svidclk(1)" )
				)
				( pin "U2D1.DB45"
					( objectStatus "sviddata(0)" )
				)
				( pin "U2D1.DJ44"
					( objectStatus "sviddata(1)" )
				)
				( pin "U2D1.AA14"
					( objectStatus "tck" )
				)
				( pin "U2D1.AC14"
					( objectStatus "tdi" )
				)
				( pin "U2D1.AE14"
					( objectStatus "tdo" )
				)
				( pin "U2D1.AY19"
					( objectStatus "test_12" )
				)
				( pin "U2D1.DB51"
					( objectStatus "test_13" )
				)
				( pin "U2D1.DC50"
					( objectStatus "test_14" )
				)
				( pin "U2D1.AW14"
					( objectStatus "test_15" )
				)
				( pin "U2D1.AB15"
					( objectStatus "thermtrip_n" )
				)
				( pin "U2D1.W14"
					( objectStatus "tms" )
				)
				( pin "U2D1.Y13"
					( objectStatus "trst_n" )
				)
				( pin "U2D1.AM11"
					( objectStatus "tsc_sync" )
				)
				( pin "U2D1.AW18"
					( objectStatus "txt_agent" )
				)
				( pin "U2D1.AV15"
					( objectStatus "txt_plten" )
				)
				( pin "U2D1.AT29"
					( objectStatus "upi01_rbias(0)" )
				)
				( pin "U2D1.AP29"
					( objectStatus "upi01_rbias(1)" )
				)
				( pin "U2D1.CL28"
					( objectStatus "upi2_rbias(0)" )
				)
				( pin "U2D1.CK29"
					( objectStatus "upi2_rbias(1)" )
				)
			)
			( gate "R6P39"
				( objectStatus "@baseboard_fab2_lib.baseboard_fab2(sch_1):page55_i181" )
				( pin "R6P39.1"
					( objectStatus "a" )
				)
				( pin "R6P39.2"
					( objectStatus "b" )
				)
			)
			( gate "U2D1"
				( objectStatus "@baseboard_fab2_lib.baseboard_fab2(sch_1):page56_i169" )
				( pin "U2D1.AV21"
					( objectStatus "debug_en_n" )
				)
				( pin "U2D1.AW12"
					( objectStatus "dmimode_override" )
				)
				( pin "U2D1.AU14"
					( objectStatus "fivr_fault" )
				)
				( pin "U2D1.AP17"
					( objectStatus "pwr_debug_n" )
				)
				( pin "U2D1.AP61"
					( objectStatus "rsvd(194)" )
				)
				( pin "U2D1.AP27"
					( objectStatus "rsvd(195)" )
				)
				( pin "U2D1.AP25"
					( objectStatus "rsvd(196)" )
				)
				( pin "U2D1.AP23"
					( objectStatus "rsvd(197)" )
				)
				( pin "U2D1.AN62"
					( objectStatus "rsvd(198)" )
				)
				( pin "U2D1.AN60"
					( objectStatus "rsvd(199)" )
				)
				( pin "U2D1.AN26"
					( objectStatus "rsvd(200)" )
				)
				( pin "U2D1.AN24"
					( objectStatus "rsvd(201)" )
				)
				( pin "U2D1.AN22"
					( objectStatus "rsvd(202)" )
				)
				( pin "U2D1.AN18"
					( objectStatus "rsvd(203)" )
				)
				( pin "U2D1.AM61"
					( objectStatus "rsvd(204)" )
				)
				( pin "U2D1.AM59"
					( objectStatus "rsvd(205)" )
				)
				( pin "U2D1.AM27"
					( objectStatus "rsvd(206)" )
				)
				( pin "U2D1.AM25"
					( objectStatus "rsvd(207)" )
				)
				( pin "U2D1.AM23"
					( objectStatus "rsvd(208)" )
				)
				( pin "U2D1.AM21"
					( objectStatus "rsvd(209)" )
				)
				( pin "U2D1.AL62"
					( objectStatus "rsvd(210)" )
				)
				( pin "U2D1.AL60"
					( objectStatus "rsvd(211)" )
				)
				( pin "U2D1.AL58"
					( objectStatus "rsvd(212)" )
				)
				( pin "U2D1.AL26"
					( objectStatus "rsvd(213)" )
				)
				( pin "U2D1.AL22"
					( objectStatus "rsvd(214)" )
				)
				( pin "U2D1.AL20"
					( objectStatus "rsvd(215)" )
				)
				( pin "U2D1.AK69"
					( objectStatus "rsvd(216)" )
				)
				( pin "U2D1.AK61"
					( objectStatus "rsvd(217)" )
				)
				( pin "U2D1.AK59"
					( objectStatus "rsvd(218)" )
				)
				( pin "U2D1.AK57"
					( objectStatus "rsvd(219)" )
				)
				( pin "U2D1.AK27"
					( objectStatus "rsvd(220)" )
				)
				( pin "U2D1.AK21"
					( objectStatus "rsvd(221)" )
				)
				( pin "U2D1.AJ70"
					( objectStatus "rsvd(222)" )
				)
				( pin "U2D1.AJ62"
					( objectStatus "rsvd(223)" )
				)
				( pin "U2D1.AJ60"
					( objectStatus "rsvd(224)" )
				)
				( pin "U2D1.AJ58"
					( objectStatus "rsvd(225)" )
				)
				( pin "U2D1.AJ56"
					( objectStatus "rsvd(226)" )
				)
				( pin "U2D1.AJ20"
					( objectStatus "rsvd(227)" )
				)
				( pin "U2D1.AH73"
					( objectStatus "rsvd(228)" )
				)
				( pin "U2D1.AH71"
					( objectStatus "rsvd(229)" )
				)
				( pin "U2D1.AH57"
					( objectStatus "rsvd(230)" )
				)
				( pin "U2D1.AH55"
					( objectStatus "rsvd(231)" )
				)
				( pin "U2D1.AH19"
					( objectStatus "rsvd(232)" )
				)
				( pin "U2D1.AH15"
					( objectStatus "rsvd(233)" )
				)
				( pin "U2D1.AG72"
					( objectStatus "rsvd(234)" )
				)
				( pin "U2D1.AG56"
					( objectStatus "rsvd(235)" )
				)
				( pin "U2D1.AG54"
					( objectStatus "rsvd(236)" )
				)
				( pin "U2D1.AG52"
					( objectStatus "rsvd(237)" )
				)
				( pin "U2D1.AG50"
					( objectStatus "rsvd(238)" )
				)
				( pin "U2D1.AG48"
					( objectStatus "rsvd(239)" )
				)
				( pin "U2D1.AG20"
					( objectStatus "rsvd(240)" )
				)
				( pin "U2D1.AF71"
					( objectStatus "rsvd(241)" )
				)
				( pin "U2D1.AF53"
					( objectStatus "rsvd(242)" )
				)
				( pin "U2D1.AF51"
					( objectStatus "rsvd(243)" )
				)
				( pin "U2D1.AF49"
					( objectStatus "rsvd(244)" )
				)
				( pin "U2D1.AF47"
					( objectStatus "rsvd(245)" )
				)
				( pin "U2D1.AF19"
					( objectStatus "rsvd(246)" )
				)
				( pin "U2D1.AE72"
					( objectStatus "rsvd(247)" )
				)
				( pin "U2D1.AE52"
					( objectStatus "rsvd(248)" )
				)
				( pin "U2D1.AE50"
					( objectStatus "rsvd(249)" )
				)
				( pin "U2D1.AE48"
					( objectStatus "rsvd(250)" )
				)
				( pin "U2D1.AE46"
					( objectStatus "rsvd(251)" )
				)
				( pin "U2D1.AD51"
					( objectStatus "rsvd(252)" )
				)
				( pin "U2D1.AD49"
					( objectStatus "rsvd(253)" )
				)
				( pin "U2D1.AD47"
					( objectStatus "rsvd(254)" )
				)
				( pin "U2D1.Y65"
					( objectStatus "rsvd(256)" )
				)
				( pin "U2D1.Y23"
					( objectStatus "rsvd(257)" )
				)
				( pin "U2D1.W66"
					( objectStatus "rsvd(258)" )
				)
				( pin "U2D1.V67"
					( objectStatus "rsvd(259)" )
				)
				( pin "U2D1.V65"
					( objectStatus "rsvd(260)" )
				)
				( pin "U2D1.U66"
					( objectStatus "rsvd(261)" )
				)
				( pin "U2D1.T67"
					( objectStatus "rsvd(262)" )
				)
				( pin "U2D1.R66"
					( objectStatus "rsvd(263)" )
				)
				( pin "U2D1.R62"
					( objectStatus "rsvd(264)" )
				)
				( pin "U2D1.P65"
					( objectStatus "rsvd(265)" )
				)
				( pin "U2D1.M63"
					( objectStatus "rsvd(266)" )
				)
				( pin "U2D1.K61"
					( objectStatus "rsvd(267)" )
				)
				( pin "U2D1.J62"
					( objectStatus "rsvd(268)" )
				)
				( pin "U2D1.J46"
					( objectStatus "rsvd(269)" )
				)
				( pin "U2D1.H85"
					( objectStatus "rsvd(270)" )
				)
				( pin "U2D1.H83"
					( objectStatus "rsvd(271)" )
				)
				( pin "U2D1.H1"
					( objectStatus "rsvd(272)" )
				)
				( pin "U2D1.G84"
					( objectStatus "rsvd(273)" )
				)
				( pin "U2D1.G64"
					( objectStatus "rsvd(274)" )
				)
				( pin "U2D1.G2"
					( objectStatus "rsvd(275)" )
				)
				( pin "U2D1.F83"
					( objectStatus "rsvd(276)" )
				)
				( pin "U2D1.F65"
					( objectStatus "rsvd(277)" )
				)
				( pin "U2D1.F23"
					( objectStatus "rsvd(278)" )
				)
				( pin "U2D1.F3"
					( objectStatus "rsvd(279)" )
				)
				( pin "U2D1.E84"
					( objectStatus "rsvd(280)" )
				)
				( pin "U2D1.E24"
					( objectStatus "rsvd(281)" )
				)
				( pin "U2D1.E4"
					( objectStatus "rsvd(282)" )
				)
				( pin "U2D1.E2"
					( objectStatus "rsvd(283)" )
				)
				( pin "U2D1.D83"
					( objectStatus "rsvd(284)" )
				)
				( pin "U2D1.D65"
					( objectStatus "rsvd(285)" )
				)
				( pin "U2D1.D17"
					( objectStatus "rsvd(286)" )
				)
				( pin "U2D1.D5"
					( objectStatus "rsvd(287)" )
				)
				( pin "U2D1.C82"
					( objectStatus "rsvd(288)" )
				)
				( pin "U2D1.C24"
					( objectStatus "rsvd(289)" )
				)
				( pin "U2D1.C18"
					( objectStatus "rsvd(290)" )
				)
				( pin "U2D1.C6"
					( objectStatus "rsvd(291)" )
				)
				( pin "U2D1.B81"
					( objectStatus "rsvd(292)" )
				)
				( pin "U2D1.B77"
					( objectStatus "rsvd(293)" )
				)
				( pin "U2D1.B17"
					( objectStatus "rsvd(294)" )
				)
				( pin "U2D1.B15"
					( objectStatus "rsvd(295)" )
				)
				( pin "U2D1.B13"
					( objectStatus "rsvd(296)" )
				)
				( pin "U2D1.B7"
					( objectStatus "rsvd(298)" )
				)
				( pin "U2D1.B3"
					( objectStatus "rsvd(299)" )
				)
				( pin "U2D1.A24"
					( objectStatus "rsvd(300)" )
				)
				( pin "U2D1.A16"
					( objectStatus "rsvd(301)" )
				)
				( pin "U2D1.A14"
					( objectStatus "rsvd(302)" )
				)
				( pin "U2D1.A6"
					( objectStatus "rsvd(303)" )
				)
				( pin "U2D1.A4"
					( objectStatus "rsvd(304)" )
				)
				( pin "U2D1.AF45"
					( objectStatus "test_1" )
				)
				( pin "U2D1.AG46"
					( objectStatus "test_2" )
				)
				( pin "U2D1.AM13"
					( objectStatus "test_3" )
				)
				( pin "U2D1.AN12"
					( objectStatus "test_4" )
				)
				( pin "U2D1.AN14"
					( objectStatus "test_5" )
				)
				( pin "U2D1.AY13"
					( objectStatus "test_11" )
				)
			)
			( gate "R8P3"
				( objectStatus "@baseboard_fab2_lib.baseboard_fab2(sch_1):page56_i173" )
				( pin "R8P3.1"
					( objectStatus "a" )
				)
				( pin "R8P3.2"
					( objectStatus "b" )
				)
			)
			( gate "R8R1"
				( objectStatus "@baseboard_fab2_lib.baseboard_fab2(sch_1):page56_i174" )
				( pin "R8R1.1"
					( objectStatus "a" )
				)
				( pin "R8R1.2"
					( objectStatus "b" )
				)
			)
			( gate "U2D1"
				( objectStatus "@baseboard_fab2_lib.baseboard_fab2(sch_1):page57_i172" )
				( pin "U2D1.J60"
					( objectStatus "ddr0_act_n" )
				)
				( pin "U2D1.B61"
					( objectStatus "ddr0_alert_n" )
				)
				( pin "U2D1.C52"
					( objectStatus "ddr0_ba(0)" )
				)
				( pin "U2D1.G54"
					( objectStatus "ddr0_ba(1)" )
				)
				( pin "U2D1.D61"
					( objectStatus "ddr0_bg(0)" )
				)
				( pin "U2D1.F63"
					( objectStatus "ddr0_bg(1)" )
				)
				( pin "U2D1.G46"
					( objectStatus "ddr0_cid(2)" )
				)
				( pin "U2D1.C62"
					( objectStatus "ddr0_cke(0)" )
				)
				( pin "U2D1.C64"
					( objectStatus "ddr0_cke(1)" )
				)
				( pin "U2D1.B63"
					( objectStatus "ddr0_cke(2)" )
				)
				( pin "U2D1.D63"
					( objectStatus "ddr0_cke(3)" )
				)
				( pin "U2D1.F55"
					( objectStatus "ddr0_clk_dn(0)" )
				)
				( pin "U2D1.C54"
					( objectStatus "ddr0_clk_dn(1)" )
				)
				( pin "U2D1.J56"
					( objectStatus "ddr0_clk_dn(2)" )
				)
				( pin "U2D1.C56"
					( objectStatus "ddr0_clk_dn(3)" )
				)
				( pin "U2D1.D55"
					( objectStatus "ddr0_clk_dp(0)" )
				)
				( pin "U2D1.B55"
					( objectStatus "ddr0_clk_dp(1)" )
				)
				( pin "U2D1.G56"
					( objectStatus "ddr0_clk_dp(2)" )
				)
				( pin "U2D1.B57"
					( objectStatus "ddr0_clk_dp(3)" )
				)
				( pin "U2D1.G52"
					( objectStatus "ddr0_cs_n(0)" )
				)
				( pin "U2D1.F49"
					( objectStatus "ddr0_cs_n(1)" )
				)
				( pin "U2D1.D47"
					( objectStatus "ddr0_cs_n(2)" )
				)
				( pin "U2D1.F47"
					( objectStatus "ddr0_cs_n(3)" )
				)
				( pin "U2D1.B51"
					( objectStatus "ddr0_cs_n(4)" )
				)
				( pin "U2D1.D49"
					( objectStatus "ddr0_cs_n(5)" )
				)
				( pin "U2D1.F45"
					( objectStatus "ddr0_cs_n(6)" )
				)
				( pin "U2D1.K45"
					( objectStatus "ddr0_cs_n(7)" )
				)
				( pin "U2D1.AN86"
					( objectStatus "ddr0_dq(0)" )
				)
				( pin "U2D1.AN84"
					( objectStatus "ddr0_dq(1)" )
				)
				( pin "U2D1.AE86"
					( objectStatus "ddr0_dq(2)" )
				)
				( pin "U2D1.AE84"
					( objectStatus "ddr0_dq(3)" )
				)
				( pin "U2D1.AR86"
					( objectStatus "ddr0_dq(4)" )
				)
				( pin "U2D1.AR84"
					( objectStatus "ddr0_dq(5)" )
				)
				( pin "U2D1.AG86"
					( objectStatus "ddr0_dq(6)" )
				)
				( pin "U2D1.AG84"
					( objectStatus "ddr0_dq(7)" )
				)
				( pin "U2D1.W86"
					( objectStatus "ddr0_dq(8)" )
				)
				( pin "U2D1.W84"
					( objectStatus "ddr0_dq(9)" )
				)
				( pin "U2D1.L86"
					( objectStatus "ddr0_dq(10)" )
				)
				( pin "U2D1.L84"
					( objectStatus "ddr0_dq(11)" )
				)
				( pin "U2D1.AA86"
					( objectStatus "ddr0_dq(12)" )
				)
				( pin "U2D1.AA84"
					( objectStatus "ddr0_dq(13)" )
				)
				( pin "U2D1.N86"
					( objectStatus "ddr0_dq(14)" )
				)
				( pin "U2D1.N84"
					( objectStatus "ddr0_dq(15)" )
				)
				( pin "U2D1.V81"
					( objectStatus "ddr0_dq(16)" )
				)
				( pin "U2D1.T79"
					( objectStatus "ddr0_dq(17)" )
				)
				( pin "U2D1.N82"
					( objectStatus "ddr0_dq(18)" )
				)
				( pin "U2D1.M81"
					( objectStatus "ddr0_dq(19)" )
				)
				( pin "U2D1.W80"
					( objectStatus "ddr0_dq(20)" )
				)
				( pin "U2D1.V79"
					( objectStatus "ddr0_dq(21)" )
				)
				( pin "U2D1.R82"
					( objectStatus "ddr0_dq(22)" )
				)
				( pin "U2D1.N80"
					( objectStatus "ddr0_dq(23)" )
				)
				( pin "U2D1.L76"
					( objectStatus "ddr0_dq(24)" )
				)
				( pin "U2D1.R76"
					( objectStatus "ddr0_dq(25)" )
				)
				( pin "U2D1.M73"
					( objectStatus "ddr0_dq(26)" )
				)
				( pin "U2D1.P73"
					( objectStatus "ddr0_dq(27)" )
				)
				( pin "U2D1.M77"
					( objectStatus "ddr0_dq(28)" )
				)
				( pin "U2D1.P77"
					( objectStatus "ddr0_dq(29)" )
				)
				( pin "U2D1.L74"
					( objectStatus "ddr0_dq(30)" )
				)
				( pin "U2D1.R74"
					( objectStatus "ddr0_dq(31)" )
				)
				( pin "U2D1.C42"
					( objectStatus "ddr0_dq(32)" )
				)
				( pin "U2D1.B41"
					( objectStatus "ddr0_dq(33)" )
				)
				( pin "U2D1.C38"
					( objectStatus "ddr0_dq(34)" )
				)
				( pin "U2D1.E38"
					( objectStatus "ddr0_dq(35)" )
				)
				( pin "U2D1.E42"
					( objectStatus "ddr0_dq(36)" )
				)
				( pin "U2D1.F41"
					( objectStatus "ddr0_dq(37)" )
				)
				( pin "U2D1.B39"
					( objectStatus "ddr0_dq(38)" )
				)
				( pin "U2D1.F39"
					( objectStatus "ddr0_dq(39)" )
				)
				( pin "U2D1.K37"
					( objectStatus "ddr0_dq(40)" )
				)
				( pin "U2D1.P37"
					( objectStatus "ddr0_dq(41)" )
				)
				( pin "U2D1.L34"
					( objectStatus "ddr0_dq(42)" )
				)
				( pin "U2D1.N34"
					( objectStatus "ddr0_dq(43)" )
				)
				( pin "U2D1.L38"
					( objectStatus "ddr0_dq(44)" )
				)
				( pin "U2D1.N38"
					( objectStatus "ddr0_dq(45)" )
				)
				( pin "U2D1.K35"
					( objectStatus "ddr0_dq(46)" )
				)
				( pin "U2D1.P35"
					( objectStatus "ddr0_dq(47)" )
				)
				( pin "U2D1.K31"
					( objectStatus "ddr0_dq(48)" )
				)
				( pin "U2D1.P31"
					( objectStatus "ddr0_dq(49)" )
				)
				( pin "U2D1.L28"
					( objectStatus "ddr0_dq(50)" )
				)
				( pin "U2D1.N28"
					( objectStatus "ddr0_dq(51)" )
				)
				( pin "U2D1.L32"
					( objectStatus "ddr0_dq(52)" )
				)
				( pin "U2D1.N32"
					( objectStatus "ddr0_dq(53)" )
				)
				( pin "U2D1.K29"
					( objectStatus "ddr0_dq(54)" )
				)
				( pin "U2D1.P29"
					( objectStatus "ddr0_dq(55)" )
				)
				( pin "U2D1.K25"
					( objectStatus "ddr0_dq(56)" )
				)
				( pin "U2D1.P25"
					( objectStatus "ddr0_dq(57)" )
				)
				( pin "U2D1.P23"
					( objectStatus "ddr0_dq(58)" )
				)
				( pin "U2D1.T23"
					( objectStatus "ddr0_dq(59)" )
				)
				( pin "U2D1.L26"
					( objectStatus "ddr0_dq(60)" )
				)
				( pin "U2D1.N26"
					( objectStatus "ddr0_dq(61)" )
				)
				( pin "U2D1.H23"
					( objectStatus "ddr0_dq(62)" )
				)
				( pin "U2D1.K23"
					( objectStatus "ddr0_dq(63)" )
				)
				( pin "U2D1.AJ84"
					( objectStatus "ddr0_dqs_dn(0)" )
				)
				( pin "U2D1.R84"
					( objectStatus "ddr0_dqs_dn(1)" )
				)
				( pin "U2D1.P79"
					( objectStatus "ddr0_dqs_dn(2)" )
				)
				( pin "U2D1.T75"
					( objectStatus "ddr0_dqs_dn(3)" )
				)
				( pin "U2D1.G40"
					( objectStatus "ddr0_dqs_dn(4)" )
				)
				( pin "U2D1.R36"
					( objectStatus "ddr0_dqs_dn(5)" )
				)
				( pin "U2D1.R30"
					( objectStatus "ddr0_dqs_dn(6)" )
				)
				( pin "U2D1.N24"
					( objectStatus "ddr0_dqs_dn(7)" )
				)
				( pin "U2D1.AH67"
					( objectStatus "ddr0_dqs_dn(8)" )
				)
				( pin "U2D1.AL84"
					( objectStatus "ddr0_dqs_dn(9)" )
				)
				( pin "U2D1.U84"
					( objectStatus "ddr0_dqs_dn(10)" )
				)
				( pin "U2D1.U82"
					( objectStatus "ddr0_dqs_dn(11)" )
				)
				( pin "U2D1.K75"
					( objectStatus "ddr0_dqs_dn(12)" )
				)
				( pin "U2D1.A40"
					( objectStatus "ddr0_dqs_dn(13)" )
				)
				( pin "U2D1.J36"
					( objectStatus "ddr0_dqs_dn(14)" )
				)
				( pin "U2D1.J30"
					( objectStatus "ddr0_dqs_dn(15)" )
				)
				( pin "U2D1.J24"
					( objectStatus "ddr0_dqs_dn(16)" )
				)
				( pin "U2D1.AB67"
					( objectStatus "ddr0_dqs_dn(17)" )
				)
				( pin "U2D1.AH85"
					( objectStatus "ddr0_dqs_dp(0)" )
				)
				( pin "U2D1.P85"
					( objectStatus "ddr0_dqs_dp(1)" )
				)
				( pin "U2D1.R80"
					( objectStatus "ddr0_dqs_dp(2)" )
				)
				( pin "U2D1.P75"
					( objectStatus "ddr0_dqs_dp(3)" )
				)
				( pin "U2D1.E40"
					( objectStatus "ddr0_dqs_dp(4)" )
				)
				( pin "U2D1.N36"
					( objectStatus "ddr0_dqs_dp(5)" )
				)
				( pin "U2D1.N30"
					( objectStatus "ddr0_dqs_dp(6)" )
				)
				( pin "U2D1.R24"
					( objectStatus "ddr0_dqs_dp(7)" )
				)
				( pin "U2D1.AF67"
					( objectStatus "ddr0_dqs_dp(8)" )
				)
				( pin "U2D1.AM85"
					( objectStatus "ddr0_dqs_dp(9)" )
				)
				( pin "U2D1.V85"
					( objectStatus "ddr0_dqs_dp(10)" )
				)
				( pin "U2D1.T81"
					( objectStatus "ddr0_dqs_dp(11)" )
				)
				( pin "U2D1.M75"
					( objectStatus "ddr0_dqs_dp(12)" )
				)
				( pin "U2D1.C40"
					( objectStatus "ddr0_dqs_dp(13)" )
				)
				( pin "U2D1.L36"
					( objectStatus "ddr0_dqs_dp(14)" )
				)
				( pin "U2D1.L30"
					( objectStatus "ddr0_dqs_dp(15)" )
				)
				( pin "U2D1.L24"
					( objectStatus "ddr0_dqs_dp(16)" )
				)
				( pin "U2D1.AD67"
					( objectStatus "ddr0_dqs_dp(17)" )
				)
				( pin "U2D1.AC68"
					( objectStatus "ddr0_ecc(0)" )
				)
				( pin "U2D1.AG68"
					( objectStatus "ddr0_ecc(1)" )
				)
				( pin "U2D1.AD65"
					( objectStatus "ddr0_ecc(2)" )
				)
				( pin "U2D1.AF65"
					( objectStatus "ddr0_ecc(3)" )
				)
				( pin "U2D1.AD69"
					( objectStatus "ddr0_ecc(4)" )
				)
				( pin "U2D1.AF69"
					( objectStatus "ddr0_ecc(5)" )
				)
				( pin "U2D1.AC66"
					( objectStatus "ddr0_ecc(6)" )
				)
				( pin "U2D1.AG66"
					( objectStatus "ddr0_ecc(7)" )
				)
				( pin "U2D1.F53"
					( objectStatus "ddr0_ma(0)" )
				)
				( pin "U2D1.F57"
					( objectStatus "ddr0_ma(1)" )
				)
				( pin "U2D1.D57"
					( objectStatus "ddr0_ma(2)" )
				)
				( pin "U2D1.C58"
					( objectStatus "ddr0_ma(3)" )
				)
				( pin "U2D1.G58"
					( objectStatus "ddr0_ma(4)" )
				)
				( pin "U2D1.F59"
					( objectStatus "ddr0_ma(5)" )
				)
				( pin "U2D1.D59"
					( objectStatus "ddr0_ma(6)" )
				)
				( pin "U2D1.G60"
					( objectStatus "ddr0_ma(7)" )
				)
				( pin "U2D1.C60"
					( objectStatus "ddr0_ma(8)" )
				)
				( pin "U2D1.F61"
					( objectStatus "ddr0_ma(9)" )
				)
				( pin "U2D1.J54"
					( objectStatus "ddr0_ma(10)" )
				)
				( pin "U2D1.G62"
					( objectStatus "ddr0_ma(11)" )
				)
				( pin "U2D1.J64"
					( objectStatus "ddr0_ma(12)" )
				)
				( pin "U2D1.J48"
					( objectStatus "ddr0_ma(13)" )
				)
				( pin "U2D1.F51"
					( objectStatus "ddr0_ma(14)" )
				)
				( pin "U2D1.K49"
					( objectStatus "ddr0_ma(15)" )
				)
				( pin "U2D1.D51"
					( objectStatus "ddr0_ma(16)" )
				)
				( pin "U2D1.K47"
					( objectStatus "ddr0_ma(17)" )
				)
				( pin "U2D1.C50"
					( objectStatus "ddr0_odt(0)" )
				)
				( pin "U2D1.C48"
					( objectStatus "ddr0_odt(1)" )
				)
				( pin "U2D1.G50"
					( objectStatus "ddr0_odt(2)" )
				)
				( pin "U2D1.G48"
					( objectStatus "ddr0_odt(3)" )
				)
				( pin "U2D1.D53"
					( objectStatus "ddr0_par" )
				)
			)
			( gate "U2D1"
				( objectStatus "@baseboard_fab2_lib.baseboard_fab2(sch_1):page58_i172" )
				( pin "U2D1.T63"
					( objectStatus "ddr1_act_n" )
				)
				( pin "U2D1.W62"
					( objectStatus "ddr1_alert_n" )
				)
				( pin "U2D1.T53"
					( objectStatus "ddr1_ba(0)" )
				)
				( pin "U2D1.K55"
					( objectStatus "ddr1_ba(1)" )
				)
				( pin "U2D1.M61"
					( objectStatus "ddr1_bg(0)" )
				)
				( pin "U2D1.N60"
					( objectStatus "ddr1_bg(1)" )
				)
				( pin "U2D1.M47"
					( objectStatus "ddr1_cid(2)" )
				)
				( pin "U2D1.N62"
					( objectStatus "ddr1_cke(0)" )
				)
				( pin "U2D1.R64"
					( objectStatus "ddr1_cke(1)" )
				)
				( pin "U2D1.K63"
					( objectStatus "ddr1_cke(2)" )
				)
				( pin "U2D1.L64"
					( objectStatus "ddr1_cke(3)" )
				)
				( pin "U2D1.M53"
					( objectStatus "ddr1_clk_dn(0)" )
				)
				( pin "U2D1.R54"
					( objectStatus "ddr1_clk_dn(1)" )
				)
				( pin "U2D1.N56"
					( objectStatus "ddr1_clk_dn(2)" )
				)
				( pin "U2D1.R56"
					( objectStatus "ddr1_clk_dn(3)" )
				)
				( pin "U2D1.N54"
					( objectStatus "ddr1_clk_dp(0)" )
				)
				( pin "U2D1.T55"
					( objectStatus "ddr1_clk_dp(1)" )
				)
				( pin "U2D1.M57"
					( objectStatus "ddr1_clk_dp(2)" )
				)
				( pin "U2D1.T57"
					( objectStatus "ddr1_clk_dp(3)" )
				)
				( pin "U2D1.K51"
					( objectStatus "ddr1_cs_n(0)" )
				)
				( pin "U2D1.R50"
					( objectStatus "ddr1_cs_n(1)" )
				)
				( pin "U2D1.N46"
					( objectStatus "ddr1_cs_n(2)" )
				)
				( pin "U2D1.V47"
					( objectStatus "ddr1_cs_n(3)" )
				)
				( pin "U2D1.J50"
					( objectStatus "ddr1_cs_n(4)" )
				)
				( pin "U2D1.T49"
					( objectStatus "ddr1_cs_n(5)" )
				)
				( pin "U2D1.M45"
					( objectStatus "ddr1_cs_n(6)" )
				)
				( pin "U2D1.R46"
					( objectStatus "ddr1_cs_n(7)" )
				)
				( pin "U2D1.AV81"
					( objectStatus "ddr1_dq(0)" )
				)
				( pin "U2D1.AT79"
					( objectStatus "ddr1_dq(1)" )
				)
				( pin "U2D1.AN82"
					( objectStatus "ddr1_dq(2)" )
				)
				( pin "U2D1.AM81"
					( objectStatus "ddr1_dq(3)" )
				)
				( pin "U2D1.AW80"
					( objectStatus "ddr1_dq(4)" )
				)
				( pin "U2D1.AV79"
					( objectStatus "ddr1_dq(5)" )
				)
				( pin "U2D1.AR82"
					( objectStatus "ddr1_dq(6)" )
				)
				( pin "U2D1.AN80"
					( objectStatus "ddr1_dq(7)" )
				)
				( pin "U2D1.AH81"
					( objectStatus "ddr1_dq(8)" )
				)
				( pin "U2D1.AF79"
					( objectStatus "ddr1_dq(9)" )
				)
				( pin "U2D1.AC82"
					( objectStatus "ddr1_dq(10)" )
				)
				( pin "U2D1.AB81"
					( objectStatus "ddr1_dq(11)" )
				)
				( pin "U2D1.AJ80"
					( objectStatus "ddr1_dq(12)" )
				)
				( pin "U2D1.AH79"
					( objectStatus "ddr1_dq(13)" )
				)
				( pin "U2D1.AE82"
					( objectStatus "ddr1_dq(14)" )
				)
				( pin "U2D1.AC80"
					( objectStatus "ddr1_dq(15)" )
				)
				( pin "U2D1.E80"
					( objectStatus "ddr1_dq(16)" )
				)
				( pin "U2D1.J80"
					( objectStatus "ddr1_dq(17)" )
				)
				( pin "U2D1.F77"
					( objectStatus "ddr1_dq(18)" )
				)
				( pin "U2D1.H77"
					( objectStatus "ddr1_dq(19)" )
				)
				( pin "U2D1.F81"
					( objectStatus "ddr1_dq(20)" )
				)
				( pin "U2D1.H81"
					( objectStatus "ddr1_dq(21)" )
				)
				( pin "U2D1.E78"
					( objectStatus "ddr1_dq(22)" )
				)
				( pin "U2D1.J78"
					( objectStatus "ddr1_dq(23)" )
				)
				( pin "U2D1.D75"
					( objectStatus "ddr1_dq(24)" )
				)
				( pin "U2D1.C74"
					( objectStatus "ddr1_dq(25)" )
				)
				( pin "U2D1.D71"
					( objectStatus "ddr1_dq(26)" )
				)
				( pin "U2D1.F71"
					( objectStatus "ddr1_dq(27)" )
				)
				( pin "U2D1.F75"
					( objectStatus "ddr1_dq(28)" )
				)
				( pin "U2D1.G74"
					( objectStatus "ddr1_dq(29)" )
				)
				( pin "U2D1.C72"
					( objectStatus "ddr1_dq(30)" )
				)
				( pin "U2D1.G72"
					( objectStatus "ddr1_dq(31)" )
				)
				( pin "U2D1.K43"
					( objectStatus "ddr1_dq(32)" )
				)
				( pin "U2D1.H43"
					( objectStatus "ddr1_dq(33)" )
				)
				( pin "U2D1.L40"
					( objectStatus "ddr1_dq(34)" )
				)
				( pin "U2D1.N40"
					( objectStatus "ddr1_dq(35)" )
				)
				( pin "U2D1.P43"
					( objectStatus "ddr1_dq(36)" )
				)
				( pin "U2D1.T43"
					( objectStatus "ddr1_dq(37)" )
				)
				( pin "U2D1.K41"
					( objectStatus "ddr1_dq(38)" )
				)
				( pin "U2D1.P41"
					( objectStatus "ddr1_dq(39)" )
				)
				( pin "U2D1.C36"
					( objectStatus "ddr1_dq(40)" )
				)
				( pin "U2D1.B35"
					( objectStatus "ddr1_dq(41)" )
				)
				( pin "U2D1.C32"
					( objectStatus "ddr1_dq(42)" )
				)
				( pin "U2D1.E32"
					( objectStatus "ddr1_dq(43)" )
				)
				( pin "U2D1.E36"
					( objectStatus "ddr1_dq(44)" )
				)
				( pin "U2D1.F35"
					( objectStatus "ddr1_dq(45)" )
				)
				( pin "U2D1.B33"
					( objectStatus "ddr1_dq(46)" )
				)
				( pin "U2D1.F33"
					( objectStatus "ddr1_dq(47)" )
				)
				( pin "U2D1.C30"
					( objectStatus "ddr1_dq(48)" )
				)
				( pin "U2D1.B29"
					( objectStatus "ddr1_dq(49)" )
				)
				( pin "U2D1.C26"
					( objectStatus "ddr1_dq(50)" )
				)
				( pin "U2D1.E26"
					( objectStatus "ddr1_dq(51)" )
				)
				( pin "U2D1.E30"
					( objectStatus "ddr1_dq(52)" )
				)
				( pin "U2D1.F29"
					( objectStatus "ddr1_dq(53)" )
				)
				( pin "U2D1.B27"
					( objectStatus "ddr1_dq(54)" )
				)
				( pin "U2D1.F27"
					( objectStatus "ddr1_dq(55)" )
				)
				( pin "U2D1.U28"
					( objectStatus "ddr1_dq(56)" )
				)
				( pin "U2D1.AA28"
					( objectStatus "ddr1_dq(57)" )
				)
				( pin "U2D1.V25"
					( objectStatus "ddr1_dq(58)" )
				)
				( pin "U2D1.Y25"
					( objectStatus "ddr1_dq(59)" )
				)
				( pin "U2D1.V29"
					( objectStatus "ddr1_dq(60)" )
				)
				( pin "U2D1.Y29"
					( objectStatus "ddr1_dq(61)" )
				)
				( pin "U2D1.U26"
					( objectStatus "ddr1_dq(62)" )
				)
				( pin "U2D1.AA26"
					( objectStatus "ddr1_dq(63)" )
				)
				( pin "U2D1.AP79"
					( objectStatus "ddr1_dqs_dn(0)" )
				)
				( pin "U2D1.AD79"
					( objectStatus "ddr1_dqs_dn(1)" )
				)
				( pin "U2D1.K79"
					( objectStatus "ddr1_dqs_dn(2)" )
				)
				( pin "U2D1.H73"
					( objectStatus "ddr1_dqs_dn(3)" )
				)
				( pin "U2D1.N42"
					( objectStatus "ddr1_dqs_dn(4)" )
				)
				( pin "U2D1.G34"
					( objectStatus "ddr1_dqs_dn(5)" )
				)
				( pin "U2D1.G28"
					( objectStatus "ddr1_dqs_dn(6)" )
				)
				( pin "U2D1.AB27"
					( objectStatus "ddr1_dqs_dn(7)" )
				)
				( pin "U2D1.N68"
					( objectStatus "ddr1_dqs_dn(8)" )
				)
				( pin "U2D1.AU82"
					( objectStatus "ddr1_dqs_dn(9)" )
				)
				( pin "U2D1.AG82"
					( objectStatus "ddr1_dqs_dn(10)" )
				)
				( pin "U2D1.D79"
					( objectStatus "ddr1_dqs_dn(11)" )
				)
				( pin "U2D1.B73"
					( objectStatus "ddr1_dqs_dn(12)" )
				)
				( pin "U2D1.J42"
					( objectStatus "ddr1_dqs_dn(13)" )
				)
				( pin "U2D1.A34"
					( objectStatus "ddr1_dqs_dn(14)" )
				)
				( pin "U2D1.A28"
					( objectStatus "ddr1_dqs_dn(15)" )
				)
				( pin "U2D1.T27"
					( objectStatus "ddr1_dqs_dn(16)" )
				)
				( pin "U2D1.G68"
					( objectStatus "ddr1_dqs_dn(17)" )
				)
				( pin "U2D1.AR80"
					( objectStatus "ddr1_dqs_dp(0)" )
				)
				( pin "U2D1.AE80"
					( objectStatus "ddr1_dqs_dp(1)" )
				)
				( pin "U2D1.H79"
					( objectStatus "ddr1_dqs_dp(2)" )
				)
				( pin "U2D1.F73"
					( objectStatus "ddr1_dqs_dp(3)" )
				)
				( pin "U2D1.R42"
					( objectStatus "ddr1_dqs_dp(4)" )
				)
				( pin "U2D1.E34"
					( objectStatus "ddr1_dqs_dp(5)" )
				)
				( pin "U2D1.E28"
					( objectStatus "ddr1_dqs_dp(6)" )
				)
				( pin "U2D1.Y27"
					( objectStatus "ddr1_dqs_dp(7)" )
				)
				( pin "U2D1.L68"
					( objectStatus "ddr1_dqs_dp(8)" )
				)
				( pin "U2D1.AT81"
					( objectStatus "ddr1_dqs_dp(9)" )
				)
				( pin "U2D1.AF81"
					( objectStatus "ddr1_dqs_dp(10)" )
				)
				( pin "U2D1.F79"
					( objectStatus "ddr1_dqs_dp(11)" )
				)
				( pin "U2D1.D73"
					( objectStatus "ddr1_dqs_dp(12)" )
				)
				( pin "U2D1.L42"
					( objectStatus "ddr1_dqs_dp(13)" )
				)
				( pin "U2D1.C34"
					( objectStatus "ddr1_dqs_dp(14)" )
				)
				( pin "U2D1.C28"
					( objectStatus "ddr1_dqs_dp(15)" )
				)
				( pin "U2D1.V27"
					( objectStatus "ddr1_dqs_dp(16)" )
				)
				( pin "U2D1.J68"
					( objectStatus "ddr1_dqs_dp(17)" )
				)
				( pin "U2D1.J70"
					( objectStatus "ddr1_ecc(0)" )
				)
				( pin "U2D1.H69"
					( objectStatus "ddr1_ecc(1)" )
				)
				( pin "U2D1.J66"
					( objectStatus "ddr1_ecc(2)" )
				)
				( pin "U2D1.L66"
					( objectStatus "ddr1_ecc(3)" )
				)
				( pin "U2D1.L70"
					( objectStatus "ddr1_ecc(4)" )
				)
				( pin "U2D1.M69"
					( objectStatus "ddr1_ecc(5)" )
				)
				( pin "U2D1.H67"
					( objectStatus "ddr1_ecc(6)" )
				)
				( pin "U2D1.M67"
					( objectStatus "ddr1_ecc(7)" )
				)
				( pin "U2D1.J52"
					( objectStatus "ddr1_ma(0)" )
				)
				( pin "U2D1.J58"
					( objectStatus "ddr1_ma(1)" )
				)
				( pin "U2D1.K57"
					( objectStatus "ddr1_ma(2)" )
				)
				( pin "U2D1.N58"
					( objectStatus "ddr1_ma(3)" )
				)
				( pin "U2D1.M59"
					( objectStatus "ddr1_ma(4)" )
				)
				( pin "U2D1.R58"
					( objectStatus "ddr1_ma(5)" )
				)
				( pin "U2D1.T59"
					( objectStatus "ddr1_ma(6)" )
				)
				( pin "U2D1.V61"
					( objectStatus "ddr1_ma(7)" )
				)
				( pin "U2D1.W60"
					( objectStatus "ddr1_ma(8)" )
				)
				( pin "U2D1.K59"
					( objectStatus "ddr1_ma(9)" )
				)
				( pin "U2D1.M55"
					( objectStatus "ddr1_ma(10)" )
				)
				( pin "U2D1.R60"
					( objectStatus "ddr1_ma(11)" )
				)
				( pin "U2D1.T61"
					( objectStatus "ddr1_ma(12)" )
				)
				( pin "U2D1.M51"
					( objectStatus "ddr1_ma(13)" )
				)
				( pin "U2D1.T51"
					( objectStatus "ddr1_ma(14)" )
				)
				( pin "U2D1.N52"
					( objectStatus "ddr1_ma(15)" )
				)
				( pin "U2D1.R52"
					( objectStatus "ddr1_ma(16)" )
				)
				( pin "U2D1.N48"
					( objectStatus "ddr1_ma(17)" )
				)
				( pin "U2D1.N50"
					( objectStatus "ddr1_odt(0)" )
				)
				( pin "U2D1.R48"
					( objectStatus "ddr1_odt(1)" )
				)
				( pin "U2D1.M49"
					( objectStatus "ddr1_odt(2)" )
				)
				( pin "U2D1.T47"
					( objectStatus "ddr1_odt(3)" )
				)
				( pin "U2D1.K53"
					( objectStatus "ddr1_par" )
				)
			)
			( gate "U2D1"
				( objectStatus "@baseboard_fab2_lib.baseboard_fab2(sch_1):page59_i172" )
				( pin "U2D1.AB61"
					( objectStatus "ddr2_act_n" )
				)
				( pin "U2D1.AD61"
					( objectStatus "ddr2_alert_n" )
				)
				( pin "U2D1.W52"
					( objectStatus "ddr2_ba(0)" )
				)
				( pin "U2D1.AE56"
					( objectStatus "ddr2_ba(1)" )
				)
				( pin "U2D1.AA60"
					( objectStatus "ddr2_bg(0)" )
				)
				( pin "U2D1.AE62"
					( objectStatus "ddr2_bg(1)" )
				)
				( pin "U2D1.AB45"
					( objectStatus "ddr2_cid(2)" )
				)
				( pin "U2D1.AA62"
					( objectStatus "ddr2_cke(0)" )
				)
				( pin "U2D1.AD63"
					( objectStatus "ddr2_cke(1)" )
				)
				( pin "U2D1.V63"
					( objectStatus "ddr2_cke(2)" )
				)
				( pin "U2D1.AB63"
					( objectStatus "ddr2_cke(3)" )
				)
				( pin "U2D1.AA54"
					( objectStatus "ddr2_clk_dn(0)" )
				)
				( pin "U2D1.W54"
					( objectStatus "ddr2_clk_dn(1)" )
				)
				( pin "U2D1.AA56"
					( objectStatus "ddr2_clk_dn(2)" )
				)
				( pin "U2D1.W56"
					( objectStatus "ddr2_clk_dn(3)" )
				)
				( pin "U2D1.AB55"
					( objectStatus "ddr2_clk_dp(0)" )
				)
				( pin "U2D1.V55"
					( objectStatus "ddr2_clk_dp(1)" )
				)
				( pin "U2D1.AB57"
					( objectStatus "ddr2_clk_dp(2)" )
				)
				( pin "U2D1.V57"
					( objectStatus "ddr2_clk_dp(3)" )
				)
				( pin "U2D1.V51"
					( objectStatus "ddr2_cs_n(0)" )
				)
				( pin "U2D1.AB49"
					( objectStatus "ddr2_cs_n(1)" )
				)
				( pin "U2D1.W46"
					( objectStatus "ddr2_cs_n(2)" )
				)
				( pin "U2D1.AA46"
					( objectStatus "ddr2_cs_n(3)" )
				)
				( pin "U2D1.AB51"
					( objectStatus "ddr2_cs_n(4)" )
				)
				( pin "U2D1.W48"
					( objectStatus "ddr2_cs_n(5)" )
				)
				( pin "U2D1.T45"
					( objectStatus "ddr2_cs_n(6)" )
				)
				( pin "U2D1.V45"
					( objectStatus "ddr2_cs_n(7)" )
				)
				( pin "U2D1.AR76"
					( objectStatus "ddr2_dq(0)" )
				)
				( pin "U2D1.AN74"
					( objectStatus "ddr2_dq(1)" )
				)
				( pin "U2D1.AK77"
					( objectStatus "ddr2_dq(2)" )
				)
				( pin "U2D1.AJ76"
					( objectStatus "ddr2_dq(3)" )
				)
				( pin "U2D1.AT75"
					( objectStatus "ddr2_dq(4)" )
				)
				( pin "U2D1.AR74"
					( objectStatus "ddr2_dq(5)" )
				)
				( pin "U2D1.AM77"
					( objectStatus "ddr2_dq(6)" )
				)
				( pin "U2D1.AK75"
					( objectStatus "ddr2_dq(7)" )
				)
				( pin "U2D1.AE76"
					( objectStatus "ddr2_dq(8)" )
				)
				( pin "U2D1.AC74"
					( objectStatus "ddr2_dq(9)" )
				)
				( pin "U2D1.Y77"
					( objectStatus "ddr2_dq(10)" )
				)
				( pin "U2D1.W76"
					( objectStatus "ddr2_dq(11)" )
				)
				( pin "U2D1.AF75"
					( objectStatus "ddr2_dq(12)" )
				)
				( pin "U2D1.AE74"
					( objectStatus "ddr2_dq(13)" )
				)
				( pin "U2D1.AB77"
					( objectStatus "ddr2_dq(14)" )
				)
				( pin "U2D1.Y75"
					( objectStatus "ddr2_dq(15)" )
				)
				( pin "U2D1.W72"
					( objectStatus "ddr2_dq(16)" )
				)
				( pin "U2D1.AA70"
					( objectStatus "ddr2_dq(17)" )
				)
				( pin "U2D1.R70"
					( objectStatus "ddr2_dq(18)" )
				)
				( pin "U2D1.T69"
					( objectStatus "ddr2_dq(19)" )
				)
				( pin "U2D1.AA72"
					( objectStatus "ddr2_dq(20)" )
				)
				( pin "U2D1.AB71"
					( objectStatus "ddr2_dq(21)" )
				)
				( pin "U2D1.T71"
					( objectStatus "ddr2_dq(22)" )
				)
				( pin "U2D1.V69"
					( objectStatus "ddr2_dq(23)" )
				)
				( pin "U2D1.AM67"
					( objectStatus "ddr2_dq(24)" )
				)
				( pin "U2D1.AT67"
					( objectStatus "ddr2_dq(25)" )
				)
				( pin "U2D1.AN64"
					( objectStatus "ddr2_dq(26)" )
				)
				( pin "U2D1.AR64"
					( objectStatus "ddr2_dq(27)" )
				)
				( pin "U2D1.AN68"
					( objectStatus "ddr2_dq(28)" )
				)
				( pin "U2D1.AR68"
					( objectStatus "ddr2_dq(29)" )
				)
				( pin "U2D1.AM65"
					( objectStatus "ddr2_dq(30)" )
				)
				( pin "U2D1.AT65"
					( objectStatus "ddr2_dq(31)" )
				)
				( pin "U2D1.U40"
					( objectStatus "ddr2_dq(32)" )
				)
				( pin "U2D1.AA40"
					( objectStatus "ddr2_dq(33)" )
				)
				( pin "U2D1.V37"
					( objectStatus "ddr2_dq(34)" )
				)
				( pin "U2D1.Y37"
					( objectStatus "ddr2_dq(35)" )
				)
				( pin "U2D1.V41"
					( objectStatus "ddr2_dq(36)" )
				)
				( pin "U2D1.Y41"
					( objectStatus "ddr2_dq(37)" )
				)
				( pin "U2D1.U38"
					( objectStatus "ddr2_dq(38)" )
				)
				( pin "U2D1.AA38"
					( objectStatus "ddr2_dq(39)" )
				)
				( pin "U2D1.U34"
					( objectStatus "ddr2_dq(40)" )
				)
				( pin "U2D1.AA34"
					( objectStatus "ddr2_dq(41)" )
				)
				( pin "U2D1.V31"
					( objectStatus "ddr2_dq(42)" )
				)
				( pin "U2D1.Y31"
					( objectStatus "ddr2_dq(43)" )
				)
				( pin "U2D1.V35"
					( objectStatus "ddr2_dq(44)" )
				)
				( pin "U2D1.Y35"
					( objectStatus "ddr2_dq(45)" )
				)
				( pin "U2D1.U32"
					( objectStatus "ddr2_dq(46)" )
				)
				( pin "U2D1.AA32"
					( objectStatus "ddr2_dq(47)" )
				)
				( pin "U2D1.AD31"
					( objectStatus "ddr2_dq(48)" )
				)
				( pin "U2D1.AH31"
					( objectStatus "ddr2_dq(49)" )
				)
				( pin "U2D1.AE28"
					( objectStatus "ddr2_dq(50)" )
				)
				( pin "U2D1.AG28"
					( objectStatus "ddr2_dq(51)" )
				)
				( pin "U2D1.AE32"
					( objectStatus "ddr2_dq(52)" )
				)
				( pin "U2D1.AG32"
					( objectStatus "ddr2_dq(53)" )
				)
				( pin "U2D1.AD29"
					( objectStatus "ddr2_dq(54)" )
				)
				( pin "U2D1.AH29"
					( objectStatus "ddr2_dq(55)" )
				)
				( pin "U2D1.AD25"
					( objectStatus "ddr2_dq(56)" )
				)
				( pin "U2D1.AH25"
					( objectStatus "ddr2_dq(57)" )
				)
				( pin "U2D1.AE22"
					( objectStatus "ddr2_dq(58)" )
				)
				( pin "U2D1.AG22"
					( objectStatus "ddr2_dq(59)" )
				)
				( pin "U2D1.AE26"
					( objectStatus "ddr2_dq(60)" )
				)
				( pin "U2D1.AG26"
					( objectStatus "ddr2_dq(61)" )
				)
				( pin "U2D1.AD23"
					( objectStatus "ddr2_dq(62)" )
				)
				( pin "U2D1.AH23"
					( objectStatus "ddr2_dq(63)" )
				)
				( pin "U2D1.AL74"
					( objectStatus "ddr2_dqs_dn(0)" )
				)
				( pin "U2D1.AA74"
					( objectStatus "ddr2_dqs_dn(1)" )
				)
				( pin "U2D1.Y69"
					( objectStatus "ddr2_dqs_dn(2)" )
				)
				( pin "U2D1.AU66"
					( objectStatus "ddr2_dqs_dn(3)" )
				)
				( pin "U2D1.AB39"
					( objectStatus "ddr2_dqs_dn(4)" )
				)
				( pin "U2D1.AB33"
					( objectStatus "ddr2_dqs_dn(5)" )
				)
				( pin "U2D1.AJ30"
					( objectStatus "ddr2_dqs_dn(6)" )
				)
				( pin "U2D1.AJ24"
					( objectStatus "ddr2_dqs_dn(7)" )
				)
				( pin "U2D1.BB71"
					( objectStatus "ddr2_dqs_dn(8)" )
				)
				( pin "U2D1.AP77"
					( objectStatus "ddr2_dqs_dn(9)" )
				)
				( pin "U2D1.AD77"
					( objectStatus "ddr2_dqs_dn(10)" )
				)
				( pin "U2D1.U72"
					( objectStatus "ddr2_dqs_dn(11)" )
				)
				( pin "U2D1.AL66"
					( objectStatus "ddr2_dqs_dn(12)" )
				)
				( pin "U2D1.T39"
					( objectStatus "ddr2_dqs_dn(13)" )
				)
				( pin "U2D1.T33"
					( objectStatus "ddr2_dqs_dn(14)" )
				)
				( pin "U2D1.AC30"
					( objectStatus "ddr2_dqs_dn(15)" )
				)
				( pin "U2D1.AC24"
					( objectStatus "ddr2_dqs_dn(16)" )
				)
				( pin "U2D1.AT71"
					( objectStatus "ddr2_dqs_dn(17)" )
				)
				( pin "U2D1.AM75"
					( objectStatus "ddr2_dqs_dp(0)" )
				)
				( pin "U2D1.AB75"
					( objectStatus "ddr2_dqs_dp(1)" )
				)
				( pin "U2D1.W70"
					( objectStatus "ddr2_dqs_dp(2)" )
				)
				( pin "U2D1.AR66"
					( objectStatus "ddr2_dqs_dp(3)" )
				)
				( pin "U2D1.Y39"
					( objectStatus "ddr2_dqs_dp(4)" )
				)
				( pin "U2D1.Y33"
					( objectStatus "ddr2_dqs_dp(5)" )
				)
				( pin "U2D1.AG30"
					( objectStatus "ddr2_dqs_dp(6)" )
				)
				( pin "U2D1.AG24"
					( objectStatus "ddr2_dqs_dp(7)" )
				)
				( pin "U2D1.AY71"
					( objectStatus "ddr2_dqs_dp(8)" )
				)
				( pin "U2D1.AN76"
					( objectStatus "ddr2_dqs_dp(9)" )
				)
				( pin "U2D1.AC76"
					( objectStatus "ddr2_dqs_dp(10)" )
				)
				( pin "U2D1.V71"
					( objectStatus "ddr2_dqs_dp(11)" )
				)
				( pin "U2D1.AN66"
					( objectStatus "ddr2_dqs_dp(12)" )
				)
				( pin "U2D1.V39"
					( objectStatus "ddr2_dqs_dp(13)" )
				)
				( pin "U2D1.V33"
					( objectStatus "ddr2_dqs_dp(14)" )
				)
				( pin "U2D1.AE30"
					( objectStatus "ddr2_dqs_dp(15)" )
				)
				( pin "U2D1.AE24"
					( objectStatus "ddr2_dqs_dp(16)" )
				)
				( pin "U2D1.AV71"
					( objectStatus "ddr2_dqs_dp(17)" )
				)
				( pin "U2D1.AU72"
					( objectStatus "ddr2_ecc(0)" )
				)
				( pin "U2D1.BA72"
					( objectStatus "ddr2_ecc(1)" )
				)
				( pin "U2D1.AV69"
					( objectStatus "ddr2_ecc(2)" )
				)
				( pin "U2D1.AY69"
					( objectStatus "ddr2_ecc(3)" )
				)
				( pin "U2D1.AV73"
					( objectStatus "ddr2_ecc(4)" )
				)
				( pin "U2D1.AY73"
					( objectStatus "ddr2_ecc(5)" )
				)
				( pin "U2D1.AU70"
					( objectStatus "ddr2_ecc(6)" )
				)
				( pin "U2D1.BA70"
					( objectStatus "ddr2_ecc(7)" )
				)
				( pin "U2D1.AB53"
					( objectStatus "ddr2_ma(0)" )
				)
				( pin "U2D1.AE58"
					( objectStatus "ddr2_ma(1)" )
				)
				( pin "U2D1.AD57"
					( objectStatus "ddr2_ma(2)" )
				)
				( pin "U2D1.W58"
					( objectStatus "ddr2_ma(3)" )
				)
				( pin "U2D1.AA58"
					( objectStatus "ddr2_ma(4)" )
				)
				( pin "U2D1.V59"
					( objectStatus "ddr2_ma(5)" )
				)
				( pin "U2D1.AB59"
					( objectStatus "ddr2_ma(6)" )
				)
				( pin "U2D1.AE60"
					( objectStatus "ddr2_ma(7)" )
				)
				( pin "U2D1.AD59"
					( objectStatus "ddr2_ma(8)" )
				)
				( pin "U2D1.AG58"
					( objectStatus "ddr2_ma(9)" )
				)
				( pin "U2D1.AD55"
					( objectStatus "ddr2_ma(10)" )
				)
				( pin "U2D1.AG60"
					( objectStatus "ddr2_ma(11)" )
				)
				( pin "U2D1.AG62"
					( objectStatus "ddr2_ma(12)" )
				)
				( pin "U2D1.AD53"
					( objectStatus "ddr2_ma(13)" )
				)
				( pin "U2D1.W50"
					( objectStatus "ddr2_ma(14)" )
				)
				( pin "U2D1.AE54"
					( objectStatus "ddr2_ma(15)" )
				)
				( pin "U2D1.AA52"
					( objectStatus "ddr2_ma(16)" )
				)
				( pin "U2D1.AC46"
					( objectStatus "ddr2_ma(17)" )
				)
				( pin "U2D1.AA50"
					( objectStatus "ddr2_odt(0)" )
				)
				( pin "U2D1.AA48"
					( objectStatus "ddr2_odt(1)" )
				)
				( pin "U2D1.V49"
					( objectStatus "ddr2_odt(2)" )
				)
				( pin "U2D1.AB47"
					( objectStatus "ddr2_odt(3)" )
				)
				( pin "U2D1.V53"
					( objectStatus "ddr2_par" )
				)
			)
			( gate "U2D1"
				( objectStatus "@baseboard_fab2_lib.baseboard_fab2(sch_1):page60_i172" )
				( pin "U2D1.DW60"
					( objectStatus "ddr3_act_n" )
				)
				( pin "U2D1.ED63"
					( objectStatus "ddr3_alert_n" )
				)
				( pin "U2D1.EE52"
					( objectStatus "ddr3_ba(0)" )
				)
				( pin "U2D1.EA54"
					( objectStatus "ddr3_ba(1)" )
				)
				( pin "U2D1.ED61"
					( objectStatus "ddr3_bg(0)" )
				)
				( pin "U2D1.DW62"
					( objectStatus "ddr3_bg(1)" )
				)
				( pin "U2D1.DV47"
					( objectStatus "ddr3_cid(2)" )
				)
				( pin "U2D1.EE62"
					( objectStatus "ddr3_cke(0)" )
				)
				( pin "U2D1.EF63"
					( objectStatus "ddr3_cke(1)" )
				)
				( pin "U2D1.EA62"
					( objectStatus "ddr3_cke(2)" )
				)
				( pin "U2D1.EB63"
					( objectStatus "ddr3_cke(3)" )
				)
				( pin "U2D1.ED55"
					( objectStatus "ddr3_clk_dn(0)" )
				)
				( pin "U2D1.EF55"
					( objectStatus "ddr3_clk_dn(1)" )
				)
				( pin "U2D1.DW56"
					( objectStatus "ddr3_clk_dn(2)" )
				)
				( pin "U2D1.EF57"
					( objectStatus "ddr3_clk_dn(3)" )
				)
				( pin "U2D1.EB55"
					( objectStatus "ddr3_clk_dp(0)" )
				)
				( pin "U2D1.EE54"
					( objectStatus "ddr3_clk_dp(1)" )
				)
				( pin "U2D1.EA56"
					( objectStatus "ddr3_clk_dp(2)" )
				)
				( pin "U2D1.EE56"
					( objectStatus "ddr3_clk_dp(3)" )
				)
				( pin "U2D1.EF51"
					( objectStatus "ddr3_cs_n(0)" )
				)
				( pin "U2D1.ED49"
					( objectStatus "ddr3_cs_n(1)" )
				)
				( pin "U2D1.ED47"
					( objectStatus "ddr3_cs_n(2)" )
				)
				( pin "U2D1.EB47"
					( objectStatus "ddr3_cs_n(3)" )
				)
				( pin "U2D1.EB51"
					( objectStatus "ddr3_cs_n(4)" )
				)
				( pin "U2D1.EB49"
					( objectStatus "ddr3_cs_n(5)" )
				)
				( pin "U2D1.DV45"
					( objectStatus "ddr3_cs_n(6)" )
				)
				( pin "U2D1.EB45"
					( objectStatus "ddr3_cs_n(7)" )
				)
				( pin "U2D1.CN84"
					( objectStatus "ddr3_dq(0)" )
				)
				( pin "U2D1.CN86"
					( objectStatus "ddr3_dq(1)" )
				)
				( pin "U2D1.DA86"
					( objectStatus "ddr3_dq(2)" )
				)
				( pin "U2D1.DA84"
					( objectStatus "ddr3_dq(3)" )
				)
				( pin "U2D1.CL84"
					( objectStatus "ddr3_dq(4)" )
				)
				( pin "U2D1.CL86"
					( objectStatus "ddr3_dq(5)" )
				)
				( pin "U2D1.CW86"
					( objectStatus "ddr3_dq(6)" )
				)
				( pin "U2D1.CW84"
					( objectStatus "ddr3_dq(7)" )
				)
				( pin "U2D1.DG84"
					( objectStatus "ddr3_dq(8)" )
				)
				( pin "U2D1.DH85"
					( objectStatus "ddr3_dq(9)" )
				)
				( pin "U2D1.DV83"
					( objectStatus "ddr3_dq(10)" )
				)
				( pin "U2D1.DY83"
					( objectStatus "ddr3_dq(11)" )
				)
				( pin "U2D1.DD85"
					( objectStatus "ddr3_dq(12)" )
				)
				( pin "U2D1.DE84"
					( objectStatus "ddr3_dq(13)" )
				)
				( pin "U2D1.DR84"
					( objectStatus "ddr3_dq(14)" )
				)
				( pin "U2D1.DV85"
					( objectStatus "ddr3_dq(15)" )
				)
				( pin "U2D1.DM79"
					( objectStatus "ddr3_dq(16)" )
				)
				( pin "U2D1.DK81"
					( objectStatus "ddr3_dq(17)" )
				)
				( pin "U2D1.DT81"
					( objectStatus "ddr3_dq(18)" )
				)
				( pin "U2D1.DR82"
					( objectStatus "ddr3_dq(19)" )
				)
				( pin "U2D1.DK79"
					( objectStatus "ddr3_dq(20)" )
				)
				( pin "U2D1.DJ80"
					( objectStatus "ddr3_dq(21)" )
				)
				( pin "U2D1.DR80"
					( objectStatus "ddr3_dq(22)" )
				)
				( pin "U2D1.DN82"
					( objectStatus "ddr3_dq(23)" )
				)
				( pin "U2D1.DN76"
					( objectStatus "ddr3_dq(24)" )
				)
				( pin "U2D1.DU76"
					( objectStatus "ddr3_dq(25)" )
				)
				( pin "U2D1.DP73"
					( objectStatus "ddr3_dq(26)" )
				)
				( pin "U2D1.DT73"
					( objectStatus "ddr3_dq(27)" )
				)
				( pin "U2D1.DP77"
					( objectStatus "ddr3_dq(28)" )
				)
				( pin "U2D1.DT77"
					( objectStatus "ddr3_dq(29)" )
				)
				( pin "U2D1.DN74"
					( objectStatus "ddr3_dq(30)" )
				)
				( pin "U2D1.DU74"
					( objectStatus "ddr3_dq(31)" )
				)
				( pin "U2D1.EC40"
					( objectStatus "ddr3_dq(32)" )
				)
				( pin "U2D1.ED39"
					( objectStatus "ddr3_dq(33)" )
				)
				( pin "U2D1.EA36"
					( objectStatus "ddr3_dq(34)" )
				)
				( pin "U2D1.EC36"
					( objectStatus "ddr3_dq(35)" )
				)
				( pin "U2D1.DY39"
					( objectStatus "ddr3_dq(36)" )
				)
				( pin "U2D1.EA40"
					( objectStatus "ddr3_dq(37)" )
				)
				( pin "U2D1.DY37"
					( objectStatus "ddr3_dq(38)" )
				)
				( pin "U2D1.ED37"
					( objectStatus "ddr3_dq(39)" )
				)
				( pin "U2D1.DN36"
					( objectStatus "ddr3_dq(40)" )
				)
				( pin "U2D1.DU36"
					( objectStatus "ddr3_dq(41)" )
				)
				( pin "U2D1.DP33"
					( objectStatus "ddr3_dq(42)" )
				)
				( pin "U2D1.DT33"
					( objectStatus "ddr3_dq(43)" )
				)
				( pin "U2D1.DP37"
					( objectStatus "ddr3_dq(44)" )
				)
				( pin "U2D1.DT37"
					( objectStatus "ddr3_dq(45)" )
				)
				( pin "U2D1.DN34"
					( objectStatus "ddr3_dq(46)" )
				)
				( pin "U2D1.DU34"
					( objectStatus "ddr3_dq(47)" )
				)
				( pin "U2D1.DN30"
					( objectStatus "ddr3_dq(48)" )
				)
				( pin "U2D1.DU30"
					( objectStatus "ddr3_dq(49)" )
				)
				( pin "U2D1.DP27"
					( objectStatus "ddr3_dq(50)" )
				)
				( pin "U2D1.DT27"
					( objectStatus "ddr3_dq(51)" )
				)
				( pin "U2D1.DP31"
					( objectStatus "ddr3_dq(52)" )
				)
				( pin "U2D1.DT31"
					( objectStatus "ddr3_dq(53)" )
				)
				( pin "U2D1.DN28"
					( objectStatus "ddr3_dq(54)" )
				)
				( pin "U2D1.DU28"
					( objectStatus "ddr3_dq(55)" )
				)
				( pin "U2D1.DN24"
					( objectStatus "ddr3_dq(56)" )
				)
				( pin "U2D1.DU24"
					( objectStatus "ddr3_dq(57)" )
				)
				( pin "U2D1.DY21"
					( objectStatus "ddr3_dq(58)" )
				)
				( pin "U2D1.EB21"
					( objectStatus "ddr3_dq(59)" )
				)
				( pin "U2D1.DP25"
					( objectStatus "ddr3_dq(60)" )
				)
				( pin "U2D1.DT25"
					( objectStatus "ddr3_dq(61)" )
				)
				( pin "U2D1.EC22"
					( objectStatus "ddr3_dq(62)" )
				)
				( pin "U2D1.DW22"
					( objectStatus "ddr3_dq(63)" )
				)
				( pin "U2D1.CU84"
					( objectStatus "ddr3_dqs_dn(0)" )
				)
				( pin "U2D1.DN84"
					( objectStatus "ddr3_dqs_dn(1)" )
				)
				( pin "U2D1.DL82"
					( objectStatus "ddr3_dqs_dn(2)" )
				)
				( pin "U2D1.DV75"
					( objectStatus "ddr3_dqs_dn(3)" )
				)
				( pin "U2D1.EE38"
					( objectStatus "ddr3_dqs_dn(4)" )
				)
				( pin "U2D1.DV35"
					( objectStatus "ddr3_dqs_dn(5)" )
				)
				( pin "U2D1.DV29"
					( objectStatus "ddr3_dqs_dn(6)" )
				)
				( pin "U2D1.DV23"
					( objectStatus "ddr3_dqs_dn(7)" )
				)
				( pin "U2D1.DF67"
					( objectStatus "ddr3_dqs_dn(8)" )
				)
				( pin "U2D1.CR84"
					( objectStatus "ddr3_dqs_dn(9)" )
				)
				( pin "U2D1.DM85"
					( objectStatus "ddr3_dqs_dn(10)" )
				)
				( pin "U2D1.DN80"
					( objectStatus "ddr3_dqs_dn(11)" )
				)
				( pin "U2D1.DP75"
					( objectStatus "ddr3_dqs_dn(12)" )
				)
				( pin "U2D1.EA38"
					( objectStatus "ddr3_dqs_dn(13)" )
				)
				( pin "U2D1.DP35"
					( objectStatus "ddr3_dqs_dn(14)" )
				)
				( pin "U2D1.DM29"
					( objectStatus "ddr3_dqs_dn(15)" )
				)
				( pin "U2D1.DM23"
					( objectStatus "ddr3_dqs_dn(16)" )
				)
				( pin "U2D1.DB67"
					( objectStatus "ddr3_dqs_dn(17)" )
				)
				( pin "U2D1.CV85"
					( objectStatus "ddr3_dqs_dp(0)" )
				)
				( pin "U2D1.DP85"
					( objectStatus "ddr3_dqs_dp(1)" )
				)
				( pin "U2D1.DM81"
					( objectStatus "ddr3_dqs_dp(2)" )
				)
				( pin "U2D1.DT75"
					( objectStatus "ddr3_dqs_dp(3)" )
				)
				( pin "U2D1.EC38"
					( objectStatus "ddr3_dqs_dp(4)" )
				)
				( pin "U2D1.DT35"
					( objectStatus "ddr3_dqs_dp(5)" )
				)
				( pin "U2D1.DT29"
					( objectStatus "ddr3_dqs_dp(6)" )
				)
				( pin "U2D1.DT23"
					( objectStatus "ddr3_dqs_dp(7)" )
				)
				( pin "U2D1.DD67"
					( objectStatus "ddr3_dqs_dp(8)" )
				)
				( pin "U2D1.CP85"
					( objectStatus "ddr3_dqs_dp(9)" )
				)
				( pin "U2D1.DL84"
					( objectStatus "ddr3_dqs_dp(10)" )
				)
				( pin "U2D1.DP79"
					( objectStatus "ddr3_dqs_dp(11)" )
				)
				( pin "U2D1.DM75"
					( objectStatus "ddr3_dqs_dp(12)" )
				)
				( pin "U2D1.DW38"
					( objectStatus "ddr3_dqs_dp(13)" )
				)
				( pin "U2D1.DM35"
					( objectStatus "ddr3_dqs_dp(14)" )
				)
				( pin "U2D1.DP29"
					( objectStatus "ddr3_dqs_dp(15)" )
				)
				( pin "U2D1.DP23"
					( objectStatus "ddr3_dqs_dp(16)" )
				)
				( pin "U2D1.CY67"
					( objectStatus "ddr3_dqs_dp(17)" )
				)
				( pin "U2D1.DA68"
					( objectStatus "ddr3_ecc(0)" )
				)
				( pin "U2D1.DE68"
					( objectStatus "ddr3_ecc(1)" )
				)
				( pin "U2D1.DB65"
					( objectStatus "ddr3_ecc(2)" )
				)
				( pin "U2D1.DD65"
					( objectStatus "ddr3_ecc(3)" )
				)
				( pin "U2D1.DB69"
					( objectStatus "ddr3_ecc(4)" )
				)
				( pin "U2D1.DD69"
					( objectStatus "ddr3_ecc(5)" )
				)
				( pin "U2D1.DA66"
					( objectStatus "ddr3_ecc(6)" )
				)
				( pin "U2D1.DE66"
					( objectStatus "ddr3_ecc(7)" )
				)
				( pin "U2D1.EB53"
					( objectStatus "ddr3_ma(0)" )
				)
				( pin "U2D1.ED57"
					( objectStatus "ddr3_ma(1)" )
				)
				( pin "U2D1.EE58"
					( objectStatus "ddr3_ma(2)" )
				)
				( pin "U2D1.EB57"
					( objectStatus "ddr3_ma(3)" )
				)
				( pin "U2D1.ED59"
					( objectStatus "ddr3_ma(4)" )
				)
				( pin "U2D1.EA58"
					( objectStatus "ddr3_ma(5)" )
				)
				( pin "U2D1.EE60"
					( objectStatus "ddr3_ma(6)" )
				)
				( pin "U2D1.EA60"
					( objectStatus "ddr3_ma(7)" )
				)
				( pin "U2D1.EB59"
					( objectStatus "ddr3_ma(8)" )
				)
				( pin "U2D1.EF61"
					( objectStatus "ddr3_ma(9)" )
				)
				( pin "U2D1.DW54"
					( objectStatus "ddr3_ma(10)" )
				)
				( pin "U2D1.EB61"
					( objectStatus "ddr3_ma(11)" )
				)
				( pin "U2D1.DT63"
					( objectStatus "ddr3_ma(12)" )
				)
				( pin "U2D1.DW48"
					( objectStatus "ddr3_ma(13)" )
				)
				( pin "U2D1.ED51"
					( objectStatus "ddr3_ma(14)" )
				)
				( pin "U2D1.DV49"
					( objectStatus "ddr3_ma(15)" )
				)
				( pin "U2D1.EA52"
					( objectStatus "ddr3_ma(16)" )
				)
				( pin "U2D1.EA46"
					( objectStatus "ddr3_ma(17)" )
				)
				( pin "U2D1.EE50"
					( objectStatus "ddr3_odt(0)" )
				)
				( pin "U2D1.EE48"
					( objectStatus "ddr3_odt(1)" )
				)
				( pin "U2D1.EA50"
					( objectStatus "ddr3_odt(2)" )
				)
				( pin "U2D1.EA48"
					( objectStatus "ddr3_odt(3)" )
				)
				( pin "U2D1.ED53"
					( objectStatus "ddr3_par" )
				)
			)
			( gate "U2D1"
				( objectStatus "@baseboard_fab2_lib.baseboard_fab2(sch_1):page61_i172" )
				( pin "U2D1.DR62"
					( objectStatus "ddr4_act_n" )
				)
				( pin "U2D1.DT61"
					( objectStatus "ddr4_alert_n" )
				)
				( pin "U2D1.DM53"
					( objectStatus "ddr4_ba(0)" )
				)
				( pin "U2D1.DV55"
					( objectStatus "ddr4_ba(1)" )
				)
				( pin "U2D1.DJ62"
					( objectStatus "ddr4_bg(0)" )
				)
				( pin "U2D1.DM61"
					( objectStatus "ddr4_bg(1)" )
				)
				( pin "U2D1.DT47"
					( objectStatus "ddr4_cid(2)" )
				)
				( pin "U2D1.DM63"
					( objectStatus "ddr4_cke(0)" )
				)
				( pin "U2D1.DN64"
					( objectStatus "ddr4_cke(1)" )
				)
				( pin "U2D1.DL64"
					( objectStatus "ddr4_cke(2)" )
				)
				( pin "U2D1.DR64"
					( objectStatus "ddr4_cke(3)" )
				)
				( pin "U2D1.DM55"
					( objectStatus "ddr4_clk_dn(0)" )
				)
				( pin "U2D1.DR54"
					( objectStatus "ddr4_clk_dn(1)" )
				)
				( pin "U2D1.DM57"
					( objectStatus "ddr4_clk_dn(2)" )
				)
				( pin "U2D1.DT57"
					( objectStatus "ddr4_clk_dn(3)" )
				)
				( pin "U2D1.DN54"
					( objectStatus "ddr4_clk_dp(0)" )
				)
				( pin "U2D1.DT53"
					( objectStatus "ddr4_clk_dp(1)" )
				)
				( pin "U2D1.DN56"
					( objectStatus "ddr4_clk_dp(2)" )
				)
				( pin "U2D1.DR56"
					( objectStatus "ddr4_clk_dp(3)" )
				)
				( pin "U2D1.DV51"
					( objectStatus "ddr4_cs_n(0)" )
				)
				( pin "U2D1.DN50"
					( objectStatus "ddr4_cs_n(1)" )
				)
				( pin "U2D1.DR46"
					( objectStatus "ddr4_cs_n(2)" )
				)
				( pin "U2D1.DK47"
					( objectStatus "ddr4_cs_n(3)" )
				)
				( pin "U2D1.DW50"
					( objectStatus "ddr4_cs_n(4)" )
				)
				( pin "U2D1.DM49"
					( objectStatus "ddr4_cs_n(5)" )
				)
				( pin "U2D1.DT45"
					( objectStatus "ddr4_cs_n(6)" )
				)
				( pin "U2D1.DN46"
					( objectStatus "ddr4_cs_n(7)" )
				)
				( pin "U2D1.CM79"
					( objectStatus "ddr4_dq(0)" )
				)
				( pin "U2D1.CK81"
					( objectStatus "ddr4_dq(1)" )
				)
				( pin "U2D1.CT81"
					( objectStatus "ddr4_dq(2)" )
				)
				( pin "U2D1.CR82"
					( objectStatus "ddr4_dq(3)" )
				)
				( pin "U2D1.CK79"
					( objectStatus "ddr4_dq(4)" )
				)
				( pin "U2D1.CJ80"
					( objectStatus "ddr4_dq(5)" )
				)
				( pin "U2D1.CR80"
					( objectStatus "ddr4_dq(6)" )
				)
				( pin "U2D1.CN82"
					( objectStatus "ddr4_dq(7)" )
				)
				( pin "U2D1.DB79"
					( objectStatus "ddr4_dq(8)" )
				)
				( pin "U2D1.CY81"
					( objectStatus "ddr4_dq(9)" )
				)
				( pin "U2D1.DE80"
					( objectStatus "ddr4_dq(10)" )
				)
				( pin "U2D1.DF81"
					( objectStatus "ddr4_dq(11)" )
				)
				( pin "U2D1.CY79"
					( objectStatus "ddr4_dq(12)" )
				)
				( pin "U2D1.CW80"
					( objectStatus "ddr4_dq(13)" )
				)
				( pin "U2D1.DC82"
					( objectStatus "ddr4_dq(14)" )
				)
				( pin "U2D1.DE82"
					( objectStatus "ddr4_dq(15)" )
				)
				( pin "U2D1.DW80"
					( objectStatus "ddr4_dq(16)" )
				)
				( pin "U2D1.EC80"
					( objectStatus "ddr4_dq(17)" )
				)
				( pin "U2D1.DY77"
					( objectStatus "ddr4_dq(18)" )
				)
				( pin "U2D1.EB77"
					( objectStatus "ddr4_dq(19)" )
				)
				( pin "U2D1.DY81"
					( objectStatus "ddr4_dq(20)" )
				)
				( pin "U2D1.EB81"
					( objectStatus "ddr4_dq(21)" )
				)
				( pin "U2D1.DW78"
					( objectStatus "ddr4_dq(22)" )
				)
				( pin "U2D1.EC78"
					( objectStatus "ddr4_dq(23)" )
				)
				( pin "U2D1.ED75"
					( objectStatus "ddr4_dq(24)" )
				)
				( pin "U2D1.EE74"
					( objectStatus "ddr4_dq(25)" )
				)
				( pin "U2D1.EB71"
					( objectStatus "ddr4_dq(26)" )
				)
				( pin "U2D1.ED71"
					( objectStatus "ddr4_dq(27)" )
				)
				( pin "U2D1.EA74"
					( objectStatus "ddr4_dq(28)" )
				)
				( pin "U2D1.EB75"
					( objectStatus "ddr4_dq(29)" )
				)
				( pin "U2D1.EA72"
					( objectStatus "ddr4_dq(30)" )
				)
				( pin "U2D1.EE72"
					( objectStatus "ddr4_dq(31)" )
				)
				( pin "U2D1.DU42"
					( objectStatus "ddr4_dq(32)" )
				)
				( pin "U2D1.DW42"
					( objectStatus "ddr4_dq(33)" )
				)
				( pin "U2D1.DP39"
					( objectStatus "ddr4_dq(34)" )
				)
				( pin "U2D1.DT39"
					( objectStatus "ddr4_dq(35)" )
				)
				( pin "U2D1.DL42"
					( objectStatus "ddr4_dq(36)" )
				)
				( pin "U2D1.DN42"
					( objectStatus "ddr4_dq(37)" )
				)
				( pin "U2D1.DN40"
					( objectStatus "ddr4_dq(38)" )
				)
				( pin "U2D1.DU40"
					( objectStatus "ddr4_dq(39)" )
				)
				( pin "U2D1.EC34"
					( objectStatus "ddr4_dq(40)" )
				)
				( pin "U2D1.ED33"
					( objectStatus "ddr4_dq(41)" )
				)
				( pin "U2D1.EA30"
					( objectStatus "ddr4_dq(42)" )
				)
				( pin "U2D1.EC30"
					( objectStatus "ddr4_dq(43)" )
				)
				( pin "U2D1.DY33"
					( objectStatus "ddr4_dq(44)" )
				)
				( pin "U2D1.EA34"
					( objectStatus "ddr4_dq(45)" )
				)
				( pin "U2D1.DY31"
					( objectStatus "ddr4_dq(46)" )
				)
				( pin "U2D1.ED31"
					( objectStatus "ddr4_dq(47)" )
				)
				( pin "U2D1.EC28"
					( objectStatus "ddr4_dq(48)" )
				)
				( pin "U2D1.ED27"
					( objectStatus "ddr4_dq(49)" )
				)
				( pin "U2D1.EA24"
					( objectStatus "ddr4_dq(50)" )
				)
				( pin "U2D1.EC24"
					( objectStatus "ddr4_dq(51)" )
				)
				( pin "U2D1.DY27"
					( objectStatus "ddr4_dq(52)" )
				)
				( pin "U2D1.EA28"
					( objectStatus "ddr4_dq(53)" )
				)
				( pin "U2D1.DY25"
					( objectStatus "ddr4_dq(54)" )
				)
				( pin "U2D1.ED25"
					( objectStatus "ddr4_dq(55)" )
				)
				( pin "U2D1.DF27"
					( objectStatus "ddr4_dq(56)" )
				)
				( pin "U2D1.DK27"
					( objectStatus "ddr4_dq(57)" )
				)
				( pin "U2D1.DD25"
					( objectStatus "ddr4_dq(58)" )
				)
				( pin "U2D1.DJ24"
					( objectStatus "ddr4_dq(59)" )
				)
				( pin "U2D1.DG28"
					( objectStatus "ddr4_dq(60)" )
				)
				( pin "U2D1.DJ28"
					( objectStatus "ddr4_dq(61)" )
				)
				( pin "U2D1.DF25"
					( objectStatus "ddr4_dq(62)" )
				)
				( pin "U2D1.DK25"
					( objectStatus "ddr4_dq(63)" )
				)
				( pin "U2D1.CL82"
					( objectStatus "ddr4_dqs_dn(0)" )
				)
				( pin "U2D1.DA82"
					( objectStatus "ddr4_dqs_dn(1)" )
				)
				( pin "U2D1.ED79"
					( objectStatus "ddr4_dqs_dn(2)" )
				)
				( pin "U2D1.EF73"
					( objectStatus "ddr4_dqs_dn(3)" )
				)
				( pin "U2D1.DV41"
					( objectStatus "ddr4_dqs_dn(4)" )
				)
				( pin "U2D1.EE32"
					( objectStatus "ddr4_dqs_dn(5)" )
				)
				( pin "U2D1.EE26"
					( objectStatus "ddr4_dqs_dn(6)" )
				)
				( pin "U2D1.DL26"
					( objectStatus "ddr4_dqs_dn(7)" )
				)
				( pin "U2D1.EB67"
					( objectStatus "ddr4_dqs_dn(8)" )
				)
				( pin "U2D1.CN80"
					( objectStatus "ddr4_dqs_dn(9)" )
				)
				( pin "U2D1.DC80"
					( objectStatus "ddr4_dqs_dn(10)" )
				)
				( pin "U2D1.DY79"
					( objectStatus "ddr4_dqs_dn(11)" )
				)
				( pin "U2D1.EB73"
					( objectStatus "ddr4_dqs_dn(12)" )
				)
				( pin "U2D1.DP41"
					( objectStatus "ddr4_dqs_dn(13)" )
				)
				( pin "U2D1.EA32"
					( objectStatus "ddr4_dqs_dn(14)" )
				)
				( pin "U2D1.EA26"
					( objectStatus "ddr4_dqs_dn(15)" )
				)
				( pin "U2D1.DG26"
					( objectStatus "ddr4_dqs_dn(16)" )
				)
				( pin "U2D1.DV67"
					( objectStatus "ddr4_dqs_dn(17)" )
				)
				( pin "U2D1.CM81"
					( objectStatus "ddr4_dqs_dp(0)" )
				)
				( pin "U2D1.DB81"
					( objectStatus "ddr4_dqs_dp(1)" )
				)
				( pin "U2D1.EB79"
					( objectStatus "ddr4_dqs_dp(2)" )
				)
				( pin "U2D1.ED73"
					( objectStatus "ddr4_dqs_dp(3)" )
				)
				( pin "U2D1.DT41"
					( objectStatus "ddr4_dqs_dp(4)" )
				)
				( pin "U2D1.EC32"
					( objectStatus "ddr4_dqs_dp(5)" )
				)
				( pin "U2D1.EC26"
					( objectStatus "ddr4_dqs_dp(6)" )
				)
				( pin "U2D1.DJ26"
					( objectStatus "ddr4_dqs_dp(7)" )
				)
				( pin "U2D1.DY67"
					( objectStatus "ddr4_dqs_dp(8)" )
				)
				( pin "U2D1.CP79"
					( objectStatus "ddr4_dqs_dp(9)" )
				)
				( pin "U2D1.DD79"
					( objectStatus "ddr4_dqs_dp(10)" )
				)
				( pin "U2D1.DV79"
					( objectStatus "ddr4_dqs_dp(11)" )
				)
				( pin "U2D1.DY73"
					( objectStatus "ddr4_dqs_dp(12)" )
				)
				( pin "U2D1.DM41"
					( objectStatus "ddr4_dqs_dp(13)" )
				)
				( pin "U2D1.DW32"
					( objectStatus "ddr4_dqs_dp(14)" )
				)
				( pin "U2D1.DW26"
					( objectStatus "ddr4_dqs_dp(15)" )
				)
				( pin "U2D1.DE26"
					( objectStatus "ddr4_dqs_dp(16)" )
				)
				( pin "U2D1.DT67"
					( objectStatus "ddr4_dqs_dp(17)" )
				)
				( pin "U2D1.DY69"
					( objectStatus "ddr4_ecc(0)" )
				)
				( pin "U2D1.EA68"
					( objectStatus "ddr4_ecc(1)" )
				)
				( pin "U2D1.DV65"
					( objectStatus "ddr4_ecc(2)" )
				)
				( pin "U2D1.DY65"
					( objectStatus "ddr4_ecc(3)" )
				)
				( pin "U2D1.DU68"
					( objectStatus "ddr4_ecc(4)" )
				)
				( pin "U2D1.DV69"
					( objectStatus "ddr4_ecc(5)" )
				)
				( pin "U2D1.DU66"
					( objectStatus "ddr4_ecc(6)" )
				)
				( pin "U2D1.EA66"
					( objectStatus "ddr4_ecc(7)" )
				)
				( pin "U2D1.DW52"
					( objectStatus "ddr4_ma(0)" )
				)
				( pin "U2D1.DW58"
					( objectStatus "ddr4_ma(1)" )
				)
				( pin "U2D1.DV57"
					( objectStatus "ddr4_ma(2)" )
				)
				( pin "U2D1.DR58"
					( objectStatus "ddr4_ma(3)" )
				)
				( pin "U2D1.DT59"
					( objectStatus "ddr4_ma(4)" )
				)
				( pin "U2D1.DN58"
					( objectStatus "ddr4_ma(5)" )
				)
				( pin "U2D1.DM59"
					( objectStatus "ddr4_ma(6)" )
				)
				( pin "U2D1.DK61"
					( objectStatus "ddr4_ma(7)" )
				)
				( pin "U2D1.DJ60"
					( objectStatus "ddr4_ma(8)" )
				)
				( pin "U2D1.DV59"
					( objectStatus "ddr4_ma(9)" )
				)
				( pin "U2D1.DT55"
					( objectStatus "ddr4_ma(10)" )
				)
				( pin "U2D1.DR60"
					( objectStatus "ddr4_ma(11)" )
				)
				( pin "U2D1.DN60"
					( objectStatus "ddr4_ma(12)" )
				)
				( pin "U2D1.DT51"
					( objectStatus "ddr4_ma(13)" )
				)
				( pin "U2D1.DM51"
					( objectStatus "ddr4_ma(14)" )
				)
				( pin "U2D1.DR52"
					( objectStatus "ddr4_ma(15)" )
				)
				( pin "U2D1.DN52"
					( objectStatus "ddr4_ma(16)" )
				)
				( pin "U2D1.DR48"
					( objectStatus "ddr4_ma(17)" )
				)
				( pin "U2D1.DR50"
					( objectStatus "ddr4_odt(0)" )
				)
				( pin "U2D1.DN48"
					( objectStatus "ddr4_odt(1)" )
				)
				( pin "U2D1.DT49"
					( objectStatus "ddr4_odt(2)" )
				)
				( pin "U2D1.DM47"
					( objectStatus "ddr4_odt(3)" )
				)
				( pin "U2D1.DV53"
					( objectStatus "ddr4_par" )
				)
			)
			( gate "U2D1"
				( objectStatus "@baseboard_fab2_lib.baseboard_fab2(sch_1):page62_i172" )
				( pin "U2D1.DC62"
					( objectStatus "ddr5_act_n" )
				)
				( pin "U2D1.DD61"
					( objectStatus "ddr5_alert_n" )
				)
				( pin "U2D1.DJ52"
					( objectStatus "ddr5_ba(0)" )
				)
				( pin "U2D1.DC56"
					( objectStatus "ddr5_ba(1)" )
				)
				( pin "U2D1.DA62"
					( objectStatus "ddr5_bg(0)" )
				)
				( pin "U2D1.DF61"
					( objectStatus "ddr5_bg(1)" )
				)
				( pin "U2D1.DF45"
					( objectStatus "ddr5_cid(2)" )
				)
				( pin "U2D1.DG62"
					( objectStatus "ddr5_cke(0)" )
				)
				( pin "U2D1.DD63"
					( objectStatus "ddr5_cke(1)" )
				)
				( pin "U2D1.DK63"
					( objectStatus "ddr5_cke(2)" )
				)
				( pin "U2D1.DF63"
					( objectStatus "ddr5_cke(3)" )
				)
				( pin "U2D1.DK55"
					( objectStatus "ddr5_clk_dn(0)" )
				)
				( pin "U2D1.DF55"
					( objectStatus "ddr5_clk_dn(1)" )
				)
				( pin "U2D1.DK57"
					( objectStatus "ddr5_clk_dn(2)" )
				)
				( pin "U2D1.DF57"
					( objectStatus "ddr5_clk_dn(3)" )
				)
				( pin "U2D1.DJ54"
					( objectStatus "ddr5_clk_dp(0)" )
				)
				( pin "U2D1.DG54"
					( objectStatus "ddr5_clk_dp(1)" )
				)
				( pin "U2D1.DJ56"
					( objectStatus "ddr5_clk_dp(2)" )
				)
				( pin "U2D1.DG56"
					( objectStatus "ddr5_clk_dp(3)" )
				)
				( pin "U2D1.DK51"
					( objectStatus "ddr5_cs_n(0)" )
				)
				( pin "U2D1.DF49"
					( objectStatus "ddr5_cs_n(1)" )
				)
				( pin "U2D1.DJ46"
					( objectStatus "ddr5_cs_n(2)" )
				)
				( pin "U2D1.DG46"
					( objectStatus "ddr5_cs_n(3)" )
				)
				( pin "U2D1.DF51"
					( objectStatus "ddr5_cs_n(4)" )
				)
				( pin "U2D1.DJ48"
					( objectStatus "ddr5_cs_n(5)" )
				)
				( pin "U2D1.DM45"
					( objectStatus "ddr5_cs_n(6)" )
				)
				( pin "U2D1.DK45"
					( objectStatus "ddr5_cs_n(7)" )
				)
				( pin "U2D1.CR74"
					( objectStatus "ddr5_dq(0)" )
				)
				( pin "U2D1.CN76"
					( objectStatus "ddr5_dq(1)" )
				)
				( pin "U2D1.CW76"
					( objectStatus "ddr5_dq(2)" )
				)
				( pin "U2D1.CV77"
					( objectStatus "ddr5_dq(3)" )
				)
				( pin "U2D1.CN74"
					( objectStatus "ddr5_dq(4)" )
				)
				( pin "U2D1.CM75"
					( objectStatus "ddr5_dq(5)" )
				)
				( pin "U2D1.CV75"
					( objectStatus "ddr5_dq(6)" )
				)
				( pin "U2D1.CT77"
					( objectStatus "ddr5_dq(7)" )
				)
				( pin "U2D1.DE74"
					( objectStatus "ddr5_dq(8)" )
				)
				( pin "U2D1.DC76"
					( objectStatus "ddr5_dq(9)" )
				)
				( pin "U2D1.DH75"
					( objectStatus "ddr5_dq(10)" )
				)
				( pin "U2D1.DJ76"
					( objectStatus "ddr5_dq(11)" )
				)
				( pin "U2D1.DC74"
					( objectStatus "ddr5_dq(12)" )
				)
				( pin "U2D1.DB75"
					( objectStatus "ddr5_dq(13)" )
				)
				( pin "U2D1.DF77"
					( objectStatus "ddr5_dq(14)" )
				)
				( pin "U2D1.DH77"
					( objectStatus "ddr5_dq(15)" )
				)
				( pin "U2D1.DG70"
					( objectStatus "ddr5_dq(16)" )
				)
				( pin "U2D1.DJ72"
					( objectStatus "ddr5_dq(17)" )
				)
				( pin "U2D1.DM69"
					( objectStatus "ddr5_dq(18)" )
				)
				( pin "U2D1.DN70"
					( objectStatus "ddr5_dq(19)" )
				)
				( pin "U2D1.DF71"
					( objectStatus "ddr5_dq(20)" )
				)
				( pin "U2D1.DG72"
					( objectStatus "ddr5_dq(21)" )
				)
				( pin "U2D1.DK69"
					( objectStatus "ddr5_dq(22)" )
				)
				( pin "U2D1.DM71"
					( objectStatus "ddr5_dq(23)" )
				)
				( pin "U2D1.CN66"
					( objectStatus "ddr5_dq(24)" )
				)
				( pin "U2D1.CU66"
					( objectStatus "ddr5_dq(25)" )
				)
				( pin "U2D1.CP63"
					( objectStatus "ddr5_dq(26)" )
				)
				( pin "U2D1.CT63"
					( objectStatus "ddr5_dq(27)" )
				)
				( pin "U2D1.CP67"
					( objectStatus "ddr5_dq(28)" )
				)
				( pin "U2D1.CT67"
					( objectStatus "ddr5_dq(29)" )
				)
				( pin "U2D1.CN64"
					( objectStatus "ddr5_dq(30)" )
				)
				( pin "U2D1.CU64"
					( objectStatus "ddr5_dq(31)" )
				)
				( pin "U2D1.DD41"
					( objectStatus "ddr5_dq(32)" )
				)
				( pin "U2D1.DG42"
					( objectStatus "ddr5_dq(33)" )
				)
				( pin "U2D1.DE38"
					( objectStatus "ddr5_dq(34)" )
				)
				( pin "U2D1.DG38"
					( objectStatus "ddr5_dq(35)" )
				)
				( pin "U2D1.DA42"
					( objectStatus "ddr5_dq(36)" )
				)
				( pin "U2D1.DE42"
					( objectStatus "ddr5_dq(37)" )
				)
				( pin "U2D1.DD39"
					( objectStatus "ddr5_dq(38)" )
				)
				( pin "U2D1.DH39"
					( objectStatus "ddr5_dq(39)" )
				)
				( pin "U2D1.DF33"
					( objectStatus "ddr5_dq(40)" )
				)
				( pin "U2D1.DK33"
					( objectStatus "ddr5_dq(41)" )
				)
				( pin "U2D1.DG30"
					( objectStatus "ddr5_dq(42)" )
				)
				( pin "U2D1.DJ30"
					( objectStatus "ddr5_dq(43)" )
				)
				( pin "U2D1.DG34"
					( objectStatus "ddr5_dq(44)" )
				)
				( pin "U2D1.DJ34"
					( objectStatus "ddr5_dq(45)" )
				)
				( pin "U2D1.DF31"
					( objectStatus "ddr5_dq(46)" )
				)
				( pin "U2D1.DK31"
					( objectStatus "ddr5_dq(47)" )
				)
				( pin "U2D1.CW36"
					( objectStatus "ddr5_dq(48)" )
				)
				( pin "U2D1.DC36"
					( objectStatus "ddr5_dq(49)" )
				)
				( pin "U2D1.CY33"
					( objectStatus "ddr5_dq(50)" )
				)
				( pin "U2D1.DB33"
					( objectStatus "ddr5_dq(51)" )
				)
				( pin "U2D1.CY37"
					( objectStatus "ddr5_dq(52)" )
				)
				( pin "U2D1.DB37"
					( objectStatus "ddr5_dq(53)" )
				)
				( pin "U2D1.CW34"
					( objectStatus "ddr5_dq(54)" )
				)
				( pin "U2D1.DC34"
					( objectStatus "ddr5_dq(55)" )
				)
				( pin "U2D1.CW30"
					( objectStatus "ddr5_dq(56)" )
				)
				( pin "U2D1.DC30"
					( objectStatus "ddr5_dq(57)" )
				)
				( pin "U2D1.CY27"
					( objectStatus "ddr5_dq(58)" )
				)
				( pin "U2D1.DB27"
					( objectStatus "ddr5_dq(59)" )
				)
				( pin "U2D1.CY31"
					( objectStatus "ddr5_dq(60)" )
				)
				( pin "U2D1.DB31"
					( objectStatus "ddr5_dq(61)" )
				)
				( pin "U2D1.CW28"
					( objectStatus "ddr5_dq(62)" )
				)
				( pin "U2D1.DC28"
					( objectStatus "ddr5_dq(63)" )
				)
				( pin "U2D1.CP77"
					( objectStatus "ddr5_dqs_dn(0)" )
				)
				( pin "U2D1.DD77"
					( objectStatus "ddr5_dqs_dn(1)" )
				)
				( pin "U2D1.DL72"
					( objectStatus "ddr5_dqs_dn(2)" )
				)
				( pin "U2D1.CV65"
					( objectStatus "ddr5_dqs_dn(3)" )
				)
				( pin "U2D1.DG40"
					( objectStatus "ddr5_dqs_dn(4)" )
				)
				( pin "U2D1.DL32"
					( objectStatus "ddr5_dqs_dn(5)" )
				)
				( pin "U2D1.DD35"
					( objectStatus "ddr5_dqs_dn(6)" )
				)
				( pin "U2D1.DD29"
					( objectStatus "ddr5_dqs_dn(7)" )
				)
				( pin "U2D1.CN70"
					( objectStatus "ddr5_dqs_dn(8)" )
				)
				( pin "U2D1.CT75"
					( objectStatus "ddr5_dqs_dn(9)" )
				)
				( pin "U2D1.DF75"
					( objectStatus "ddr5_dqs_dn(10)" )
				)
				( pin "U2D1.DJ70"
					( objectStatus "ddr5_dqs_dn(11)" )
				)
				( pin "U2D1.CP65"
					( objectStatus "ddr5_dqs_dn(12)" )
				)
				( pin "U2D1.DE40"
					( objectStatus "ddr5_dqs_dn(13)" )
				)
				( pin "U2D1.DG32"
					( objectStatus "ddr5_dqs_dn(14)" )
				)
				( pin "U2D1.CY35"
					( objectStatus "ddr5_dqs_dn(15)" )
				)
				( pin "U2D1.CY29"
					( objectStatus "ddr5_dqs_dn(16)" )
				)
				( pin "U2D1.CJ70"
					( objectStatus "ddr5_dqs_dn(17)" )
				)
				( pin "U2D1.CR76"
					( objectStatus "ddr5_dqs_dp(0)" )
				)
				( pin "U2D1.DE76"
					( objectStatus "ddr5_dqs_dp(1)" )
				)
				( pin "U2D1.DK71"
					( objectStatus "ddr5_dqs_dp(2)" )
				)
				( pin "U2D1.CT65"
					( objectStatus "ddr5_dqs_dp(3)" )
				)
				( pin "U2D1.DJ40"
					( objectStatus "ddr5_dqs_dp(4)" )
				)
				( pin "U2D1.DJ32"
					( objectStatus "ddr5_dqs_dp(5)" )
				)
				( pin "U2D1.DB35"
					( objectStatus "ddr5_dqs_dp(6)" )
				)
				( pin "U2D1.DB29"
					( objectStatus "ddr5_dqs_dp(7)" )
				)
				( pin "U2D1.CL70"
					( objectStatus "ddr5_dqs_dp(8)" )
				)
				( pin "U2D1.CU74"
					( objectStatus "ddr5_dqs_dp(9)" )
				)
				( pin "U2D1.DG74"
					( objectStatus "ddr5_dqs_dp(10)" )
				)
				( pin "U2D1.DH69"
					( objectStatus "ddr5_dqs_dp(11)" )
				)
				( pin "U2D1.CM65"
					( objectStatus "ddr5_dqs_dp(12)" )
				)
				( pin "U2D1.DC40"
					( objectStatus "ddr5_dqs_dp(13)" )
				)
				( pin "U2D1.DE32"
					( objectStatus "ddr5_dqs_dp(14)" )
				)
				( pin "U2D1.CV35"
					( objectStatus "ddr5_dqs_dp(15)" )
				)
				( pin "U2D1.CV29"
					( objectStatus "ddr5_dqs_dp(16)" )
				)
				( pin "U2D1.CG70"
					( objectStatus "ddr5_dqs_dp(17)" )
				)
				( pin "U2D1.CH71"
					( objectStatus "ddr5_ecc(0)" )
				)
				( pin "U2D1.CM71"
					( objectStatus "ddr5_ecc(1)" )
				)
				( pin "U2D1.CJ68"
					( objectStatus "ddr5_ecc(2)" )
				)
				( pin "U2D1.CL68"
					( objectStatus "ddr5_ecc(3)" )
				)
				( pin "U2D1.CJ72"
					( objectStatus "ddr5_ecc(4)" )
				)
				( pin "U2D1.CL72"
					( objectStatus "ddr5_ecc(5)" )
				)
				( pin "U2D1.CH69"
					( objectStatus "ddr5_ecc(6)" )
				)
				( pin "U2D1.CM69"
					( objectStatus "ddr5_ecc(7)" )
				)
				( pin "U2D1.DF53"
					( objectStatus "ddr5_ma(0)" )
				)
				( pin "U2D1.DC58"
					( objectStatus "ddr5_ma(1)" )
				)
				( pin "U2D1.DD57"
					( objectStatus "ddr5_ma(2)" )
				)
				( pin "U2D1.DG58"
					( objectStatus "ddr5_ma(3)" )
				)
				( pin "U2D1.DJ58"
					( objectStatus "ddr5_ma(4)" )
				)
				( pin "U2D1.DF59"
					( objectStatus "ddr5_ma(5)" )
				)
				( pin "U2D1.DK59"
					( objectStatus "ddr5_ma(6)" )
				)
				( pin "U2D1.DC60"
					( objectStatus "ddr5_ma(7)" )
				)
				( pin "U2D1.DD59"
					( objectStatus "ddr5_ma(8)" )
				)
				( pin "U2D1.DA58"
					( objectStatus "ddr5_ma(9)" )
				)
				( pin "U2D1.DD55"
					( objectStatus "ddr5_ma(10)" )
				)
				( pin "U2D1.DA60"
					( objectStatus "ddr5_ma(11)" )
				)
				( pin "U2D1.DG60"
					( objectStatus "ddr5_ma(12)" )
				)
				( pin "U2D1.DD53"
					( objectStatus "ddr5_ma(13)" )
				)
				( pin "U2D1.DJ50"
					( objectStatus "ddr5_ma(14)" )
				)
				( pin "U2D1.DC54"
					( objectStatus "ddr5_ma(15)" )
				)
				( pin "U2D1.DG52"
					( objectStatus "ddr5_ma(16)" )
				)
				( pin "U2D1.DE46"
					( objectStatus "ddr5_ma(17)" )
				)
				( pin "U2D1.DG50"
					( objectStatus "ddr5_odt(0)" )
				)
				( pin "U2D1.DG48"
					( objectStatus "ddr5_odt(1)" )
				)
				( pin "U2D1.DK49"
					( objectStatus "ddr5_odt(2)" )
				)
				( pin "U2D1.DF47"
					( objectStatus "ddr5_odt(3)" )
				)
				( pin "U2D1.DK53"
					( objectStatus "ddr5_par" )
				)
			)
			( gate "U2D1"
				( objectStatus "@baseboard_fab2_lib.baseboard_fab2(sch_1):page63_i23" )
				( pin "U2D1.BN22"
					( objectStatus "cd_hfi0_i2cclk" )
				)
				( pin "U2D1.BP23"
					( objectStatus "cd_hfi0_i2cdat" )
				)
				( pin "U2D1.BP19"
					( objectStatus "cd_hfi0_int_n" )
				)
				( pin "U2D1.BK21"
					( objectStatus "cd_hfi0_led_n" )
				)
				( pin "U2D1.BR20"
					( objectStatus "cd_hfi0_modprst_n" )
				)
				( pin "U2D1.BN24"
					( objectStatus "cd_hfi0_reset_n" )
				)
				( pin "U2D1.BJ22"
					( objectStatus "cd_hfi1_i2cclk" )
				)
				( pin "U2D1.BH23"
					( objectStatus "cd_hfi1_i2cdat" )
				)
				( pin "U2D1.BM21"
					( objectStatus "cd_hfi1_int_n" )
				)
				( pin "U2D1.BM23"
					( objectStatus "cd_hfi1_led_n" )
				)
				( pin "U2D1.BT19"
					( objectStatus "cd_hfi1_modprst_n" )
				)
				( pin "U2D1.BK23"
					( objectStatus "cd_hfi1_reset_n" )
				)
				( pin "U2D1.BE16"
					( objectStatus "cd_hfi_refclk_dn" )
				)
				( pin "U2D1.BG16"
					( objectStatus "cd_hfi_refclk_dp" )
				)
				( pin "U2D1.BU24"
					( objectStatus "cd_pe_refclk_dn" )
				)
				( pin "U2D1.BW24"
					( objectStatus "cd_pe_refclk_dp" )
				)
				( pin "U2D1.CF25"
					( objectStatus "cd_por_n" )
				)
				( pin "U2D1.CB23"
					( objectStatus "cd_tclk" )
				)
				( pin "U2D1.BY21"
					( objectStatus "cd_tdi" )
				)
				( pin "U2D1.CC22"
					( objectStatus "cd_tdo" )
				)
				( pin "U2D1.CE24"
					( objectStatus "cd_tms" )
				)
				( pin "U2D1.CD23"
					( objectStatus "cd_trst_n" )
				)
				( pin "U2D1.CK9"
					( objectStatus "dmi_rx_dn(0)" )
				)
				( pin "U2D1.CM11"
					( objectStatus "dmi_rx_dn(1)" )
				)
				( pin "U2D1.CR12"
					( objectStatus "dmi_rx_dn(2)" )
				)
				( pin "U2D1.CT11"
					( objectStatus "dmi_rx_dn(3)" )
				)
				( pin "U2D1.CL10"
					( objectStatus "dmi_rx_dp(0)" )
				)
				( pin "U2D1.CN10"
					( objectStatus "dmi_rx_dp(1)" )
				)
				( pin "U2D1.CP11"
					( objectStatus "dmi_rx_dp(2)" )
				)
				( pin "U2D1.CV11"
					( objectStatus "dmi_rx_dp(3)" )
				)
				( pin "U2D1.CG4"
					( objectStatus "dmi_tx_dn(0)" )
				)
				( pin "U2D1.CJ4"
					( objectStatus "dmi_tx_dn(1)" )
				)
				( pin "U2D1.CN4"
					( objectStatus "dmi_tx_dn(2)" )
				)
				( pin "U2D1.CP5"
					( objectStatus "dmi_tx_dn(3)" )
				)
				( pin "U2D1.CH5"
					( objectStatus "dmi_tx_dp(0)" )
				)
				( pin "U2D1.CL4"
					( objectStatus "dmi_tx_dp(1)" )
				)
				( pin "U2D1.CM3"
					( objectStatus "dmi_tx_dp(2)" )
				)
				( pin "U2D1.CR4"
					( objectStatus "dmi_tx_dp(3)" )
				)
				( pin "U2D1.BA76"
					( objectStatus "rsvd(172)" )
				)
				( pin "U2D1.BA66"
					( objectStatus "rsvd(173)" )
				)
				( pin "U2D1.BA64"
					( objectStatus "rsvd(174)" )
				)
				( pin "U2D1.BA22"
					( objectStatus "rsvd(175)" )
				)
				( pin "U2D1.BA18"
					( objectStatus "rsvd(176)" )
				)
				( pin "U2D1.BA16"
					( objectStatus "rsvd(177)" )
				)
				( pin "U2D1.BA14"
					( objectStatus "rsvd(178)" )
				)
				( pin "U2D1.AY77"
					( objectStatus "rsvd(179)" )
				)
				( pin "U2D1.AY75"
					( objectStatus "rsvd(180)" )
				)
				( pin "U2D1.AY67"
					( objectStatus "rsvd(181)" )
				)
				( pin "U2D1.AY65"
					( objectStatus "rsvd(182)" )
				)
				( pin "U2D1.AW76"
					( objectStatus "rsvd(183)" )
				)
				( pin "U2D1.AW64"
					( objectStatus "rsvd(184)" )
				)
				( pin "U2D1.AV77"
					( objectStatus "rsvd(186)" )
				)
				( pin "U2D1.AT25"
					( objectStatus "rsvd(187)" )
				)
				( pin "U2D1.AT23"
					( objectStatus "rsvd(188)" )
				)
				( pin "U2D1.AT13"
					( objectStatus "rsvd(189)" )
				)
				( pin "U2D1.AR62"
					( objectStatus "rsvd(190)" )
				)
				( pin "U2D1.AR26"
					( objectStatus "rsvd(191)" )
				)
				( pin "U2D1.AR22"
					( objectStatus "rsvd(192)" )
				)
				( pin "U2D1.AR20"
					( objectStatus "rsvd(193)" )
				)
			)
			( gate "U2D1"
				( objectStatus "@baseboard_fab2_lib.baseboard_fab2(sch_1):page64_i68" )
				( pin "U2D1.CW8"
					( objectStatus "pe1_rx_dn(0)" )
				)
				( pin "U2D1.DA8"
					( objectStatus "pe1_rx_dn(1)" )
				)
				( pin "U2D1.DC8"
					( objectStatus "pe1_rx_dn(2)" )
				)
				( pin "U2D1.DC10"
					( objectStatus "pe1_rx_dn(3)" )
				)
				( pin "U2D1.DE10"
					( objectStatus "pe1_rx_dn(4)" )
				)
				( pin "U2D1.DH9"
					( objectStatus "pe1_rx_dn(5)" )
				)
				( pin "U2D1.DK9"
					( objectStatus "pe1_rx_dn(6)" )
				)
				( pin "U2D1.DM9"
					( objectStatus "pe1_rx_dn(7)" )
				)
				( pin "U2D1.DM11"
					( objectStatus "pe1_rx_dn(8)" )
				)
				( pin "U2D1.DP11"
					( objectStatus "pe1_rx_dn(9)" )
				)
				( pin "U2D1.DT11"
					( objectStatus "pe1_rx_dn(10)" )
				)
				( pin "U2D1.DT13"
					( objectStatus "pe1_rx_dn(11)" )
				)
				( pin "U2D1.DV13"
					( objectStatus "pe1_rx_dn(12)" )
				)
				( pin "U2D1.DW14"
					( objectStatus "pe1_rx_dn(13)" )
				)
				( pin "U2D1.DY15"
					( objectStatus "pe1_rx_dn(14)" )
				)
				( pin "U2D1.DU16"
					( objectStatus "pe1_rx_dn(15)" )
				)
				( pin "U2D1.CU8"
					( objectStatus "pe1_rx_dp(0)" )
				)
				( pin "U2D1.CY7"
					( objectStatus "pe1_rx_dp(1)" )
				)
				( pin "U2D1.DB9"
					( objectStatus "pe1_rx_dp(2)" )
				)
				( pin "U2D1.DA10"
					( objectStatus "pe1_rx_dp(3)" )
				)
				( pin "U2D1.DD9"
					( objectStatus "pe1_rx_dp(4)" )
				)
				( pin "U2D1.DF9"
					( objectStatus "pe1_rx_dp(5)" )
				)
				( pin "U2D1.DJ8"
					( objectStatus "pe1_rx_dp(6)" )
				)
				( pin "U2D1.DL10"
					( objectStatus "pe1_rx_dp(7)" )
				)
				( pin "U2D1.DK11"
					( objectStatus "pe1_rx_dp(8)" )
				)
				( pin "U2D1.DN10"
					( objectStatus "pe1_rx_dp(9)" )
				)
				( pin "U2D1.DR12"
					( objectStatus "pe1_rx_dp(10)" )
				)
				( pin "U2D1.DP13"
					( objectStatus "pe1_rx_dp(11)" )
				)
				( pin "U2D1.DU12"
					( objectStatus "pe1_rx_dp(12)" )
				)
				( pin "U2D1.DY13"
					( objectStatus "pe1_rx_dp(13)" )
				)
				( pin "U2D1.DV15"
					( objectStatus "pe1_rx_dp(14)" )
				)
				( pin "U2D1.DT15"
					( objectStatus "pe1_rx_dp(15)" )
				)
				( pin "U2D1.DA2"
					( objectStatus "pe1_tx_dn(0)" )
				)
				( pin "U2D1.DC2"
					( objectStatus "pe1_tx_dn(1)" )
				)
				( pin "U2D1.DE2"
					( objectStatus "pe1_tx_dn(2)" )
				)
				( pin "U2D1.DE4"
					( objectStatus "pe1_tx_dn(3)" )
				)
				( pin "U2D1.DG4"
					( objectStatus "pe1_tx_dn(4)" )
				)
				( pin "U2D1.DK3"
					( objectStatus "pe1_tx_dn(5)" )
				)
				( pin "U2D1.DM3"
					( objectStatus "pe1_tx_dn(6)" )
				)
				( pin "U2D1.DN4"
					( objectStatus "pe1_tx_dn(7)" )
				)
				( pin "U2D1.DT5"
					( objectStatus "pe1_tx_dn(8)" )
				)
				( pin "U2D1.DV3"
					( objectStatus "pe1_tx_dn(9)" )
				)
				( pin "U2D1.DW4"
					( objectStatus "pe1_tx_dn(10)" )
				)
				( pin "U2D1.DU6"
					( objectStatus "pe1_tx_dn(11)" )
				)
				( pin "U2D1.DV7"
					( objectStatus "pe1_tx_dn(12)" )
				)
				( pin "U2D1.DY7"
					( objectStatus "pe1_tx_dn(13)" )
				)
				( pin "U2D1.EA8"
					( objectStatus "pe1_tx_dn(14)" )
				)
				( pin "U2D1.ED9"
					( objectStatus "pe1_tx_dn(15)" )
				)
				( pin "U2D1.CW2"
					( objectStatus "pe1_tx_dp(0)" )
				)
				( pin "U2D1.DB1"
					( objectStatus "pe1_tx_dp(1)" )
				)
				( pin "U2D1.DD3"
					( objectStatus "pe1_tx_dp(2)" )
				)
				( pin "U2D1.DC4"
					( objectStatus "pe1_tx_dp(3)" )
				)
				( pin "U2D1.DF3"
					( objectStatus "pe1_tx_dp(4)" )
				)
				( pin "U2D1.DH3"
					( objectStatus "pe1_tx_dp(5)" )
				)
				( pin "U2D1.DL2"
					( objectStatus "pe1_tx_dp(6)" )
				)
				( pin "U2D1.DP3"
					( objectStatus "pe1_tx_dp(7)" )
				)
				( pin "U2D1.DR4"
					( objectStatus "pe1_tx_dp(8)" )
				)
				( pin "U2D1.DU2"
					( objectStatus "pe1_tx_dp(9)" )
				)
				( pin "U2D1.DU4"
					( objectStatus "pe1_tx_dp(10)" )
				)
				( pin "U2D1.DV5"
					( objectStatus "pe1_tx_dp(11)" )
				)
				( pin "U2D1.DT7"
					( objectStatus "pe1_tx_dp(12)" )
				)
				( pin "U2D1.DW6"
					( objectStatus "pe1_tx_dp(13)" )
				)
				( pin "U2D1.EB7"
					( objectStatus "pe1_tx_dp(14)" )
				)
				( pin "U2D1.EC8"
					( objectStatus "pe1_tx_dp(15)" )
				)
			)
			( gate "U2D1"
				( objectStatus "@baseboard_fab2_lib.baseboard_fab2(sch_1):page65_i68" )
				( pin "U2D1.CT9"
					( objectStatus "pe2_rx_dn(0)" )
				)
				( pin "U2D1.CP9"
					( objectStatus "pe2_rx_dn(1)" )
				)
				( pin "U2D1.CP7"
					( objectStatus "pe2_rx_dn(2)" )
				)
				( pin "U2D1.CM7"
					( objectStatus "pe2_rx_dn(3)" )
				)
				( pin "U2D1.CK7"
					( objectStatus "pe2_rx_dn(4)" )
				)
				( pin "U2D1.CG8"
					( objectStatus "pe2_rx_dn(5)" )
				)
				( pin "U2D1.CE6"
					( objectStatus "pe2_rx_dn(6)" )
				)
				( pin "U2D1.CE8"
					( objectStatus "pe2_rx_dn(7)" )
				)
				( pin "U2D1.BY9"
					( objectStatus "pe2_rx_dn(8)" )
				)
				( pin "U2D1.BY7"
					( objectStatus "pe2_rx_dn(9)" )
				)
				( pin "U2D1.BV7"
					( objectStatus "pe2_rx_dn(10)" )
				)
				( pin "U2D1.BT7"
					( objectStatus "pe2_rx_dn(11)" )
				)
				( pin "U2D1.BR8"
					( objectStatus "pe2_rx_dn(12)" )
				)
				( pin "U2D1.BN8"
					( objectStatus "pe2_rx_dn(13)" )
				)
				( pin "U2D1.BL8"
					( objectStatus "pe2_rx_dn(14)" )
				)
				( pin "U2D1.BK9"
					( objectStatus "pe2_rx_dn(15)" )
				)
				( pin "U2D1.CR8"
					( objectStatus "pe2_rx_dp(0)" )
				)
				( pin "U2D1.CM9"
					( objectStatus "pe2_rx_dp(1)" )
				)
				( pin "U2D1.CN8"
					( objectStatus "pe2_rx_dp(2)" )
				)
				( pin "U2D1.CL6"
					( objectStatus "pe2_rx_dp(3)" )
				)
				( pin "U2D1.CH7"
					( objectStatus "pe2_rx_dp(4)" )
				)
				( pin "U2D1.CF7"
					( objectStatus "pe2_rx_dp(5)" )
				)
				( pin "U2D1.CD7"
					( objectStatus "pe2_rx_dp(6)" )
				)
				( pin "U2D1.CC8"
					( objectStatus "pe2_rx_dp(7)" )
				)
				( pin "U2D1.BV9"
					( objectStatus "pe2_rx_dp(8)" )
				)
				( pin "U2D1.BW8"
					( objectStatus "pe2_rx_dp(9)" )
				)
				( pin "U2D1.BU6"
					( objectStatus "pe2_rx_dp(10)" )
				)
				( pin "U2D1.BP7"
					( objectStatus "pe2_rx_dp(11)" )
				)
				( pin "U2D1.BP9"
					( objectStatus "pe2_rx_dp(12)" )
				)
				( pin "U2D1.BM7"
					( objectStatus "pe2_rx_dp(13)" )
				)
				( pin "U2D1.BJ8"
					( objectStatus "pe2_rx_dp(14)" )
				)
				( pin "U2D1.BJ10"
					( objectStatus "pe2_rx_dp(15)" )
				)
				( pin "U2D1.CY3"
					( objectStatus "pe2_tx_dn(0)" )
				)
				( pin "U2D1.CV3"
					( objectStatus "pe2_tx_dn(1)" )
				)
				( pin "U2D1.CT1"
					( objectStatus "pe2_tx_dn(2)" )
				)
				( pin "U2D1.CT3"
					( objectStatus "pe2_tx_dn(3)" )
				)
				( pin "U2D1.CM1"
					( objectStatus "pe2_tx_dn(4)" )
				)
				( pin "U2D1.CL2"
					( objectStatus "pe2_tx_dn(5)" )
				)
				( pin "U2D1.CG2"
					( objectStatus "pe2_tx_dn(6)" )
				)
				( pin "U2D1.CF3"
					( objectStatus "pe2_tx_dn(7)" )
				)
				( pin "U2D1.CC2"
					( objectStatus "pe2_tx_dn(8)" )
				)
				( pin "U2D1.CB3"
					( objectStatus "pe2_tx_dn(9)" )
				)
				( pin "U2D1.CA4"
					( objectStatus "pe2_tx_dn(10)" )
				)
				( pin "U2D1.BW4"
					( objectStatus "pe2_tx_dn(11)" )
				)
				( pin "U2D1.BU4"
					( objectStatus "pe2_tx_dn(12)" )
				)
				( pin "U2D1.BP5"
					( objectStatus "pe2_tx_dn(13)" )
				)
				( pin "U2D1.BL4"
					( objectStatus "pe2_tx_dn(14)" )
				)
				( pin "U2D1.BM5"
					( objectStatus "pe2_tx_dn(15)" )
				)
				( pin "U2D1.CW4"
					( objectStatus "pe2_tx_dp(0)" )
				)
				( pin "U2D1.CU2"
					( objectStatus "pe2_tx_dp(1)" )
				)
				( pin "U2D1.CR2"
					( objectStatus "pe2_tx_dp(2)" )
				)
				( pin "U2D1.CP3"
					( objectStatus "pe2_tx_dp(3)" )
				)
				( pin "U2D1.CK1"
					( objectStatus "pe2_tx_dp(4)" )
				)
				( pin "U2D1.CK3"
					( objectStatus "pe2_tx_dp(5)" )
				)
				( pin "U2D1.CE2"
					( objectStatus "pe2_tx_dp(6)" )
				)
				( pin "U2D1.CE4"
					( objectStatus "pe2_tx_dp(7)" )
				)
				( pin "U2D1.CD3"
					( objectStatus "pe2_tx_dp(8)" )
				)
				( pin "U2D1.BY3"
					( objectStatus "pe2_tx_dp(9)" )
				)
				( pin "U2D1.BY5"
					( objectStatus "pe2_tx_dp(10)" )
				)
				( pin "U2D1.BV3"
					( objectStatus "pe2_tx_dp(11)" )
				)
				( pin "U2D1.BR4"
					( objectStatus "pe2_tx_dp(12)" )
				)
				( pin "U2D1.BN4"
					( objectStatus "pe2_tx_dp(13)" )
				)
				( pin "U2D1.BM3"
					( objectStatus "pe2_tx_dp(14)" )
				)
				( pin "U2D1.BK5"
					( objectStatus "pe2_tx_dp(15)" )
				)
			)
			( gate "U2D1"
				( objectStatus "@baseboard_fab2_lib.baseboard_fab2(sch_1):page66_i84" )
				( pin "U2D1.EA18"
					( objectStatus "pe3_rx_dn(0)" )
				)
				( pin "U2D1.DW18"
					( objectStatus "pe3_rx_dn(1)" )
				)
				( pin "U2D1.DW16"
					( objectStatus "pe3_rx_dn(2)" )
				)
				( pin "U2D1.DT19"
					( objectStatus "pe3_rx_dn(3)" )
				)
				( pin "U2D1.DR16"
					( objectStatus "pe3_rx_dn(4)" )
				)
				( pin "U2D1.DR14"
					( objectStatus "pe3_rx_dn(5)" )
				)
				( pin "U2D1.DN14"
					( objectStatus "pe3_rx_dn(6)" )
				)
				( pin "U2D1.DL14"
					( objectStatus "pe3_rx_dn(7)" )
				)
				( pin "U2D1.DL12"
					( objectStatus "pe3_rx_dn(8)" )
				)
				( pin "U2D1.DJ12"
					( objectStatus "pe3_rx_dn(9)" )
				)
				( pin "U2D1.DG12"
					( objectStatus "pe3_rx_dn(10)" )
				)
				( pin "U2D1.DG10"
					( objectStatus "pe3_rx_dn(11)" )
				)
				( pin "U2D1.DD13"
					( objectStatus "pe3_rx_dn(12)" )
				)
				( pin "U2D1.DB11"
					( objectStatus "pe3_rx_dn(13)" )
				)
				( pin "U2D1.CY11"
					( objectStatus "pe3_rx_dn(14)" )
				)
				( pin "U2D1.CV9"
					( objectStatus "pe3_rx_dn(15)" )
				)
				( pin "U2D1.DY17"
					( objectStatus "pe3_rx_dp(0)" )
				)
				( pin "U2D1.DU18"
					( objectStatus "pe3_rx_dp(1)" )
				)
				( pin "U2D1.DV17"
					( objectStatus "pe3_rx_dp(2)" )
				)
				( pin "U2D1.DR18"
					( objectStatus "pe3_rx_dp(3)" )
				)
				( pin "U2D1.DN16"
					( objectStatus "pe3_rx_dp(4)" )
				)
				( pin "U2D1.DP15"
					( objectStatus "pe3_rx_dp(5)" )
				)
				( pin "U2D1.DM13"
					( objectStatus "pe3_rx_dp(6)" )
				)
				( pin "U2D1.DJ14"
					( objectStatus "pe3_rx_dp(7)" )
				)
				( pin "U2D1.DK13"
					( objectStatus "pe3_rx_dp(8)" )
				)
				( pin "U2D1.DH11"
					( objectStatus "pe3_rx_dp(9)" )
				)
				( pin "U2D1.DE12"
					( objectStatus "pe3_rx_dp(10)" )
				)
				( pin "U2D1.DF11"
					( objectStatus "pe3_rx_dp(11)" )
				)
				( pin "U2D1.DC12"
					( objectStatus "pe3_rx_dp(12)" )
				)
				( pin "U2D1.DA12"
					( objectStatus "pe3_rx_dp(13)" )
				)
				( pin "U2D1.CW10"
					( objectStatus "pe3_rx_dp(14)" )
				)
				( pin "U2D1.CU10"
					( objectStatus "pe3_rx_dp(15)" )
				)
				( pin "U2D1.EE14"
					( objectStatus "pe3_tx_dn(0)" )
				)
				( pin "U2D1.EE12"
					( objectStatus "pe3_tx_dn(1)" )
				)
				( pin "U2D1.EC12"
					( objectStatus "pe3_tx_dn(2)" )
				)
				( pin "U2D1.DY11"
					( objectStatus "pe3_tx_dn(3)" )
				)
				( pin "U2D1.EB9"
					( objectStatus "pe3_tx_dn(4)" )
				)
				( pin "U2D1.DW10"
					( objectStatus "pe3_tx_dn(5)" )
				)
				( pin "U2D1.DU8"
					( objectStatus "pe3_tx_dn(6)" )
				)
				( pin "U2D1.DR8"
					( objectStatus "pe3_tx_dn(7)" )
				)
				( pin "U2D1.DM7"
					( objectStatus "pe3_tx_dn(8)" )
				)
				( pin "U2D1.DP5"
					( objectStatus "pe3_tx_dn(9)" )
				)
				( pin "U2D1.DL6"
					( objectStatus "pe3_tx_dn(10)" )
				)
				( pin "U2D1.DJ4"
					( objectStatus "pe3_tx_dn(11)" )
				)
				( pin "U2D1.DJ6"
					( objectStatus "pe3_tx_dn(12)" )
				)
				( pin "U2D1.DD5"
					( objectStatus "pe3_tx_dn(13)" )
				)
				( pin "U2D1.DB5"
					( objectStatus "pe3_tx_dn(14)" )
				)
				( pin "U2D1.CY5"
					( objectStatus "pe3_tx_dn(15)" )
				)
				( pin "U2D1.EC14"
					( objectStatus "pe3_tx_dp(0)" )
				)
				( pin "U2D1.ED13"
					( objectStatus "pe3_tx_dp(1)" )
				)
				( pin "U2D1.EB11"
					( objectStatus "pe3_tx_dp(2)" )
				)
				( pin "U2D1.EA10"
					( objectStatus "pe3_tx_dp(3)" )
				)
				( pin "U2D1.DY9"
					( objectStatus "pe3_tx_dp(4)" )
				)
				( pin "U2D1.DV9"
					( objectStatus "pe3_tx_dp(5)" )
				)
				( pin "U2D1.DT9"
					( objectStatus "pe3_tx_dp(6)" )
				)
				( pin "U2D1.DP7"
					( objectStatus "pe3_tx_dp(7)" )
				)
				( pin "U2D1.DN6"
					( objectStatus "pe3_tx_dp(8)" )
				)
				( pin "U2D1.DM5"
					( objectStatus "pe3_tx_dp(9)" )
				)
				( pin "U2D1.DK5"
					( objectStatus "pe3_tx_dp(10)" )
				)
				( pin "U2D1.DH5"
					( objectStatus "pe3_tx_dp(11)" )
				)
				( pin "U2D1.DG6"
					( objectStatus "pe3_tx_dp(12)" )
				)
				( pin "U2D1.DC6"
					( objectStatus "pe3_tx_dp(13)" )
				)
				( pin "U2D1.DA4"
					( objectStatus "pe3_tx_dp(14)" )
				)
				( pin "U2D1.CV5"
					( objectStatus "pe3_tx_dp(15)" )
				)
			)
			( gate "U2D1"
				( objectStatus "@baseboard_fab2_lib.baseboard_fab2(sch_1):page67_i132" )
				( pin "U2D1.AC10"
					( objectStatus "upi0_rx_dn(0)" )
				)
				( pin "U2D1.AA8"
					( objectStatus "upi0_rx_dn(1)" )
				)
				( pin "U2D1.AB7"
					( objectStatus "upi0_rx_dn(2)" )
				)
				( pin "U2D1.AD5"
					( objectStatus "upi0_rx_dn(3)" )
				)
				( pin "U2D1.AE6"
					( objectStatus "upi0_rx_dn(4)" )
				)
				( pin "U2D1.AG8"
					( objectStatus "upi0_rx_dn(5)" )
				)
				( pin "U2D1.AJ6"
					( objectStatus "upi0_rx_dn(6)" )
				)
				( pin "U2D1.AL6"
					( objectStatus "upi0_rx_dn(7)" )
				)
				( pin "U2D1.AK7"
					( objectStatus "upi0_rx_dn(8)" )
				)
				( pin "U2D1.AM9"
					( objectStatus "upi0_rx_dn(9)" )
				)
				( pin "U2D1.AP7"
					( objectStatus "upi0_rx_dn(10)" )
				)
				( pin "U2D1.AR8"
					( objectStatus "upi0_rx_dn(11)" )
				)
				( pin "U2D1.AU10"
					( objectStatus "upi0_rx_dn(12)" )
				)
				( pin "U2D1.BA8"
					( objectStatus "upi0_rx_dn(13)" )
				)
				( pin "U2D1.BC6"
					( objectStatus "upi0_rx_dn(14)" )
				)
				( pin "U2D1.BD7"
					( objectStatus "upi0_rx_dn(15)" )
				)
				( pin "U2D1.AW8"
					( objectStatus "upi0_rx_dn(16)" )
				)
				( pin "U2D1.AY9"
					( objectStatus "upi0_rx_dn(17)" )
				)
				( pin "U2D1.BD9"
					( objectStatus "upi0_rx_dn(18)" )
				)
				( pin "U2D1.BB11"
					( objectStatus "upi0_rx_dn(19)" )
				)
				( pin "U2D1.AB9"
					( objectStatus "upi0_rx_dp(0)" )
				)
				( pin "U2D1.AC8"
					( objectStatus "upi0_rx_dp(1)" )
				)
				( pin "U2D1.AA6"
					( objectStatus "upi0_rx_dp(2)" )
				)
				( pin "U2D1.AC6"
					( objectStatus "upi0_rx_dp(3)" )
				)
				( pin "U2D1.AG6"
					( objectStatus "upi0_rx_dp(4)" )
				)
				( pin "U2D1.AF7"
					( objectStatus "upi0_rx_dp(5)" )
				)
				( pin "U2D1.AH7"
					( objectStatus "upi0_rx_dp(6)" )
				)
				( pin "U2D1.AK5"
					( objectStatus "upi0_rx_dp(7)" )
				)
				( pin "U2D1.AM7"
					( objectStatus "upi0_rx_dp(8)" )
				)
				( pin "U2D1.AL8"
					( objectStatus "upi0_rx_dp(9)" )
				)
				( pin "U2D1.AN8"
					( objectStatus "upi0_rx_dp(10)" )
				)
				( pin "U2D1.AU8"
					( objectStatus "upi0_rx_dp(11)" )
				)
				( pin "U2D1.AT9"
					( objectStatus "upi0_rx_dp(12)" )
				)
				( pin "U2D1.AY7"
					( objectStatus "upi0_rx_dp(13)" )
				)
				( pin "U2D1.BB7"
					( objectStatus "upi0_rx_dp(14)" )
				)
				( pin "U2D1.BF7"
					( objectStatus "upi0_rx_dp(15)" )
				)
				( pin "U2D1.AV9"
					( objectStatus "upi0_rx_dp(16)" )
				)
				( pin "U2D1.BB9"
					( objectStatus "upi0_rx_dp(17)" )
				)
				( pin "U2D1.BC10"
					( objectStatus "upi0_rx_dp(18)" )
				)
				( pin "U2D1.BA10"
					( objectStatus "upi0_rx_dp(19)" )
				)
				( pin "U2D1.N2"
					( objectStatus "upi0_tx_dn(0)" )
				)
				( pin "U2D1.P1"
					( objectStatus "upi0_tx_dn(1)" )
				)
				( pin "U2D1.V3"
					( objectStatus "upi0_tx_dn(2)" )
				)
				( pin "U2D1.Y1"
					( objectStatus "upi0_tx_dn(3)" )
				)
				( pin "U2D1.AB3"
					( objectStatus "upi0_tx_dn(4)" )
				)
				( pin "U2D1.AC2"
					( objectStatus "upi0_tx_dn(5)" )
				)
				( pin "U2D1.AG4"
					( objectStatus "upi0_tx_dn(6)" )
				)
				( pin "U2D1.AE2"
					( objectStatus "upi0_tx_dn(7)" )
				)
				( pin "U2D1.AH3"
					( objectStatus "upi0_tx_dn(8)" )
				)
				( pin "U2D1.AL2"
					( objectStatus "upi0_tx_dn(9)" )
				)
				( pin "U2D1.AM3"
					( objectStatus "upi0_tx_dn(10)" )
				)
				( pin "U2D1.AN4"
					( objectStatus "upi0_tx_dn(11)" )
				)
				( pin "U2D1.AT1"
					( objectStatus "upi0_tx_dn(12)" )
				)
				( pin "U2D1.AT3"
					( objectStatus "upi0_tx_dn(13)" )
				)
				( pin "U2D1.AU4"
					( objectStatus "upi0_tx_dn(14)" )
				)
				( pin "U2D1.AV5"
					( objectStatus "upi0_tx_dn(15)" )
				)
				( pin "U2D1.BA4"
					( objectStatus "upi0_tx_dn(16)" )
				)
				( pin "U2D1.BB3"
					( objectStatus "upi0_tx_dn(17)" )
				)
				( pin "U2D1.BF3"
					( objectStatus "upi0_tx_dn(18)" )
				)
				( pin "U2D1.BG4"
					( objectStatus "upi0_tx_dn(19)" )
				)
				( pin "U2D1.M1"
					( objectStatus "upi0_tx_dp(0)" )
				)
				( pin "U2D1.T1"
					( objectStatus "upi0_tx_dp(1)" )
				)
				( pin "U2D1.Y3"
					( objectStatus "upi0_tx_dp(2)" )
				)
				( pin "U2D1.W2"
					( objectStatus "upi0_tx_dp(3)" )
				)
				( pin "U2D1.AA2"
					( objectStatus "upi0_tx_dp(4)" )
				)
				( pin "U2D1.AD1"
					( objectStatus "upi0_tx_dp(5)" )
				)
				( pin "U2D1.AF3"
					( objectStatus "upi0_tx_dp(6)" )
				)
				( pin "U2D1.AG2"
					( objectStatus "upi0_tx_dp(7)" )
				)
				( pin "U2D1.AJ2"
					( objectStatus "upi0_tx_dp(8)" )
				)
				( pin "U2D1.AK1"
					( objectStatus "upi0_tx_dp(9)" )
				)
				( pin "U2D1.AK3"
					( objectStatus "upi0_tx_dp(10)" )
				)
				( pin "U2D1.AP3"
					( objectStatus "upi0_tx_dp(11)" )
				)
				( pin "U2D1.AP1"
					( objectStatus "upi0_tx_dp(12)" )
				)
				( pin "U2D1.AR2"
					( objectStatus "upi0_tx_dp(13)" )
				)
				( pin "U2D1.AR4"
					( objectStatus "upi0_tx_dp(14)" )
				)
				( pin "U2D1.AW4"
					( objectStatus "upi0_tx_dp(15)" )
				)
				( pin "U2D1.AY3"
					( objectStatus "upi0_tx_dp(16)" )
				)
				( pin "U2D1.BC2"
					( objectStatus "upi0_tx_dp(17)" )
				)
				( pin "U2D1.BD3"
					( objectStatus "upi0_tx_dp(18)" )
				)
				( pin "U2D1.BH3"
					( objectStatus "upi0_tx_dp(19)" )
				)
			)
			( gate "U2D1"
				( objectStatus "@baseboard_fab2_lib.baseboard_fab2(sch_1):page68_i125" )
				( pin "U2D1.T5"
					( objectStatus "upi1_rx_dn(0)" )
				)
				( pin "U2D1.P7"
					( objectStatus "upi1_rx_dn(1)" )
				)
				( pin "U2D1.V7"
					( objectStatus "upi1_rx_dn(2)" )
				)
				( pin "U2D1.T9"
					( objectStatus "upi1_rx_dn(3)" )
				)
				( pin "U2D1.P9"
					( objectStatus "upi1_rx_dn(4)" )
				)
				( pin "U2D1.R10"
					( objectStatus "upi1_rx_dn(5)" )
				)
				( pin "U2D1.U12"
					( objectStatus "upi1_rx_dn(6)" )
				)
				( pin "U2D1.L12"
					( objectStatus "upi1_rx_dn(7)" )
				)
				( pin "U2D1.N14"
					( objectStatus "upi1_rx_dn(8)" )
				)
				( pin "U2D1.R12"
					( objectStatus "upi1_rx_dn(9)" )
				)
				( pin "U2D1.R16"
					( objectStatus "upi1_rx_dn(10)" )
				)
				( pin "U2D1.P17"
					( objectStatus "upi1_rx_dn(11)" )
				)
				( pin "U2D1.U16"
					( objectStatus "upi1_rx_dn(12)" )
				)
				( pin "U2D1.W18"
					( objectStatus "upi1_rx_dn(13)" )
				)
				( pin "U2D1.R20"
					( objectStatus "upi1_rx_dn(14)" )
				)
				( pin "U2D1.U18"
					( objectStatus "upi1_rx_dn(15)" )
				)
				( pin "U2D1.P21"
					( objectStatus "upi1_rx_dn(16)" )
				)
				( pin "U2D1.V19"
					( objectStatus "upi1_rx_dn(17)" )
				)
				( pin "U2D1.Y21"
					( objectStatus "upi1_rx_dn(18)" )
				)
				( pin "U2D1.AB19"
					( objectStatus "upi1_rx_dn(19)" )
				)
				( pin "U2D1.R6"
					( objectStatus "upi1_rx_dp(0)" )
				)
				( pin "U2D1.T7"
					( objectStatus "upi1_rx_dp(1)" )
				)
				( pin "U2D1.U8"
					( objectStatus "upi1_rx_dp(2)" )
				)
				( pin "U2D1.R8"
					( objectStatus "upi1_rx_dp(3)" )
				)
				( pin "U2D1.N10"
					( objectStatus "upi1_rx_dp(4)" )
				)
				( pin "U2D1.U10"
					( objectStatus "upi1_rx_dp(5)" )
				)
				( pin "U2D1.T11"
					( objectStatus "upi1_rx_dp(6)" )
				)
				( pin "U2D1.N12"
					( objectStatus "upi1_rx_dp(7)" )
				)
				( pin "U2D1.M13"
					( objectStatus "upi1_rx_dp(8)" )
				)
				( pin "U2D1.P13"
					( objectStatus "upi1_rx_dp(9)" )
				)
				( pin "U2D1.T15"
					( objectStatus "upi1_rx_dp(10)" )
				)
				( pin "U2D1.N16"
					( objectStatus "upi1_rx_dp(11)" )
				)
				( pin "U2D1.W16"
					( objectStatus "upi1_rx_dp(12)" )
				)
				( pin "U2D1.V17"
					( objectStatus "upi1_rx_dp(13)" )
				)
				( pin "U2D1.P19"
					( objectStatus "upi1_rx_dp(14)" )
				)
				( pin "U2D1.T19"
					( objectStatus "upi1_rx_dp(15)" )
				)
				( pin "U2D1.T21"
					( objectStatus "upi1_rx_dp(16)" )
				)
				( pin "U2D1.Y19"
					( objectStatus "upi1_rx_dp(17)" )
				)
				( pin "U2D1.W20"
					( objectStatus "upi1_rx_dp(18)" )
				)
				( pin "U2D1.AA20"
					( objectStatus "upi1_rx_dp(19)" )
				)
				( pin "U2D1.M3"
					( objectStatus "upi1_tx_dn(0)" )
				)
				( pin "U2D1.L4"
					( objectStatus "upi1_tx_dn(1)" )
				)
				( pin "U2D1.K5"
					( objectStatus "upi1_tx_dn(2)" )
				)
				( pin "U2D1.J6"
					( objectStatus "upi1_tx_dn(3)" )
				)
				( pin "U2D1.G6"
					( objectStatus "upi1_tx_dn(4)" )
				)
				( pin "U2D1.H7"
					( objectStatus "upi1_tx_dn(5)" )
				)
				( pin "U2D1.K9"
					( objectStatus "upi1_tx_dn(6)" )
				)
				( pin "U2D1.D9"
					( objectStatus "upi1_tx_dn(7)" )
				)
				( pin "U2D1.F11"
					( objectStatus "upi1_tx_dn(8)" )
				)
				( pin "U2D1.G10"
					( objectStatus "upi1_tx_dn(9)" )
				)
				( pin "U2D1.E12"
					( objectStatus "upi1_tx_dn(10)" )
				)
				( pin "U2D1.G14"
					( objectStatus "upi1_tx_dn(11)" )
				)
				( pin "U2D1.D15"
					( objectStatus "upi1_tx_dn(12)" )
				)
				( pin "U2D1.F15"
					( objectStatus "upi1_tx_dn(13)" )
				)
				( pin "U2D1.H17"
					( objectStatus "upi1_tx_dn(14)" )
				)
				( pin "U2D1.K19"
					( objectStatus "upi1_tx_dn(15)" )
				)
				( pin "U2D1.G18"
					( objectStatus "upi1_tx_dn(16)" )
				)
				( pin "U2D1.J20"
					( objectStatus "upi1_tx_dn(17)" )
				)
				( pin "U2D1.F21"
					( objectStatus "upi1_tx_dn(18)" )
				)
				( pin "U2D1.H21"
					( objectStatus "upi1_tx_dn(19)" )
				)
				( pin "U2D1.P3"
					( objectStatus "upi1_tx_dp(0)" )
				)
				( pin "U2D1.K3"
					( objectStatus "upi1_tx_dp(1)" )
				)
				( pin "U2D1.M5"
					( objectStatus "upi1_tx_dp(2)" )
				)
				( pin "U2D1.H5"
					( objectStatus "upi1_tx_dp(3)" )
				)
				( pin "U2D1.F7"
					( objectStatus "upi1_tx_dp(4)" )
				)
				( pin "U2D1.K7"
					( objectStatus "upi1_tx_dp(5)" )
				)
				( pin "U2D1.J8"
					( objectStatus "upi1_tx_dp(6)" )
				)
				( pin "U2D1.F9"
					( objectStatus "upi1_tx_dp(7)" )
				)
				( pin "U2D1.E10"
					( objectStatus "upi1_tx_dp(8)" )
				)
				( pin "U2D1.H9"
					( objectStatus "upi1_tx_dp(9)" )
				)
				( pin "U2D1.G12"
					( objectStatus "upi1_tx_dp(10)" )
				)
				( pin "U2D1.F13"
					( objectStatus "upi1_tx_dp(11)" )
				)
				( pin "U2D1.E14"
					( objectStatus "upi1_tx_dp(12)" )
				)
				( pin "U2D1.H15"
					( objectStatus "upi1_tx_dp(13)" )
				)
				( pin "U2D1.G16"
					( objectStatus "upi1_tx_dp(14)" )
				)
				( pin "U2D1.L18"
					( objectStatus "upi1_tx_dp(15)" )
				)
				( pin "U2D1.J18"
					( objectStatus "upi1_tx_dp(16)" )
				)
				( pin "U2D1.H19"
					( objectStatus "upi1_tx_dp(17)" )
				)
				( pin "U2D1.G20"
					( objectStatus "upi1_tx_dp(18)" )
				)
				( pin "U2D1.K21"
					( objectStatus "upi1_tx_dp(19)" )
				)
			)
			( gate "U2D1"
				( objectStatus "@baseboard_fab2_lib.baseboard_fab2(sch_1):page69_i1" )
				( pin "U2D1.DF23"
					( objectStatus "upi2_rx_dn(0)" )
				)
				( pin "U2D1.DE22"
					( objectStatus "upi2_rx_dn(1)" )
				)
				( pin "U2D1.DC22"
					( objectStatus "upi2_rx_dn(2)" )
				)
				( pin "U2D1.DB21"
					( objectStatus "upi2_rx_dn(3)" )
				)
				( pin "U2D1.DD19"
					( objectStatus "upi2_rx_dn(4)" )
				)
				( pin "U2D1.DA20"
					( objectStatus "upi2_rx_dn(5)" )
				)
				( pin "U2D1.CW20"
					( objectStatus "upi2_rx_dn(6)" )
				)
				( pin "U2D1.CV19"
					( objectStatus "upi2_rx_dn(7)" )
				)
				( pin "U2D1.CT21"
					( objectStatus "upi2_rx_dn(8)" )
				)
				( pin "U2D1.CR18"
					( objectStatus "upi2_rx_dn(9)" )
				)
				( pin "U2D1.CN20"
					( objectStatus "upi2_rx_dn(10)" )
				)
				( pin "U2D1.CP21"
					( objectStatus "upi2_rx_dn(11)" )
				)
				( pin "U2D1.CL16"
					( objectStatus "upi2_rx_dn(12)" )
				)
				( pin "U2D1.CJ18"
					( objectStatus "upi2_rx_dn(13)" )
				)
				( pin "U2D1.CH17"
					( objectStatus "upi2_rx_dn(14)" )
				)
				( pin "U2D1.CE16"
					( objectStatus "upi2_rx_dn(15)" )
				)
				( pin "U2D1.CD15"
					( objectStatus "upi2_rx_dn(16)" )
				)
				( pin "U2D1.CF17"
					( objectStatus "upi2_rx_dn(17)" )
				)
				( pin "U2D1.CB15"
					( objectStatus "upi2_rx_dn(18)" )
				)
				( pin "U2D1.BY17"
					( objectStatus "upi2_rx_dn(19)" )
				)
				( pin "U2D1.DG22"
					( objectStatus "upi2_rx_dp(0)" )
				)
				( pin "U2D1.DD21"
					( objectStatus "upi2_rx_dp(1)" )
				)
				( pin "U2D1.DA22"
					( objectStatus "upi2_rx_dp(2)" )
				)
				( pin "U2D1.DC20"
					( objectStatus "upi2_rx_dp(3)" )
				)
				( pin "U2D1.DB19"
					( objectStatus "upi2_rx_dp(4)" )
				)
				( pin "U2D1.CY19"
					( objectStatus "upi2_rx_dp(5)" )
				)
				( pin "U2D1.CU20"
					( objectStatus "upi2_rx_dp(6)" )
				)
				( pin "U2D1.CW18"
					( objectStatus "upi2_rx_dp(7)" )
				)
				( pin "U2D1.CR20"
					( objectStatus "upi2_rx_dp(8)" )
				)
				( pin "U2D1.CN18"
					( objectStatus "upi2_rx_dp(9)" )
				)
				( pin "U2D1.CP19"
					( objectStatus "upi2_rx_dp(10)" )
				)
				( pin "U2D1.CM21"
					( objectStatus "upi2_rx_dp(11)" )
				)
				( pin "U2D1.CJ16"
					( objectStatus "upi2_rx_dp(12)" )
				)
				( pin "U2D1.CK17"
					( objectStatus "upi2_rx_dp(13)" )
				)
				( pin "U2D1.CG16"
					( objectStatus "upi2_rx_dp(14)" )
				)
				( pin "U2D1.CF15"
					( objectStatus "upi2_rx_dp(15)" )
				)
				( pin "U2D1.CC14"
					( objectStatus "upi2_rx_dp(16)" )
				)
				( pin "U2D1.CD17"
					( objectStatus "upi2_rx_dp(17)" )
				)
				( pin "U2D1.BY15"
					( objectStatus "upi2_rx_dp(18)" )
				)
				( pin "U2D1.CA16"
					( objectStatus "upi2_rx_dp(19)" )
				)
				( pin "U2D1.DT21"
					( objectStatus "upi2_tx_dn(0)" )
				)
				( pin "U2D1.DM21"
					( objectStatus "upi2_tx_dn(1)" )
				)
				( pin "U2D1.DL20"
					( objectStatus "upi2_tx_dn(2)" )
				)
				( pin "U2D1.DG20"
					( objectStatus "upi2_tx_dn(3)" )
				)
				( pin "U2D1.DH19"
					( objectStatus "upi2_tx_dn(4)" )
				)
				( pin "U2D1.DK17"
					( objectStatus "upi2_tx_dn(5)" )
				)
				( pin "U2D1.DG18"
					( objectStatus "upi2_tx_dn(6)" )
				)
				( pin "U2D1.DD17"
					( objectStatus "upi2_tx_dn(7)" )
				)
				( pin "U2D1.DF15"
					( objectStatus "upi2_tx_dn(8)" )
				)
				( pin "U2D1.DC16"
					( objectStatus "upi2_tx_dn(9)" )
				)
				( pin "U2D1.DA16"
					( objectStatus "upi2_tx_dn(10)" )
				)
				( pin "U2D1.CW14"
					( objectStatus "upi2_tx_dn(11)" )
				)
				( pin "U2D1.CU14"
					( objectStatus "upi2_tx_dn(12)" )
				)
				( pin "U2D1.CM13"
					( objectStatus "upi2_tx_dn(13)" )
				)
				( pin "U2D1.CJ14"
					( objectStatus "upi2_tx_dn(14)" )
				)
				( pin "U2D1.CF13"
					( objectStatus "upi2_tx_dn(15)" )
				)
				( pin "U2D1.CH11"
					( objectStatus "upi2_tx_dn(16)" )
				)
				( pin "U2D1.CE12"
					( objectStatus "upi2_tx_dn(17)" )
				)
				( pin "U2D1.CC10"
					( objectStatus "upi2_tx_dn(18)" )
				)
				( pin "U2D1.CC12"
					( objectStatus "upi2_tx_dn(19)" )
				)
				( pin "U2D1.DP21"
					( objectStatus "upi2_tx_dp(0)" )
				)
				( pin "U2D1.DN20"
					( objectStatus "upi2_tx_dp(1)" )
				)
				( pin "U2D1.DK19"
					( objectStatus "upi2_tx_dp(2)" )
				)
				( pin "U2D1.DJ20"
					( objectStatus "upi2_tx_dp(3)" )
				)
				( pin "U2D1.DJ18"
					( objectStatus "upi2_tx_dp(4)" )
				)
				( pin "U2D1.DH17"
					( objectStatus "upi2_tx_dp(5)" )
				)
				( pin "U2D1.DF17"
					( objectStatus "upi2_tx_dp(6)" )
				)
				( pin "U2D1.DE16"
					( objectStatus "upi2_tx_dp(7)" )
				)
				( pin "U2D1.DD15"
					( objectStatus "upi2_tx_dp(8)" )
				)
				( pin "U2D1.DB15"
					( objectStatus "upi2_tx_dp(9)" )
				)
				( pin "U2D1.CW16"
					( objectStatus "upi2_tx_dp(10)" )
				)
				( pin "U2D1.CV13"
					( objectStatus "upi2_tx_dp(11)" )
				)
				( pin "U2D1.CR14"
					( objectStatus "upi2_tx_dp(12)" )
				)
				( pin "U2D1.CK13"
					( objectStatus "upi2_tx_dp(13)" )
				)
				( pin "U2D1.CH13"
					( objectStatus "upi2_tx_dp(14)" )
				)
				( pin "U2D1.CG12"
					( objectStatus "upi2_tx_dp(15)" )
				)
				( pin "U2D1.CF11"
					( objectStatus "upi2_tx_dp(16)" )
				)
				( pin "U2D1.CD11"
					( objectStatus "upi2_tx_dp(17)" )
				)
				( pin "U2D1.CB11"
					( objectStatus "upi2_tx_dp(18)" )
				)
				( pin "U2D1.CA12"
					( objectStatus "upi2_tx_dp(19)" )
				)
			)
			( gate "U2D1"
				( objectStatus "@baseboard_fab2_lib.baseboard_fab2(sch_1):page70_i9" )
				( pin "U2D1.CH23"
					( objectStatus "rsvd(92)" )
				)
				( pin "U2D1.CH21"
					( objectStatus "rsvd(93)" )
				)
				( pin "U2D1.CG82"
					( objectStatus "rsvd(94)" )
				)
				( pin "U2D1.CG78"
					( objectStatus "rsvd(95)" )
				)
				( pin "U2D1.CG26"
					( objectStatus "rsvd(96)" )
				)
				( pin "U2D1.CG24"
					( objectStatus "rsvd(97)" )
				)
				( pin "U2D1.CG20"
					( objectStatus "rsvd(98)" )
				)
				( pin "U2D1.CG10"
					( objectStatus "rsvd(99)" )
				)
				( pin "U2D1.CF81"
					( objectStatus "rsvd(100)" )
				)
				( pin "U2D1.CF79"
					( objectStatus "rsvd(101)" )
				)
				( pin "U2D1.CF23"
					( objectStatus "rsvd(102)" )
				)
				( pin "U2D1.CF21"
					( objectStatus "rsvd(103)" )
				)
				( pin "U2D1.CF19"
					( objectStatus "rsvd(104)" )
				)
				( pin "U2D1.CE80"
					( objectStatus "rsvd(105)" )
				)
				( pin "U2D1.CE78"
					( objectStatus "rsvd(106)" )
				)
				( pin "U2D1.CE22"
					( objectStatus "rsvd(107)" )
				)
				( pin "U2D1.CD25"
					( objectStatus "rsvd(108)" )
				)
				( pin "U2D1.CD21"
					( objectStatus "rsvd(109)" )
				)
				( pin "U2D1.CD19"
					( objectStatus "rsvd(110)" )
				)
				( pin "U2D1.CC6"
					( objectStatus "rsvd(111)" )
				)
				( pin "U2D1.CC20"
					( objectStatus "rsvd(112)" )
				)
				( pin "U2D1.CB5"
					( objectStatus "rsvd(113)" )
				)
				( pin "U2D1.CB25"
					( objectStatus "rsvd(114)" )
				)
				( pin "U2D1.CB21"
					( objectStatus "rsvd(115)" )
				)
				( pin "U2D1.CB19"
					( objectStatus "rsvd(116)" )
				)
				( pin "U2D1.CA24"
					( objectStatus "rsvd(117)" )
				)
				( pin "U2D1.CA22"
					( objectStatus "rsvd(118)" )
				)
				( pin "U2D1.BY25"
					( objectStatus "rsvd(119)" )
				)
				( pin "U2D1.BY19"
					( objectStatus "rsvd(120)" )
				)
				( pin "U2D1.BW22"
					( objectStatus "rsvd(121)" )
				)
				( pin "U2D1.BW20"
					( objectStatus "rsvd(122)" )
				)
				( pin "U2D1.BW10"
					( objectStatus "rsvd(123)" )
				)
				( pin "U2D1.BV23"
					( objectStatus "rsvd(124)" )
				)
				( pin "U2D1.BV21"
					( objectStatus "rsvd(125)" )
				)
				( pin "U2D1.BV19"
					( objectStatus "rsvd(126)" )
				)
				( pin "U2D1.BU22"
					( objectStatus "rsvd(127)" )
				)
				( pin "U2D1.BU20"
					( objectStatus "rsvd(128)" )
				)
				( pin "U2D1.BU18"
					( objectStatus "rsvd(129)" )
				)
				( pin "U2D1.BR24"
					( objectStatus "rsvd(130)" )
				)
				( pin "U2D1.BR22"
					( objectStatus "rsvd(131)" )
				)
				( pin "U2D1.BP21"
					( objectStatus "rsvd(132)" )
				)
				( pin "U2D1.BP17"
					( objectStatus "rsvd(133)" )
				)
				( pin "U2D1.BN18"
					( objectStatus "rsvd(134)" )
				)
				( pin "U2D1.BM19"
					( objectStatus "rsvd(135)" )
				)
				( pin "U2D1.BM17"
					( objectStatus "rsvd(136)" )
				)
				( pin "U2D1.BL20"
					( objectStatus "rsvd(137)" )
				)
				( pin "U2D1.BL18"
					( objectStatus "rsvd(138)" )
				)
				( pin "U2D1.BK17"
					( objectStatus "rsvd(139)" )
				)
				( pin "U2D1.BJ20"
					( objectStatus "rsvd(140)" )
				)
				( pin "U2D1.BJ18"
					( objectStatus "rsvd(141)" )
				)
				( pin "U2D1.BJ16"
					( objectStatus "rsvd(142)" )
				)
				( pin "U2D1.BH19"
					( objectStatus "rsvd(143)" )
				)
				( pin "U2D1.BG20"
					( objectStatus "rsvd(144)" )
				)
				( pin "U2D1.BG18"
					( objectStatus "rsvd(145)" )
				)
				( pin "U2D1.BF21"
					( objectStatus "rsvd(146)" )
				)
				( pin "U2D1.BE22"
					( objectStatus "rsvd(147)" )
				)
				( pin "U2D1.BE20"
					( objectStatus "rsvd(148)" )
				)
				( pin "U2D1.BE18"
					( objectStatus "rsvd(149)" )
				)
				( pin "U2D1.BD69"
					( objectStatus "rsvd(150)" )
				)
				( pin "U2D1.BD67"
					( objectStatus "rsvd(151)" )
				)
				( pin "U2D1.BD65"
					( objectStatus "rsvd(152)" )
				)
				( pin "U2D1.BD25"
					( objectStatus "rsvd(153)" )
				)
				( pin "U2D1.BD19"
					( objectStatus "rsvd(154)" )
				)
				( pin "U2D1.BD17"
					( objectStatus "rsvd(155)" )
				)
				( pin "U2D1.BC68"
					( objectStatus "rsvd(156)" )
				)
				( pin "U2D1.BC66"
					( objectStatus "rsvd(157)" )
				)
				( pin "U2D1.BC64"
					( objectStatus "rsvd(158)" )
				)
				( pin "U2D1.BC22"
					( objectStatus "rsvd(159)" )
				)
				( pin "U2D1.BC20"
					( objectStatus "rsvd(160)" )
				)
				( pin "U2D1.BC18"
					( objectStatus "rsvd(161)" )
				)
				( pin "U2D1.BC14"
					( objectStatus "rsvd(162)" )
				)
				( pin "U2D1.BB67"
					( objectStatus "rsvd(163)" )
				)
				( pin "U2D1.BB65"
					( objectStatus "rsvd(164)" )
				)
				( pin "U2D1.BB25"
					( objectStatus "rsvd(165)" )
				)
				( pin "U2D1.BB21"
					( objectStatus "rsvd(166)" )
				)
				( pin "U2D1.BB17"
					( objectStatus "rsvd(167)" )
				)
				( pin "U2D1.BB15"
					( objectStatus "rsvd(168)" )
				)
				( pin "U2D1.BB13"
					( objectStatus "rsvd(169)" )
				)
				( pin "U2D1.BA82"
					( objectStatus "rsvd(170)" )
				)
				( pin "U2D1.BA78"
					( objectStatus "rsvd(171)" )
				)
				( pin "U2D1.AY83"
					( objectStatus "rsvd(255)" )
				)
			)
			( gate "U2D1"
				( objectStatus "@baseboard_fab2_lib.baseboard_fab2(sch_1):page70_i10" )
				( pin "U2D1.CL24"
					( objectStatus "rsvd(81)" )
				)
				( pin "U2D1.CK77"
					( objectStatus "rsvd(82)" )
				)
				( pin "U2D1.CK25"
					( objectStatus "rsvd(83)" )
				)
				( pin "U2D1.CK23"
					( objectStatus "rsvd(84)" )
				)
				( pin "U2D1.CK19"
					( objectStatus "rsvd(85)" )
				)
				( pin "U2D1.CJ26"
					( objectStatus "rsvd(86)" )
				)
				( pin "U2D1.CJ24"
					( objectStatus "rsvd(87)" )
				)
				( pin "U2D1.CJ22"
					( objectStatus "rsvd(88)" )
				)
				( pin "U2D1.CJ20"
					( objectStatus "rsvd(89)" )
				)
				( pin "U2D1.CH77"
					( objectStatus "rsvd(90)" )
				)
				( pin "U2D1.CH25"
					( objectStatus "rsvd(91)" )
				)
				( pin "U2D1.AR16"
					( objectStatus "test_6" )
				)
				( pin "U2D1.AU18"
					( objectStatus "test_7" )
				)
				( pin "U2D1.AW16"
					( objectStatus "test_8" )
				)
				( pin "U2D1.AW20"
					( objectStatus "test_9" )
				)
				( pin "U2D1.AW22"
					( objectStatus "test_10" )
				)
			)
			( gate "R3D27"
				( objectStatus "@baseboard_fab2_lib.baseboard_fab2(sch_1):page71_i43" )
				( pin "R3D27.1"
					( objectStatus "a" )
				)
				( pin "R3D27.2"
					( objectStatus "b" )
				)
			)
			( gate "RT8P1"
				( objectStatus "@baseboard_fab2_lib.baseboard_fab2(sch_1):page71_i49" )
				( pin "RT8P1.1"
					( objectStatus "a" )
				)
				( pin "RT8P1.2"
					( objectStatus "b" )
				)
			)
			( gate "U2D1"
				( objectStatus "@baseboard_fab2_lib.baseboard_fab2(sch_1):page71_i50" )
				( pin "U2D1.BN78"
					( objectStatus "vccin(130)" )
				)
				( pin "U2D1.BN76"
					( objectStatus "vccin(131)" )
				)
				( pin "U2D1.BN74"
					( objectStatus "vccin(132)" )
				)
				( pin "U2D1.BN72"
					( objectStatus "vccin(133)" )
				)
				( pin "U2D1.BN70"
					( objectStatus "vccin(134)" )
				)
				( pin "U2D1.BN68"
					( objectStatus "vccin(135)" )
				)
				( pin "U2D1.BN66"
					( objectStatus "vccin(136)" )
				)
				( pin "U2D1.BN64"
					( objectStatus "vccin(137)" )
				)
				( pin "U2D1.BN62"
					( objectStatus "vccin(138)" )
				)
				( pin "U2D1.BN60"
					( objectStatus "vccin(139)" )
				)
				( pin "U2D1.BM83"
					( objectStatus "vccin(140)" )
				)
				( pin "U2D1.BM81"
					( objectStatus "vccin(141)" )
				)
				( pin "U2D1.BM79"
					( objectStatus "vccin(142)" )
				)
				( pin "U2D1.BM77"
					( objectStatus "vccin(143)" )
				)
				( pin "U2D1.BM75"
					( objectStatus "vccin(144)" )
				)
				( pin "U2D1.BM73"
					( objectStatus "vccin(145)" )
				)
				( pin "U2D1.BM71"
					( objectStatus "vccin(146)" )
				)
				( pin "U2D1.BM69"
					( objectStatus "vccin(147)" )
				)
				( pin "U2D1.BM67"
					( objectStatus "vccin(148)" )
				)
				( pin "U2D1.BM65"
					( objectStatus "vccin(149)" )
				)
				( pin "U2D1.BM63"
					( objectStatus "vccin(150)" )
				)
				( pin "U2D1.BM61"
					( objectStatus "vccin(151)" )
				)
				( pin "U2D1.BL84"
					( objectStatus "vccin(152)" )
				)
				( pin "U2D1.BL62"
					( objectStatus "vccin(153)" )
				)
				( pin "U2D1.BL60"
					( objectStatus "vccin(154)" )
				)
				( pin "U2D1.BK83"
					( objectStatus "vccin(155)" )
				)
				( pin "U2D1.BK81"
					( objectStatus "vccin(156)" )
				)
				( pin "U2D1.BK79"
					( objectStatus "vccin(157)" )
				)
				( pin "U2D1.BK77"
					( objectStatus "vccin(158)" )
				)
				( pin "U2D1.BK75"
					( objectStatus "vccin(159)" )
				)
				( pin "U2D1.BK73"
					( objectStatus "vccin(160)" )
				)
				( pin "U2D1.BK71"
					( objectStatus "vccin(161)" )
				)
				( pin "U2D1.BK69"
					( objectStatus "vccin(162)" )
				)
				( pin "U2D1.BK67"
					( objectStatus "vccin(163)" )
				)
				( pin "U2D1.BK65"
					( objectStatus "vccin(164)" )
				)
				( pin "U2D1.BK63"
					( objectStatus "vccin(165)" )
				)
				( pin "U2D1.BK61"
					( objectStatus "vccin(166)" )
				)
				( pin "U2D1.BJ84"
					( objectStatus "vccin(167)" )
				)
				( pin "U2D1.BJ82"
					( objectStatus "vccin(168)" )
				)
				( pin "U2D1.BJ80"
					( objectStatus "vccin(169)" )
				)
				( pin "U2D1.BJ78"
					( objectStatus "vccin(170)" )
				)
				( pin "U2D1.BJ76"
					( objectStatus "vccin(171)" )
				)
				( pin "U2D1.BJ74"
					( objectStatus "vccin(172)" )
				)
				( pin "U2D1.BJ72"
					( objectStatus "vccin(173)" )
				)
				( pin "U2D1.BJ70"
					( objectStatus "vccin(174)" )
				)
				( pin "U2D1.BJ68"
					( objectStatus "vccin(175)" )
				)
				( pin "U2D1.BJ66"
					( objectStatus "vccin(176)" )
				)
				( pin "U2D1.BJ64"
					( objectStatus "vccin(177)" )
				)
				( pin "U2D1.BJ62"
					( objectStatus "vccin(178)" )
				)
				( pin "U2D1.BJ60"
					( objectStatus "vccin(179)" )
				)
				( pin "U2D1.BH83"
					( objectStatus "vccin(180)" )
				)
				( pin "U2D1.BH81"
					( objectStatus "vccin(181)" )
				)
				( pin "U2D1.BH79"
					( objectStatus "vccin(182)" )
				)
				( pin "U2D1.BH77"
					( objectStatus "vccin(183)" )
				)
				( pin "U2D1.BH75"
					( objectStatus "vccin(184)" )
				)
				( pin "U2D1.BH73"
					( objectStatus "vccin(185)" )
				)
				( pin "U2D1.BH71"
					( objectStatus "vccin(186)" )
				)
				( pin "U2D1.BH69"
					( objectStatus "vccin(187)" )
				)
				( pin "U2D1.BH67"
					( objectStatus "vccin(188)" )
				)
				( pin "U2D1.BH65"
					( objectStatus "vccin(189)" )
				)
				( pin "U2D1.BH63"
					( objectStatus "vccin(190)" )
				)
				( pin "U2D1.BH61"
					( objectStatus "vccin(191)" )
				)
				( pin "U2D1.BG84"
					( objectStatus "vccin(192)" )
				)
				( pin "U2D1.BG70"
					( objectStatus "vccin(193)" )
				)
				( pin "U2D1.BG68"
					( objectStatus "vccin(194)" )
				)
				( pin "U2D1.BG66"
					( objectStatus "vccin(195)" )
				)
				( pin "U2D1.BG64"
					( objectStatus "vccin(196)" )
				)
				( pin "U2D1.BG62"
					( objectStatus "vccin(197)" )
				)
				( pin "U2D1.BG60"
					( objectStatus "vccin(198)" )
				)
				( pin "U2D1.BF85"
					( objectStatus "vccin(199)" )
				)
				( pin "U2D1.BF83"
					( objectStatus "vccin(200)" )
				)
				( pin "U2D1.BF81"
					( objectStatus "vccin(201)" )
				)
				( pin "U2D1.BF79"
					( objectStatus "vccin(202)" )
				)
				( pin "U2D1.BF77"
					( objectStatus "vccin(203)" )
				)
				( pin "U2D1.BF75"
					( objectStatus "vccin(204)" )
				)
				( pin "U2D1.BF73"
					( objectStatus "vccin(205)" )
				)
				( pin "U2D1.BF61"
					( objectStatus "vccin(206)" )
				)
				( pin "U2D1.BE84"
					( objectStatus "vccin(207)" )
				)
				( pin "U2D1.BE82"
					( objectStatus "vccin(208)" )
				)
				( pin "U2D1.BE80"
					( objectStatus "vccin(209)" )
				)
				( pin "U2D1.BE78"
					( objectStatus "vccin(210)" )
				)
				( pin "U2D1.BE76"
					( objectStatus "vccin(211)" )
				)
				( pin "U2D1.BE74"
					( objectStatus "vccin(212)" )
				)
				( pin "U2D1.BE72"
					( objectStatus "vccin(213)" )
				)
				( pin "U2D1.BE62"
					( objectStatus "vccin(214)" )
				)
				( pin "U2D1.BE60"
					( objectStatus "vccin(215)" )
				)
				( pin "U2D1.BD85"
					( objectStatus "vccin(216)" )
				)
				( pin "U2D1.BD83"
					( objectStatus "vccin(217)" )
				)
				( pin "U2D1.BD81"
					( objectStatus "vccin(218)" )
				)
				( pin "U2D1.BD79"
					( objectStatus "vccin(219)" )
				)
				( pin "U2D1.BD77"
					( objectStatus "vccin(220)" )
				)
				( pin "U2D1.BD75"
					( objectStatus "vccin(221)" )
				)
				( pin "U2D1.BD73"
					( objectStatus "vccin(222)" )
				)
				( pin "U2D1.BD61"
					( objectStatus "vccin(223)" )
				)
				( pin "U2D1.BC84"
					( objectStatus "vccin(224)" )
				)
				( pin "U2D1.BC62"
					( objectStatus "vccin(225)" )
				)
				( pin "U2D1.BC60"
					( objectStatus "vccin(226)" )
				)
				( pin "U2D1.BB85"
					( objectStatus "vccin(227)" )
				)
				( pin "U2D1.BB61"
					( objectStatus "vccin(228)" )
				)
				( pin "U2D1.BA60"
					( objectStatus "vccin(229)" )
				)
				( pin "U2D1.AY61"
					( objectStatus "vccin(230)" )
				)
				( pin "U2D1.AW60"
					( objectStatus "vccin(231)" )
				)
				( pin "U2D1.AV61"
					( objectStatus "vccin(232)" )
				)
				( pin "U2D1.AV59"
					( objectStatus "vccin(233)" )
				)
				( pin "U2D1.AU60"
					( objectStatus "vccin(234)" )
				)
				( pin "U2D1.AU58"
					( objectStatus "vccin(235)" )
				)
				( pin "U2D1.AT59"
					( objectStatus "vccin(236)" )
				)
				( pin "U2D1.AT57"
					( objectStatus "vccin(237)" )
				)
				( pin "U2D1.AR58"
					( objectStatus "vccin(238)" )
				)
				( pin "U2D1.AR56"
					( objectStatus "vccin(239)" )
				)
				( pin "U2D1.AP57"
					( objectStatus "vccin(240)" )
				)
				( pin "U2D1.AP55"
					( objectStatus "vccin(241)" )
				)
				( pin "U2D1.AN56"
					( objectStatus "vccin(242)" )
				)
				( pin "U2D1.AN54"
					( objectStatus "vccin(243)" )
				)
				( pin "U2D1.AN32"
					( objectStatus "vccin(244)" )
				)
				( pin "U2D1.AM55"
					( objectStatus "vccin(245)" )
				)
				( pin "U2D1.AM53"
					( objectStatus "vccin(246)" )
				)
				( pin "U2D1.AM33"
					( objectStatus "vccin(247)" )
				)
				( pin "U2D1.AL54"
					( objectStatus "vccin(248)" )
				)
				( pin "U2D1.AL52"
					( objectStatus "vccin(249)" )
				)
				( pin "U2D1.AL50"
					( objectStatus "vccin(250)" )
				)
				( pin "U2D1.AL48"
					( objectStatus "vccin(251)" )
				)
				( pin "U2D1.AL46"
					( objectStatus "vccin(252)" )
				)
				( pin "U2D1.AL34"
					( objectStatus "vccin(253)" )
				)
				( pin "U2D1.AK53"
					( objectStatus "vccin(254)" )
				)
				( pin "U2D1.AK51"
					( objectStatus "vccin(255)" )
				)
				( pin "U2D1.AK49"
					( objectStatus "vccin(256)" )
				)
				( pin "U2D1.AK47"
					( objectStatus "vccin(257)" )
				)
				( pin "U2D1.AK45"
					( objectStatus "vccin(258)" )
				)
				( pin "U2D1.AK35"
					( objectStatus "vccin(259)" )
				)
				( pin "U2D1.AJ36"
					( objectStatus "vccin(260)" )
				)
				( pin "U2D1.AH41"
					( objectStatus "vccin(261)" )
				)
				( pin "U2D1.AH39"
					( objectStatus "vccin(262)" )
				)
				( pin "U2D1.AH37"
					( objectStatus "vccin(263)" )
				)
				( pin "U2D1.AG42"
					( objectStatus "vccin(264)" )
				)
				( pin "U2D1.AG40"
					( objectStatus "vccin(265)" )
				)
				( pin "U2D1.AG38"
					( objectStatus "vccin(266)" )
				)
				( pin "U2D1.AF43"
					( objectStatus "vccin(267)" )
				)
			)
			( gate "U2D1"
				( objectStatus "@baseboard_fab2_lib.baseboard_fab2(sch_1):page71_i51" )
				( pin "U2D1.CY49"
					( objectStatus "vccin(0)" )
				)
				( pin "U2D1.CY47"
					( objectStatus "vccin(1)" )
				)
				( pin "U2D1.CW50"
					( objectStatus "vccin(2)" )
				)
				( pin "U2D1.CW48"
					( objectStatus "vccin(3)" )
				)
				( pin "U2D1.CW46"
					( objectStatus "vccin(4)" )
				)
				( pin "U2D1.CV51"
					( objectStatus "vccin(5)" )
				)
				( pin "U2D1.CU54"
					( objectStatus "vccin(6)" )
				)
				( pin "U2D1.CU52"
					( objectStatus "vccin(7)" )
				)
				( pin "U2D1.CU42"
					( objectStatus "vccin(8)" )
				)
				( pin "U2D1.CU40"
					( objectStatus "vccin(9)" )
				)
				( pin "U2D1.CU38"
					( objectStatus "vccin(10)" )
				)
				( pin "U2D1.CT55"
					( objectStatus "vccin(11)" )
				)
				( pin "U2D1.CT53"
					( objectStatus "vccin(12)" )
				)
				( pin "U2D1.CT41"
					( objectStatus "vccin(13)" )
				)
				( pin "U2D1.CT39"
					( objectStatus "vccin(14)" )
				)
				( pin "U2D1.CT37"
					( objectStatus "vccin(15)" )
				)
				( pin "U2D1.CR56"
					( objectStatus "vccin(16)" )
				)
				( pin "U2D1.CR54"
					( objectStatus "vccin(17)" )
				)
				( pin "U2D1.CR34"
					( objectStatus "vccin(18)" )
				)
				( pin "U2D1.CP57"
					( objectStatus "vccin(19)" )
				)
				( pin "U2D1.CP55"
					( objectStatus "vccin(20)" )
				)
				( pin "U2D1.CP33"
					( objectStatus "vccin(21)" )
				)
				( pin "U2D1.CN58"
					( objectStatus "vccin(22)" )
				)
				( pin "U2D1.CN56"
					( objectStatus "vccin(23)" )
				)
				( pin "U2D1.CM59"
					( objectStatus "vccin(24)" )
				)
				( pin "U2D1.CM57"
					( objectStatus "vccin(25)" )
				)
				( pin "U2D1.CL60"
					( objectStatus "vccin(26)" )
				)
				( pin "U2D1.CL58"
					( objectStatus "vccin(27)" )
				)
				( pin "U2D1.CK61"
					( objectStatus "vccin(28)" )
				)
				( pin "U2D1.CK59"
					( objectStatus "vccin(29)" )
				)
				( pin "U2D1.CJ60"
					( objectStatus "vccin(30)" )
				)
				( pin "U2D1.CH85"
					( objectStatus "vccin(31)" )
				)
				( pin "U2D1.CH61"
					( objectStatus "vccin(32)" )
				)
				( pin "U2D1.CG84"
					( objectStatus "vccin(33)" )
				)
				( pin "U2D1.CG60"
					( objectStatus "vccin(34)" )
				)
				( pin "U2D1.CF85"
					( objectStatus "vccin(35)" )
				)
				( pin "U2D1.CF61"
					( objectStatus "vccin(36)" )
				)
				( pin "U2D1.CE84"
					( objectStatus "vccin(37)" )
				)
				( pin "U2D1.CE60"
					( objectStatus "vccin(38)" )
				)
				( pin "U2D1.CD85"
					( objectStatus "vccin(39)" )
				)
				( pin "U2D1.CD83"
					( objectStatus "vccin(40)" )
				)
				( pin "U2D1.CD61"
					( objectStatus "vccin(41)" )
				)
				( pin "U2D1.CC84"
					( objectStatus "vccin(42)" )
				)
				( pin "U2D1.CC62"
					( objectStatus "vccin(43)" )
				)
				( pin "U2D1.CC60"
					( objectStatus "vccin(44)" )
				)
				( pin "U2D1.CB83"
					( objectStatus "vccin(45)" )
				)
				( pin "U2D1.CB81"
					( objectStatus "vccin(46)" )
				)
				( pin "U2D1.CB79"
					( objectStatus "vccin(47)" )
				)
				( pin "U2D1.CB77"
					( objectStatus "vccin(48)" )
				)
				( pin "U2D1.CB75"
					( objectStatus "vccin(49)" )
				)
				( pin "U2D1.CB73"
					( objectStatus "vccin(50)" )
				)
				( pin "U2D1.CB61"
					( objectStatus "vccin(51)" )
				)
				( pin "U2D1.CA84"
					( objectStatus "vccin(52)" )
				)
				( pin "U2D1.CA82"
					( objectStatus "vccin(53)" )
				)
				( pin "U2D1.CA80"
					( objectStatus "vccin(54)" )
				)
				( pin "U2D1.CA78"
					( objectStatus "vccin(55)" )
				)
				( pin "U2D1.CA76"
					( objectStatus "vccin(56)" )
				)
				( pin "U2D1.CA74"
					( objectStatus "vccin(57)" )
				)
				( pin "U2D1.CA72"
					( objectStatus "vccin(58)" )
				)
				( pin "U2D1.CA62"
					( objectStatus "vccin(59)" )
				)
				( pin "U2D1.CA60"
					( objectStatus "vccin(60)" )
				)
				( pin "U2D1.BY83"
					( objectStatus "vccin(61)" )
				)
				( pin "U2D1.BY81"
					( objectStatus "vccin(62)" )
				)
				( pin "U2D1.BY79"
					( objectStatus "vccin(63)" )
				)
				( pin "U2D1.BY77"
					( objectStatus "vccin(64)" )
				)
				( pin "U2D1.BY75"
					( objectStatus "vccin(65)" )
				)
				( pin "U2D1.BY73"
					( objectStatus "vccin(66)" )
				)
				( pin "U2D1.BY61"
					( objectStatus "vccin(67)" )
				)
				( pin "U2D1.BW84"
					( objectStatus "vccin(68)" )
				)
				( pin "U2D1.BW70"
					( objectStatus "vccin(69)" )
				)
				( pin "U2D1.BW68"
					( objectStatus "vccin(70)" )
				)
				( pin "U2D1.BW66"
					( objectStatus "vccin(71)" )
				)
				( pin "U2D1.BW64"
					( objectStatus "vccin(72)" )
				)
				( pin "U2D1.BW62"
					( objectStatus "vccin(73)" )
				)
				( pin "U2D1.BW60"
					( objectStatus "vccin(74)" )
				)
				( pin "U2D1.BV83"
					( objectStatus "vccin(75)" )
				)
				( pin "U2D1.BV81"
					( objectStatus "vccin(76)" )
				)
				( pin "U2D1.BV79"
					( objectStatus "vccin(77)" )
				)
				( pin "U2D1.BV77"
					( objectStatus "vccin(78)" )
				)
				( pin "U2D1.BV75"
					( objectStatus "vccin(79)" )
				)
				( pin "U2D1.BV73"
					( objectStatus "vccin(80)" )
				)
				( pin "U2D1.BV71"
					( objectStatus "vccin(81)" )
				)
				( pin "U2D1.BV69"
					( objectStatus "vccin(82)" )
				)
				( pin "U2D1.BV67"
					( objectStatus "vccin(83)" )
				)
				( pin "U2D1.BV65"
					( objectStatus "vccin(84)" )
				)
				( pin "U2D1.BV63"
					( objectStatus "vccin(85)" )
				)
				( pin "U2D1.BV61"
					( objectStatus "vccin(86)" )
				)
				( pin "U2D1.BU84"
					( objectStatus "vccin(87)" )
				)
				( pin "U2D1.BU82"
					( objectStatus "vccin(88)" )
				)
				( pin "U2D1.BU80"
					( objectStatus "vccin(89)" )
				)
				( pin "U2D1.BU78"
					( objectStatus "vccin(90)" )
				)
				( pin "U2D1.BU76"
					( objectStatus "vccin(91)" )
				)
				( pin "U2D1.BU74"
					( objectStatus "vccin(92)" )
				)
				( pin "U2D1.BU72"
					( objectStatus "vccin(93)" )
				)
				( pin "U2D1.BU70"
					( objectStatus "vccin(94)" )
				)
				( pin "U2D1.BU68"
					( objectStatus "vccin(95)" )
				)
				( pin "U2D1.BU66"
					( objectStatus "vccin(96)" )
				)
				( pin "U2D1.BU64"
					( objectStatus "vccin(97)" )
				)
				( pin "U2D1.BU62"
					( objectStatus "vccin(98)" )
				)
				( pin "U2D1.BU60"
					( objectStatus "vccin(99)" )
				)
				( pin "U2D1.BT83"
					( objectStatus "vccin(100)" )
				)
				( pin "U2D1.BT81"
					( objectStatus "vccin(101)" )
				)
				( pin "U2D1.BT79"
					( objectStatus "vccin(102)" )
				)
				( pin "U2D1.BT77"
					( objectStatus "vccin(103)" )
				)
				( pin "U2D1.BT75"
					( objectStatus "vccin(104)" )
				)
				( pin "U2D1.BT73"
					( objectStatus "vccin(105)" )
				)
				( pin "U2D1.BT71"
					( objectStatus "vccin(106)" )
				)
				( pin "U2D1.BT69"
					( objectStatus "vccin(107)" )
				)
				( pin "U2D1.BT67"
					( objectStatus "vccin(108)" )
				)
				( pin "U2D1.BT65"
					( objectStatus "vccin(109)" )
				)
				( pin "U2D1.BT63"
					( objectStatus "vccin(110)" )
				)
				( pin "U2D1.BT61"
					( objectStatus "vccin(111)" )
				)
				( pin "U2D1.BR84"
					( objectStatus "vccin(112)" )
				)
				( pin "U2D1.BR62"
					( objectStatus "vccin(113)" )
				)
				( pin "U2D1.BR60"
					( objectStatus "vccin(114)" )
				)
				( pin "U2D1.BP83"
					( objectStatus "vccin(115)" )
				)
				( pin "U2D1.BP81"
					( objectStatus "vccin(116)" )
				)
				( pin "U2D1.BP79"
					( objectStatus "vccin(117)" )
				)
				( pin "U2D1.BP77"
					( objectStatus "vccin(118)" )
				)
				( pin "U2D1.BP75"
					( objectStatus "vccin(119)" )
				)
				( pin "U2D1.BP73"
					( objectStatus "vccin(120)" )
				)
				( pin "U2D1.BP71"
					( objectStatus "vccin(121)" )
				)
				( pin "U2D1.BP69"
					( objectStatus "vccin(122)" )
				)
				( pin "U2D1.BP67"
					( objectStatus "vccin(123)" )
				)
				( pin "U2D1.BP65"
					( objectStatus "vccin(124)" )
				)
				( pin "U2D1.BP63"
					( objectStatus "vccin(125)" )
				)
				( pin "U2D1.BP61"
					( objectStatus "vccin(126)" )
				)
				( pin "U2D1.BN84"
					( objectStatus "vccin(127)" )
				)
				( pin "U2D1.BN82"
					( objectStatus "vccin(128)" )
				)
				( pin "U2D1.BN80"
					( objectStatus "vccin(129)" )
				)
				( pin "U2D1.BA86"
					( objectStatus "vccin_sense" )
				)
				( pin "U2D1.AW86"
					( objectStatus "vccinpmax(0)" )
				)
				( pin "U2D1.AV85"
					( objectStatus "vccinpmax(1)" )
				)
				( pin "U2D1.AD41"
					( objectStatus "vsensepmax" )
				)
				( pin "U2D1.AY85"
					( objectStatus "vss_vccin_sense" )
				)
			)
			( gate "R15"
				( objectStatus "@baseboard_fab2_lib.baseboard_fab2(sch_1):page71_i53" )
				( pin "R15.1"
					( objectStatus "a" )
				)
				( pin "R15.2"
					( objectStatus "b" )
				)
			)
			( gate "C3D3"
				( objectStatus "@baseboard_fab2_lib.baseboard_fab2(sch_1):page72_i25" )
				( pin "C3D3.1"
					( objectStatus "a" )
				)
				( pin "C3D3.2"
					( objectStatus "b" )
				)
			)
			( gate "U2D1"
				( objectStatus "@baseboard_fab2_lib.baseboard_fab2(sch_1):page72_i32" )
				( pin "U2D1.B49"
					( objectStatus "vccd012(0)" )
				)
				( pin "U2D1.B53"
					( objectStatus "vccd012(1)" )
				)
				( pin "U2D1.B59"
					( objectStatus "vccd012(2)" )
				)
				( pin "U2D1.E46"
					( objectStatus "vccd012(3)" )
				)
				( pin "U2D1.E48"
					( objectStatus "vccd012(4)" )
				)
				( pin "U2D1.E50"
					( objectStatus "vccd012(5)" )
				)
				( pin "U2D1.E52"
					( objectStatus "vccd012(6)" )
				)
				( pin "U2D1.E54"
					( objectStatus "vccd012(7)" )
				)
				( pin "U2D1.E56"
					( objectStatus "vccd012(8)" )
				)
				( pin "U2D1.E58"
					( objectStatus "vccd012(9)" )
				)
				( pin "U2D1.E60"
					( objectStatus "vccd012(10)" )
				)
				( pin "U2D1.E62"
					( objectStatus "vccd012(11)" )
				)
				( pin "U2D1.E64"
					( objectStatus "vccd012(12)" )
				)
				( pin "U2D1.L46"
					( objectStatus "vccd012(13)" )
				)
				( pin "U2D1.L48"
					( objectStatus "vccd012(14)" )
				)
				( pin "U2D1.L50"
					( objectStatus "vccd012(15)" )
				)
				( pin "U2D1.L52"
					( objectStatus "vccd012(16)" )
				)
				( pin "U2D1.L54"
					( objectStatus "vccd012(17)" )
				)
				( pin "U2D1.L56"
					( objectStatus "vccd012(18)" )
				)
				( pin "U2D1.L58"
					( objectStatus "vccd012(19)" )
				)
				( pin "U2D1.L60"
					( objectStatus "vccd012(20)" )
				)
				( pin "U2D1.L62"
					( objectStatus "vccd012(21)" )
				)
				( pin "U2D1.N64"
					( objectStatus "vccd012(22)" )
				)
				( pin "U2D1.U46"
					( objectStatus "vccd012(23)" )
				)
				( pin "U2D1.U48"
					( objectStatus "vccd012(24)" )
				)
				( pin "U2D1.U50"
					( objectStatus "vccd012(25)" )
				)
				( pin "U2D1.U52"
					( objectStatus "vccd012(26)" )
				)
				( pin "U2D1.U54"
					( objectStatus "vccd012(27)" )
				)
				( pin "U2D1.U56"
					( objectStatus "vccd012(28)" )
				)
				( pin "U2D1.U58"
					( objectStatus "vccd012(29)" )
				)
				( pin "U2D1.U60"
					( objectStatus "vccd012(30)" )
				)
				( pin "U2D1.U62"
					( objectStatus "vccd012(31)" )
				)
				( pin "U2D1.W64"
					( objectStatus "vccd012(32)" )
				)
				( pin "U2D1.Y45"
					( objectStatus "vccd012(33)" )
				)
				( pin "U2D1.Y47"
					( objectStatus "vccd012(34)" )
				)
				( pin "U2D1.Y49"
					( objectStatus "vccd012(35)" )
				)
				( pin "U2D1.Y51"
					( objectStatus "vccd012(36)" )
				)
				( pin "U2D1.Y53"
					( objectStatus "vccd012(37)" )
				)
				( pin "U2D1.Y55"
					( objectStatus "vccd012(38)" )
				)
				( pin "U2D1.Y57"
					( objectStatus "vccd012(39)" )
				)
				( pin "U2D1.Y59"
					( objectStatus "vccd012(40)" )
				)
				( pin "U2D1.Y61"
					( objectStatus "vccd012(41)" )
				)
				( pin "U2D1.Y63"
					( objectStatus "vccd012(42)" )
				)
				( pin "U2D1.AD45"
					( objectStatus "vccd012(43)" )
				)
				( pin "U2D1.AF55"
					( objectStatus "vccd012(44)" )
				)
				( pin "U2D1.AF57"
					( objectStatus "vccd012(45)" )
				)
				( pin "U2D1.AF59"
					( objectStatus "vccd012(46)" )
				)
				( pin "U2D1.AF61"
					( objectStatus "vccd012(47)" )
				)
				( pin "U2D1.AF63"
					( objectStatus "vccd012(48)" )
				)
				( pin "U2D1.D45"
					( objectStatus "vccd012(49)" )
				)
				( pin "U2D1.C46"
					( objectStatus "vccd012(50)" )
				)
				( pin "U2D1.B47"
					( objectStatus "vccd012(51)" )
				)
				( pin "U2D1.EF59"
					( objectStatus "vccd345(0)" )
				)
				( pin "U2D1.EF53"
					( objectStatus "vccd345(1)" )
				)
				( pin "U2D1.EF49"
					( objectStatus "vccd345(2)" )
				)
				( pin "U2D1.EC62"
					( objectStatus "vccd345(3)" )
				)
				( pin "U2D1.EC60"
					( objectStatus "vccd345(4)" )
				)
				( pin "U2D1.EC58"
					( objectStatus "vccd345(5)" )
				)
				( pin "U2D1.EC56"
					( objectStatus "vccd345(6)" )
				)
				( pin "U2D1.EC54"
					( objectStatus "vccd345(7)" )
				)
				( pin "U2D1.EC52"
					( objectStatus "vccd345(8)" )
				)
				( pin "U2D1.EC50"
					( objectStatus "vccd345(9)" )
				)
				( pin "U2D1.EC48"
					( objectStatus "vccd345(10)" )
				)
				( pin "U2D1.EC46"
					( objectStatus "vccd345(11)" )
				)
				( pin "U2D1.DU64"
					( objectStatus "vccd345(12)" )
				)
				( pin "U2D1.DU62"
					( objectStatus "vccd345(13)" )
				)
				( pin "U2D1.DU60"
					( objectStatus "vccd345(14)" )
				)
				( pin "U2D1.DU58"
					( objectStatus "vccd345(15)" )
				)
				( pin "U2D1.DU56"
					( objectStatus "vccd345(16)" )
				)
				( pin "U2D1.DU54"
					( objectStatus "vccd345(17)" )
				)
				( pin "U2D1.DU52"
					( objectStatus "vccd345(18)" )
				)
				( pin "U2D1.DU50"
					( objectStatus "vccd345(19)" )
				)
				( pin "U2D1.DU48"
					( objectStatus "vccd345(20)" )
				)
				( pin "U2D1.DU46"
					( objectStatus "vccd345(21)" )
				)
				( pin "U2D1.DL62"
					( objectStatus "vccd345(22)" )
				)
				( pin "U2D1.DL60"
					( objectStatus "vccd345(23)" )
				)
				( pin "U2D1.DL58"
					( objectStatus "vccd345(24)" )
				)
				( pin "U2D1.DL56"
					( objectStatus "vccd345(25)" )
				)
				( pin "U2D1.DL54"
					( objectStatus "vccd345(26)" )
				)
				( pin "U2D1.DL52"
					( objectStatus "vccd345(27)" )
				)
				( pin "U2D1.DL50"
					( objectStatus "vccd345(28)" )
				)
				( pin "U2D1.DL48"
					( objectStatus "vccd345(29)" )
				)
				( pin "U2D1.DL46"
					( objectStatus "vccd345(30)" )
				)
				( pin "U2D1.DJ64"
					( objectStatus "vccd345(31)" )
				)
				( pin "U2D1.DH63"
					( objectStatus "vccd345(32)" )
				)
				( pin "U2D1.DH61"
					( objectStatus "vccd345(33)" )
				)
				( pin "U2D1.DH59"
					( objectStatus "vccd345(34)" )
				)
				( pin "U2D1.DH57"
					( objectStatus "vccd345(35)" )
				)
				( pin "U2D1.DH55"
					( objectStatus "vccd345(36)" )
				)
				( pin "U2D1.DH53"
					( objectStatus "vccd345(37)" )
				)
				( pin "U2D1.DH51"
					( objectStatus "vccd345(38)" )
				)
				( pin "U2D1.DH49"
					( objectStatus "vccd345(39)" )
				)
				( pin "U2D1.DH47"
					( objectStatus "vccd345(40)" )
				)
				( pin "U2D1.DH45"
					( objectStatus "vccd345(41)" )
				)
				( pin "U2D1.DD45"
					( objectStatus "vccd345(42)" )
				)
				( pin "U2D1.DB63"
					( objectStatus "vccd345(43)" )
				)
				( pin "U2D1.DB61"
					( objectStatus "vccd345(44)" )
				)
				( pin "U2D1.DB59"
					( objectStatus "vccd345(45)" )
				)
				( pin "U2D1.DB57"
					( objectStatus "vccd345(46)" )
				)
				( pin "U2D1.DB55"
					( objectStatus "vccd345(47)" )
				)
				( pin "U2D1.DB53"
					( objectStatus "vccd345(48)" )
				)
				( pin "U2D1.EF45"
					( objectStatus "vccd345(49)" )
				)
				( pin "U2D1.EE44"
					( objectStatus "vccd345(50)" )
				)
			)
			( gate "U2D1"
				( objectStatus "@baseboard_fab2_lib.baseboard_fab2(sch_1):page72_i33" )
				( pin "U2D1.BL14"
					( objectStatus "cd_vcc_core(0)" )
				)
				( pin "U2D1.BK15"
					( objectStatus "cd_vcc_core(1)" )
				)
				( pin "U2D1.BK13"
					( objectStatus "cd_vcc_core(2)" )
				)
				( pin "U2D1.BJ14"
					( objectStatus "cd_vcc_core(3)" )
				)
				( pin "U2D1.BJ12"
					( objectStatus "cd_vcc_core(4)" )
				)
				( pin "U2D1.BH13"
					( objectStatus "cd_vcc_core(5)" )
				)
				( pin "U2D1.BG14"
					( objectStatus "cd_vcc_core(6)" )
				)
				( pin "U2D1.BG12"
					( objectStatus "cd_vcc_core(7)" )
				)
				( pin "U2D1.BF13"
					( objectStatus "cd_vcc_core(8)" )
				)
				( pin "U2D1.BF11"
					( objectStatus "cd_vcc_core(9)" )
				)
				( pin "U2D1.BE14"
					( objectStatus "cd_vcc_core(10)" )
				)
				( pin "U2D1.BE12"
					( objectStatus "cd_vcc_core(11)" )
				)
				( pin "U2D1.BD13"
					( objectStatus "cd_vcc_core(12)" )
				)
				( pin "U2D1.BT27"
					( objectStatus "cd_vccin(0)" )
				)
				( pin "U2D1.BU26"
					( objectStatus "cd_vccin(1)" )
				)
				( pin "U2D1.BV27"
					( objectStatus "cd_vccin(2)" )
				)
				( pin "U2D1.BY27"
					( objectStatus "cd_vccin(3)" )
				)
				( pin "U2D1.BV15"
					( objectStatus "cd_vccp(0)" )
				)
				( pin "U2D1.BV13"
					( objectStatus "cd_vccp(1)" )
				)
				( pin "U2D1.BV11"
					( objectStatus "cd_vccp(2)" )
				)
				( pin "U2D1.BU14"
					( objectStatus "cd_vccp(3)" )
				)
				( pin "U2D1.BU12"
					( objectStatus "cd_vccp(4)" )
				)
				( pin "U2D1.BT15"
					( objectStatus "cd_vccp(5)" )
				)
				( pin "U2D1.BT13"
					( objectStatus "cd_vccp(6)" )
				)
				( pin "U2D1.BT11"
					( objectStatus "cd_vccp(7)" )
				)
				( pin "U2D1.BR14"
					( objectStatus "cd_vccp(8)" )
				)
				( pin "U2D1.BR12"
					( objectStatus "cd_vccp(9)" )
				)
				( pin "U2D1.BP15"
					( objectStatus "cd_vccp(10)" )
				)
				( pin "U2D1.BP13"
					( objectStatus "cd_vccp(11)" )
				)
				( pin "U2D1.BP11"
					( objectStatus "cd_vccp(12)" )
				)
				( pin "U2D1.BN14"
					( objectStatus "cd_vccp(13)" )
				)
				( pin "U2D1.BN12"
					( objectStatus "cd_vccp(14)" )
				)
				( pin "U2D1.BM11"
					( objectStatus "cd_vccp(15)" )
				)
				( pin "U2D1.B11"
					( objectStatus "cd_vpp(0)" )
				)
				( pin "U2D1.A12"
					( objectStatus "cd_vpp(1)" )
				)
				( pin "U2D1.A10"
					( objectStatus "cd_vpp(2)" )
				)
				( pin "U2D1.A8"
					( objectStatus "cd_vpp(3)" )
				)
				( pin "U2D1.CY55"
					( objectStatus "vcc33" )
				)
				( pin "U2D1.CM15"
					( objectStatus "vccio(20)" )
				)
				( pin "U2D1.CL12"
					( objectStatus "vccio(21)" )
				)
				( pin "U2D1.CK5"
					( objectStatus "vccio(22)" )
				)
				( pin "U2D1.CV7"
					( objectStatus "vccio(23)" )
				)
				( pin "U2D1.CH9"
					( objectStatus "vccio(24)" )
				)
				( pin "U2D1.D7"
					( objectStatus "vccio(25)" )
				)
				( pin "U2D1.CE18"
					( objectStatus "vccio(26)" )
				)
				( pin "U2D1.CD9"
					( objectStatus "vccio(27)" )
				)
				( pin "U2D1.CB17"
					( objectStatus "vccio(28)" )
				)
				( pin "U2D1.CB13"
					( objectStatus "vccio(29)" )
				)
				( pin "U2D1.BP25"
					( objectStatus "vccio(30)" )
				)
				( pin "U2D1.BJ24"
					( objectStatus "vccio(31)" )
				)
				( pin "U2D1.BF23"
					( objectStatus "vccio(32)" )
				)
				( pin "U2D1.DA14"
					( objectStatus "vccio(33)" )
				)
				( pin "U2D1.BB5"
					( objectStatus "vccio(34)" )
				)
				( pin "U2D1.BA24"
					( objectStatus "vccio(35)" )
				)
				( pin "U2D1.AY11"
					( objectStatus "vccio(36)" )
				)
				( pin "U2D1.AW6"
					( objectStatus "vccio(37)" )
				)
				( pin "U2D1.AT11"
					( objectStatus "vccio(38)" )
				)
				( pin "U2D1.DD7"
					( objectStatus "vccio(39)" )
				)
				( pin "U2D1.AN10"
					( objectStatus "vccio(40)" )
				)
				( pin "U2D1.DF13"
					( objectStatus "vccio(41)" )
				)
				( pin "U2D1.AH9"
					( objectStatus "vccio(42)" )
				)
				( pin "U2D1.AC4"
					( objectStatus "vccio(43)" )
				)
				( pin "U2D1.AC20"
					( objectStatus "vccio(44)" )
				)
				( pin "U2D1.AA10"
					( objectStatus "vccio(45)" )
				)
				( pin "U2D1.W6"
					( objectStatus "vccio(46)" )
				)
				( pin "U2D1.W4"
					( objectStatus "vccio(47)" )
				)
				( pin "U2D1.DF21"
					( objectStatus "vccio(48)" )
				)
				( pin "U2D1.U14"
					( objectStatus "vccio(49)" )
				)
				( pin "U2D1.T3"
					( objectStatus "vccio(50)" )
				)
				( pin "U2D1.P5"
					( objectStatus "vccio(51)" )
				)
				( pin "U2D1.M21"
					( objectStatus "vccio(52)" )
				)
				( pin "U2D1.M11"
					( objectStatus "vccio(53)" )
				)
				( pin "U2D1.DG8"
					( objectStatus "vccio(54)" )
				)
				( pin "U2D1.DH7"
					( objectStatus "vccio(55)" )
				)
				( pin "U2D1.L16"
					( objectStatus "vccio(56)" )
				)
				( pin "U2D1.L14"
					( objectStatus "vccio(57)" )
				)
				( pin "U2D1.J10"
					( objectStatus "vccio(58)" )
				)
				( pin "U2D1.H13"
					( objectStatus "vccio(59)" )
				)
				( pin "U2D1.DJ16"
					( objectStatus "vccio(60)" )
				)
				( pin "U2D1.DM17"
					( objectStatus "vccio(61)" )
				)
				( pin "U2D1.DN8"
					( objectStatus "vccio(62)" )
				)
				( pin "U2D1.DP19"
					( objectStatus "vccio(63)" )
				)
				( pin "U2D1.DR10"
					( objectStatus "vccio(64)" )
				)
				( pin "U2D1.DR2"
					( objectStatus "vccio(65)" )
				)
				( pin "U2D1.DU20"
					( objectStatus "vccio(66)" )
				)
				( pin "U2D1.EA12"
					( objectStatus "vccio(67)" )
				)
				( pin "U2D1.EB15"
					( objectStatus "vccio(68)" )
				)
				( pin "U2D1.J2"
					( objectStatus "vccio(69)" )
				)
				( pin "U2D1.K15"
					( objectStatus "vccio(70)" )
				)
				( pin "U2D1.M7"
					( objectStatus "vccio(71)" )
				)
				( pin "U2D1.M9"
					( objectStatus "vccio(72)" )
				)
				( pin "U2D1.N18"
					( objectStatus "vccio(73)" )
				)
				( pin "U2D1.W10"
					( objectStatus "vccio(74)" )
				)
				( pin "U2D1.BC26"
					( objectStatus "vccio(75)" )
				)
				( pin "U2D1.BB27"
					( objectStatus "vccio(76)" )
				)
				( pin "U2D1.BA26"
					( objectStatus "vccio(77)" )
				)
				( pin "U2D1.AY27"
					( objectStatus "vccio(78)" )
				)
				( pin "U2D1.AW26"
					( objectStatus "vccio(79)" )
				)
				( pin "U2D1.AV27"
					( objectStatus "vccio(80)" )
				)
				( pin "U2D1.CF27"
					( objectStatus "vccio(81)" )
				)
				( pin "U2D1.CD27"
					( objectStatus "vccio(82)" )
				)
				( pin "U2D1.CC26"
					( objectStatus "vccio(83)" )
				)
				( pin "U2D1.CJ28"
					( objectStatus "vccio(84)" )
				)
				( pin "U2D1.CH27"
					( objectStatus "vccio(85)" )
				)
				( pin "U2D1.BM27"
					( objectStatus "vccio(86)" )
				)
				( pin "U2D1.BL26"
					( objectStatus "vccio(87)" )
				)
				( pin "U2D1.BK27"
					( objectStatus "vccio(88)" )
				)
				( pin "U2D1.BK25"
					( objectStatus "vccio(89)" )
				)
				( pin "U2D1.BJ26"
					( objectStatus "vccio(90)" )
				)
				( pin "U2D1.BH27"
					( objectStatus "vccio(91)" )
				)
				( pin "U2D1.BH25"
					( objectStatus "vccio(92)" )
				)
				( pin "U2D1.BG26"
					( objectStatus "vccio(93)" )
				)
				( pin "U2D1.BF27"
					( objectStatus "vccio(94)" )
				)
				( pin "U2D1.AE36"
					( objectStatus "vccio(95)" )
				)
				( pin "U2D1.AD37"
					( objectStatus "vccio(96)" )
				)
				( pin "U2D1.AC36"
					( objectStatus "vccio(97)" )
				)
				( pin "U2D1.AF35"
					( objectStatus "vccio(98)" )
				)
				( pin "U2D1.AD35"
					( objectStatus "vccio(99)" )
				)
				( pin "U2D1.AE34"
					( objectStatus "vccio(100)" )
				)
				( pin "U2D1.AG34"
					( objectStatus "vccio(101)" )
				)
				( pin "U2D1.AM29"
					( objectStatus "vccio(102)" )
				)
				( pin "U2D1.AL28"
					( objectStatus "vccio(103)" )
				)
				( pin "U2D1.AR28"
					( objectStatus "vccio(104)" )
				)
				( pin "U2D1.CJ66"
					( objectStatus "vccsa(0)" )
				)
				( pin "U2D1.CJ64"
					( objectStatus "vccsa(1)" )
				)
				( pin "U2D1.CH75"
					( objectStatus "vccsa(2)" )
				)
				( pin "U2D1.CH65"
					( objectStatus "vccsa(3)" )
				)
				( pin "U2D1.CG74"
					( objectStatus "vccsa(4)" )
				)
				( pin "U2D1.CG66"
					( objectStatus "vccsa(5)" )
				)
				( pin "U2D1.CG64"
					( objectStatus "vccsa(6)" )
				)
				( pin "U2D1.CF75"
					( objectStatus "vccsa(7)" )
				)
				( pin "U2D1.CF73"
					( objectStatus "vccsa(8)" )
				)
				( pin "U2D1.CF67"
					( objectStatus "vccsa(9)" )
				)
				( pin "U2D1.CF65"
					( objectStatus "vccsa(10)" )
				)
				( pin "U2D1.CE74"
					( objectStatus "vccsa(11)" )
				)
				( pin "U2D1.CE72"
					( objectStatus "vccsa(12)" )
				)
				( pin "U2D1.CE68"
					( objectStatus "vccsa(13)" )
				)
				( pin "U2D1.CE66"
					( objectStatus "vccsa(14)" )
				)
				( pin "U2D1.CE64"
					( objectStatus "vccsa(15)" )
				)
				( pin "U2D1.CD71"
					( objectStatus "vccsa(16)" )
				)
				( pin "U2D1.CD69"
					( objectStatus "vccsa(17)" )
				)
				( pin "U2D1.CD67"
					( objectStatus "vccsa(18)" )
				)
				( pin "U2D1.CD65"
					( objectStatus "vccsa(19)" )
				)
				( pin "U2D1.CC70"
					( objectStatus "vccsa(20)" )
				)
				( pin "U2D1.CC68"
					( objectStatus "vccsa(21)" )
				)
				( pin "U2D1.CC66"
					( objectStatus "vccsa(22)" )
				)
				( pin "U2D1.CB69"
					( objectStatus "vccsa(23)" )
				)
				( pin "U2D1.CB67"
					( objectStatus "vccsa(24)" )
				)
				( pin "U2D1.CB65"
					( objectStatus "vccsa(25)" )
				)
			)
			( gate "U2D1"
				( objectStatus "@baseboard_fab2_lib.baseboard_fab2(sch_1):page73_i107" )
				( pin "U2D1.BN16"
					( objectStatus "cd_vcc_core_sense" )
				)
				( pin "U2D1.BU16"
					( objectStatus "cd_vccp_sense(0)" )
				)
				( pin "U2D1.BT17"
					( objectStatus "cd_vccp_sense(1)" )
				)
				( pin "U2D1.BL16"
					( objectStatus "cd_vss_vcc_core_sense" )
				)
				( pin "U2D1.EF83"
					( objectStatus "rsvd(0)" )
				)
				( pin "U2D1.EF81"
					( objectStatus "rsvd(1)" )
				)
				( pin "U2D1.EF77"
					( objectStatus "rsvd(2)" )
				)
				( pin "U2D1.EF47"
					( objectStatus "rsvd(3)" )
				)
				( pin "U2D1.EE84"
					( objectStatus "rsvd(4)" )
				)
				( pin "U2D1.EE82"
					( objectStatus "rsvd(5)" )
				)
				( pin "U2D1.EE6"
					( objectStatus "rsvd(6)" )
				)
				( pin "U2D1.EE46"
					( objectStatus "rsvd(7)" )
				)
				( pin "U2D1.EE16"
					( objectStatus "rsvd(8)" )
				)
				( pin "U2D1.ED83"
					( objectStatus "rsvd(9)" )
				)
				( pin "U2D1.ED5"
					( objectStatus "rsvd(10)" )
				)
				( pin "U2D1.ED45"
					( objectStatus "rsvd(11)" )
				)
				( pin "U2D1.EC84"
					( objectStatus "rsvd(12)" )
				)
				( pin "U2D1.EC44"
					( objectStatus "rsvd(13)" )
				)
				( pin "U2D1.EC4"
					( objectStatus "rsvd(14)" )
				)
				( pin "U2D1.EC16"
					( objectStatus "rsvd(15)" )
				)
				( pin "U2D1.EB85"
					( objectStatus "rsvd(16)" )
				)
				( pin "U2D1.EB5"
					( objectStatus "rsvd(17)" )
				)
				( pin "U2D1.EB3"
					( objectStatus "rsvd(18)" )
				)
				( pin "U2D1.EA44"
					( objectStatus "rsvd(19)" )
				)
				( pin "U2D1.EA4"
					( objectStatus "rsvd(20)" )
				)
				( pin "U2D1.DY3"
					( objectStatus "rsvd(21)" )
				)
				( pin "U2D1.DW46"
					( objectStatus "rsvd(22)" )
				)
				( pin "U2D1.DW44"
					( objectStatus "rsvd(23)" )
				)
				( pin "U2D1.DV71"
					( objectStatus "rsvd(24)" )
				)
				( pin "U2D1.DV61"
					( objectStatus "rsvd(25)" )
				)
				( pin "U2D1.DU44"
					( objectStatus "rsvd(26)" )
				)
				( pin "U2D1.DT71"
					( objectStatus "rsvd(27)" )
				)
				( pin "U2D1.DR44"
					( objectStatus "rsvd(28)" )
				)
				( pin "U2D1.DP65"
					( objectStatus "rsvd(29)" )
				)
				( pin "U2D1.DP17"
					( objectStatus "rsvd(30)" )
				)
				( pin "U2D1.DN66"
					( objectStatus "rsvd(31)" )
				)
				( pin "U2D1.DN62"
					( objectStatus "rsvd(32)" )
				)
				( pin "U2D1.DM67"
					( objectStatus "rsvd(33)" )
				)
				( pin "U2D1.DL66"
					( objectStatus "rsvd(34)" )
				)
				( pin "U2D1.DL38"
					( objectStatus "rsvd(35)" )
				)
				( pin "U2D1.DK67"
					( objectStatus "rsvd(36)" )
				)
				( pin "U2D1.DK65"
					( objectStatus "rsvd(37)" )
				)
				( pin "U2D1.DK37"
					( objectStatus "rsvd(38)" )
				)
				( pin "U2D1.DK15"
					( objectStatus "rsvd(39)" )
				)
				( pin "U2D1.DJ66"
					( objectStatus "rsvd(40)" )
				)
				( pin "U2D1.DJ36"
					( objectStatus "rsvd(41)" )
				)
				( pin "U2D1.DH65"
					( objectStatus "rsvd(42)" )
				)
				( pin "U2D1.DG64"
					( objectStatus "rsvd(43)" )
				)
				( pin "U2D1.DG36"
					( objectStatus "rsvd(44)" )
				)
				( pin "U2D1.DD51"
					( objectStatus "rsvd(45)" )
				)
				( pin "U2D1.DC52"
					( objectStatus "rsvd(46)" )
				)
				( pin "U2D1.DC46"
					( objectStatus "rsvd(47)" )
				)
				( pin "U2D1.DA56"
					( objectStatus "rsvd(48)" )
				)
				( pin "U2D1.DA54"
					( objectStatus "rsvd(49)" )
				)
				( pin "U2D1.DA52"
					( objectStatus "rsvd(50)" )
				)
				( pin "U2D1.DA40"
					( objectStatus "rsvd(51)" )
				)
				( pin "U2D1.DA24"
					( objectStatus "rsvd(52)" )
				)
				( pin "U2D1.CY73"
					( objectStatus "rsvd(53)" )
				)
				( pin "U2D1.CY63"
					( objectStatus "rsvd(54)" )
				)
				( pin "U2D1.CY57"
					( objectStatus "rsvd(55)" )
				)
				( pin "U2D1.CY53"
					( objectStatus "rsvd(56)" )
				)
				( pin "U2D1.CY39"
					( objectStatus "rsvd(57)" )
				)
				( pin "U2D1.CY25"
					( objectStatus "rsvd(58)" )
				)
				( pin "U2D1.CY23"
					( objectStatus "rsvd(59)" )
				)
				( pin "U2D1.CW62"
					( objectStatus "rsvd(60)" )
				)
				( pin "U2D1.CW60"
					( objectStatus "rsvd(61)" )
				)
				( pin "U2D1.CW24"
					( objectStatus "rsvd(62)" )
				)
				( pin "U2D1.CW22"
					( objectStatus "rsvd(63)" )
				)
				( pin "U2D1.CV69"
					( objectStatus "rsvd(64)" )
				)
				( pin "U2D1.CV23"
					( objectStatus "rsvd(65)" )
				)
				( pin "U2D1.CU60"
					( objectStatus "rsvd(66)" )
				)
				( pin "U2D1.CU6"
					( objectStatus "rsvd(67)" )
				)
				( pin "U2D1.CU24"
					( objectStatus "rsvd(68)" )
				)
				( pin "U2D1.CT69"
					( objectStatus "rsvd(69)" )
				)
				( pin "U2D1.CT5"
					( objectStatus "rsvd(70)" )
				)
				( pin "U2D1.CT23"
					( objectStatus "rsvd(71)" )
				)
				( pin "U2D1.CR60"
					( objectStatus "rsvd(72)" )
				)
				( pin "U2D1.CP31"
					( objectStatus "rsvd(73)" )
				)
				( pin "U2D1.CP23"
					( objectStatus "rsvd(74)" )
				)
				( pin "U2D1.CN28"
					( objectStatus "rsvd(75)" )
				)
				( pin "U2D1.CN24"
					( objectStatus "rsvd(76)" )
				)
				( pin "U2D1.CN22"
					( objectStatus "rsvd(77)" )
				)
				( pin "U2D1.CM25"
					( objectStatus "rsvd(78)" )
				)
				( pin "U2D1.CM23"
					( objectStatus "rsvd(79)" )
				)
				( pin "U2D1.CL26"
					( objectStatus "rsvd(80)" )
				)
				( pin "U2D1.EE10"
					( objectStatus "vccio(0)" )
				)
				( pin "U2D1.AE10"
					( objectStatus "vccio(1)" )
				)
				( pin "U2D1.AF5"
					( objectStatus "vccio(2)" )
				)
				( pin "U2D1.DV11"
					( objectStatus "vccio(3)" )
				)
				( pin "U2D1.AM5"
					( objectStatus "vccio(4)" )
				)
				( pin "U2D1.AT5"
					( objectStatus "vccio(5)" )
				)
				( pin "U2D1.AT7"
					( objectStatus "vccio(6)" )
				)
				( pin "U2D1.BE24"
					( objectStatus "vccio(7)" )
				)
				( pin "U2D1.DK21"
					( objectStatus "vccio(8)" )
				)
				( pin "U2D1.CF5"
					( objectStatus "vccio(9)" )
				)
				( pin "U2D1.CG14"
					( objectStatus "vccio(10)" )
				)
				( pin "U2D1.CL20"
					( objectStatus "vccio(11)" )
				)
				( pin "U2D1.CP13"
					( objectStatus "vccio(12)" )
				)
				( pin "U2D1.DE14"
					( objectStatus "vccio(13)" )
				)
				( pin "U2D1.DC18"
					( objectStatus "vccio(14)" )
				)
				( pin "U2D1.CY17"
					( objectStatus "vccio(15)" )
				)
				( pin "U2D1.CU18"
					( objectStatus "vccio(16)" )
				)
				( pin "U2D1.CV21"
					( objectStatus "vccio(17)" )
				)
				( pin "U2D1.CU12"
					( objectStatus "vccio(18)" )
				)
				( pin "U2D1.CN6"
					( objectStatus "vccio(19)" )
				)
				( pin "U2D1.BH5"
					( objectStatus "vccio_sense" )
				)
				( pin "U2D1.CE76"
					( objectStatus "vccsa_sense" )
				)
				( pin "U2D1.BF5"
					( objectStatus "vss_vccio_sense" )
				)
				( pin "U2D1.CG76"
					( objectStatus "vss_vccsa_sense" )
				)
			)
			( gate "U2D1"
				( objectStatus "@baseboard_fab2_lib.baseboard_fab2(sch_1):page74_i20" )
				( pin "U2D1.J74"
					( objectStatus "vss(1094)" )
				)
				( pin "U2D1.J72"
					( objectStatus "vss(1095)" )
				)
				( pin "U2D1.J40"
					( objectStatus "vss(1096)" )
				)
				( pin "U2D1.J38"
					( objectStatus "vss(1097)" )
				)
				( pin "U2D1.J34"
					( objectStatus "vss(1098)" )
				)
				( pin "U2D1.J32"
					( objectStatus "vss(1099)" )
				)
				( pin "U2D1.J28"
					( objectStatus "vss(1100)" )
				)
				( pin "U2D1.J26"
					( objectStatus "vss(1101)" )
				)
				( pin "U2D1.J22"
					( objectStatus "vss(1102)" )
				)
				( pin "U2D1.J14"
					( objectStatus "vss(1103)" )
				)
				( pin "U2D1.J12"
					( objectStatus "vss(1104)" )
				)
				( pin "U2D1.J4"
					( objectStatus "vss(1105)" )
				)
				( pin "U2D1.DN44"
					( objectStatus "vss(1106)" )
				)
				( pin "U2D1.H75"
					( objectStatus "vss(1107)" )
				)
				( pin "U2D1.H71"
					( objectStatus "vss(1108)" )
				)
				( pin "U2D1.H65"
					( objectStatus "vss(1109)" )
				)
				( pin "U2D1.H41"
					( objectStatus "vss(1110)" )
				)
				( pin "U2D1.H39"
					( objectStatus "vss(1111)" )
				)
				( pin "U2D1.H37"
					( objectStatus "vss(1112)" )
				)
				( pin "U2D1.H35"
					( objectStatus "vss(1113)" )
				)
				( pin "U2D1.H33"
					( objectStatus "vss(1114)" )
				)
				( pin "U2D1.H31"
					( objectStatus "vss(1115)" )
				)
				( pin "U2D1.H29"
					( objectStatus "vss(1116)" )
				)
				( pin "U2D1.H27"
					( objectStatus "vss(1117)" )
				)
				( pin "U2D1.H25"
					( objectStatus "vss(1118)" )
				)
				( pin "U2D1.H11"
					( objectStatus "vss(1119)" )
				)
				( pin "U2D1.H3"
					( objectStatus "vss(1120)" )
				)
				( pin "U2D1.G82"
					( objectStatus "vss(1121)" )
				)
				( pin "U2D1.G80"
					( objectStatus "vss(1122)" )
				)
				( pin "U2D1.G78"
					( objectStatus "vss(1123)" )
				)
				( pin "U2D1.G76"
					( objectStatus "vss(1124)" )
				)
				( pin "U2D1.G70"
					( objectStatus "vss(1125)" )
				)
				( pin "U2D1.G66"
					( objectStatus "vss(1126)" )
				)
				( pin "U2D1.G42"
					( objectStatus "vss(1127)" )
				)
				( pin "U2D1.G38"
					( objectStatus "vss(1128)" )
				)
				( pin "U2D1.G36"
					( objectStatus "vss(1129)" )
				)
				( pin "U2D1.G32"
					( objectStatus "vss(1130)" )
				)
				( pin "U2D1.G30"
					( objectStatus "vss(1131)" )
				)
				( pin "U2D1.G26"
					( objectStatus "vss(1132)" )
				)
				( pin "U2D1.G24"
					( objectStatus "vss(1133)" )
				)
				( pin "U2D1.G22"
					( objectStatus "vss(1134)" )
				)
				( pin "U2D1.G8"
					( objectStatus "vss(1135)" )
				)
				( pin "U2D1.G4"
					( objectStatus "vss(1136)" )
				)
				( pin "U2D1.F69"
					( objectStatus "vss(1137)" )
				)
				( pin "U2D1.F67"
					( objectStatus "vss(1138)" )
				)
				( pin "U2D1.F43"
					( objectStatus "vss(1139)" )
				)
				( pin "U2D1.F37"
					( objectStatus "vss(1140)" )
				)
				( pin "U2D1.F31"
					( objectStatus "vss(1141)" )
				)
				( pin "U2D1.F25"
					( objectStatus "vss(1142)" )
				)
				( pin "U2D1.F19"
					( objectStatus "vss(1143)" )
				)
				( pin "U2D1.F17"
					( objectStatus "vss(1144)" )
				)
				( pin "U2D1.F5"
					( objectStatus "vss(1145)" )
				)
				( pin "U2D1.E76"
					( objectStatus "vss(1146)" )
				)
				( pin "U2D1.E74"
					( objectStatus "vss(1147)" )
				)
				( pin "U2D1.E72"
					( objectStatus "vss(1148)" )
				)
				( pin "U2D1.E22"
					( objectStatus "vss(1149)" )
				)
				( pin "U2D1.E20"
					( objectStatus "vss(1150)" )
				)
				( pin "U2D1.E18"
					( objectStatus "vss(1151)" )
				)
				( pin "U2D1.E16"
					( objectStatus "vss(1152)" )
				)
				( pin "U2D1.E8"
					( objectStatus "vss(1153)" )
				)
				( pin "U2D1.E6"
					( objectStatus "vss(1154)" )
				)
				( pin "U2D1.D77"
					( objectStatus "vss(1155)" )
				)
				( pin "U2D1.D43"
					( objectStatus "vss(1156)" )
				)
				( pin "U2D1.D41"
					( objectStatus "vss(1157)" )
				)
				( pin "U2D1.D39"
					( objectStatus "vss(1158)" )
				)
				( pin "U2D1.D37"
					( objectStatus "vss(1159)" )
				)
				( pin "U2D1.D35"
					( objectStatus "vss(1160)" )
				)
				( pin "U2D1.D33"
					( objectStatus "vss(1161)" )
				)
				( pin "U2D1.D31"
					( objectStatus "vss(1162)" )
				)
				( pin "U2D1.D29"
					( objectStatus "vss(1163)" )
				)
				( pin "U2D1.D27"
					( objectStatus "vss(1164)" )
				)
				( pin "U2D1.D25"
					( objectStatus "vss(1165)" )
				)
				( pin "U2D1.D13"
					( objectStatus "vss(1166)" )
				)
				( pin "U2D1.D11"
					( objectStatus "vss(1167)" )
				)
				( pin "U2D1.CM27"
					( objectStatus "vss(1168)" )
				)
				( pin "U2D1.C78"
					( objectStatus "vss(1169)" )
				)
				( pin "U2D1.C76"
					( objectStatus "vss(1170)" )
				)
				( pin "U2D1.C16"
					( objectStatus "vss(1171)" )
				)
				( pin "U2D1.C14"
					( objectStatus "vss(1172)" )
				)
				( pin "U2D1.C12"
					( objectStatus "vss(1173)" )
				)
				( pin "U2D1.C10"
					( objectStatus "vss(1174)" )
				)
				( pin "U2D1.C8"
					( objectStatus "vss(1175)" )
				)
				( pin "U2D1.B75"
					( objectStatus "vss(1176)" )
				)
				( pin "U2D1.B71"
					( objectStatus "vss(1177)" )
				)
				( pin "U2D1.B37"
					( objectStatus "vss(1178)" )
				)
				( pin "U2D1.B31"
					( objectStatus "vss(1179)" )
				)
				( pin "U2D1.B25"
					( objectStatus "vss(1180)" )
				)
				( pin "U2D1.A38"
					( objectStatus "vss(1181)" )
				)
				( pin "U2D1.A36"
					( objectStatus "vss(1182)" )
				)
				( pin "U2D1.A32"
					( objectStatus "vss(1183)" )
				)
				( pin "U2D1.A30"
					( objectStatus "vss(1184)" )
				)
				( pin "U2D1.A26"
					( objectStatus "vss(1185)" )
				)
				( pin "U2D1.AC58"
					( objectStatus "vss(1186)" )
				)
				( pin "U2D1.AC60"
					( objectStatus "vss(1187)" )
				)
				( pin "U2D1.AC62"
					( objectStatus "vss(1188)" )
				)
				( pin "U2D1.AJ4"
					( objectStatus "vss(1189)" )
				)
				( pin "U2D1.AR6"
					( objectStatus "vss(1190)" )
				)
				( pin "U2D1.CG6"
					( objectStatus "vss(1191)" )
				)
				( pin "U2D1.CW6"
					( objectStatus "vss(1192)" )
				)
				( pin "U2D1.DE48"
					( objectStatus "vss(1193)" )
				)
				( pin "U2D1.DE50"
					( objectStatus "vss(1194)" )
				)
				( pin "U2D1.DE52"
					( objectStatus "vss(1195)" )
				)
				( pin "U2D1.DE54"
					( objectStatus "vss(1196)" )
				)
				( pin "U2D1.DE56"
					( objectStatus "vss(1197)" )
				)
				( pin "U2D1.DE58"
					( objectStatus "vss(1198)" )
				)
				( pin "U2D1.DE60"
					( objectStatus "vss(1199)" )
				)
				( pin "U2D1.DE62"
					( objectStatus "vss(1200)" )
				)
				( pin "U2D1.DL8"
					( objectStatus "vss(1201)" )
				)
				( pin "U2D1.DN18"
					( objectStatus "vss(1202)" )
				)
				( pin "U2D1.DP45"
					( objectStatus "vss(1203)" )
				)
				( pin "U2D1.DP47"
					( objectStatus "vss(1204)" )
				)
				( pin "U2D1.DP49"
					( objectStatus "vss(1205)" )
				)
				( pin "U2D1.DP51"
					( objectStatus "vss(1206)" )
				)
				( pin "U2D1.DP53"
					( objectStatus "vss(1207)" )
				)
				( pin "U2D1.DP55"
					( objectStatus "vss(1208)" )
				)
				( pin "U2D1.DP57"
					( objectStatus "vss(1209)" )
				)
				( pin "U2D1.DP59"
					( objectStatus "vss(1210)" )
				)
				( pin "U2D1.DP61"
					( objectStatus "vss(1211)" )
				)
				( pin "U2D1.DP63"
					( objectStatus "vss(1212)" )
				)
				( pin "U2D1.DP9"
					( objectStatus "vss(1213)" )
				)
				( pin "U2D1.DV19"
					( objectStatus "vss(1214)" )
				)
				( pin "U2D1.DY45"
					( objectStatus "vss(1215)" )
				)
				( pin "U2D1.DY47"
					( objectStatus "vss(1216)" )
				)
				( pin "U2D1.DY49"
					( objectStatus "vss(1217)" )
				)
				( pin "U2D1.DY51"
					( objectStatus "vss(1218)" )
				)
				( pin "U2D1.DY53"
					( objectStatus "vss(1219)" )
				)
				( pin "U2D1.DY55"
					( objectStatus "vss(1220)" )
				)
				( pin "U2D1.DY57"
					( objectStatus "vss(1221)" )
				)
				( pin "U2D1.DY59"
					( objectStatus "vss(1222)" )
				)
				( pin "U2D1.DY61"
					( objectStatus "vss(1223)" )
				)
				( pin "U2D1.DY63"
					( objectStatus "vss(1224)" )
				)
				( pin "U2D1.EA14"
					( objectStatus "vss(1225)" )
				)
				( pin "U2D1.L8"
					( objectStatus "vss(1226)" )
				)
				( pin "U2D1.V11"
					( objectStatus "vss(1227)" )
				)
				( pin "U2D1.E66"
					( objectStatus "vss(1228)" )
				)
				( pin "U2D1.ED69"
					( objectStatus "vss(1229)" )
				)
				( pin "U2D1.EE80"
					( objectStatus "vss(1230)" )
				)
				( pin "U2D1.EE8"
					( objectStatus "vss(1231)" )
				)
				( pin "U2D1.EE40"
					( objectStatus "vss(1232)" )
				)
				( pin "U2D1.ED81"
					( objectStatus "vss(1233)" )
				)
				( pin "U2D1.ED7"
					( objectStatus "vss(1234)" )
				)
				( pin "U2D1.ED41"
					( objectStatus "vss(1235)" )
				)
				( pin "U2D1.EC82"
					( objectStatus "vss(1236)" )
				)
				( pin "U2D1.EC6"
					( objectStatus "vss(1237)" )
				)
				( pin "U2D1.EC42"
					( objectStatus "vss(1238)" )
				)
				( pin "U2D1.DW2"
					( objectStatus "vss(1239)" )
				)
				( pin "U2D1.EB83"
					( objectStatus "vss(1240)" )
				)
				( pin "U2D1.EA84"
					( objectStatus "vss(1241)" )
				)
				( pin "U2D1.DY85"
					( objectStatus "vss(1242)" )
				)
				( pin "U2D1.J86"
					( objectStatus "vss(1243)" )
				)
				( pin "U2D1.E82"
					( objectStatus "vss(1244)" )
				)
				( pin "U2D1.D81"
					( objectStatus "vss(1245)" )
				)
				( pin "U2D1.D3"
					( objectStatus "vss(1246)" )
				)
				( pin "U2D1.C80"
					( objectStatus "vss(1247)" )
				)
				( pin "U2D1.C4"
					( objectStatus "vss(1248)" )
				)
				( pin "U2D1.B79"
					( objectStatus "vss(1249)" )
				)
				( pin "U2D1.B5"
					( objectStatus "vss(1250)" )
				)
				( pin "U2D1.B43"
					( objectStatus "vss(1251)" )
				)
				( pin "U2D1.A42"
					( objectStatus "vss(1252)" )
				)
				( pin "U2D1.B9"
					( objectStatus "vss(1253)" )
				)
			)
			( gate "U2D1"
				( objectStatus "@baseboard_fab2_lib.baseboard_fab2(sch_1):page74_i21" )
				( pin "U2D1.AA16"
					( objectStatus "vss(934)" )
				)
				( pin "U2D1.AA4"
					( objectStatus "vss(935)" )
				)
				( pin "U2D1.Y85"
					( objectStatus "vss(936)" )
				)
				( pin "U2D1.Y83"
					( objectStatus "vss(937)" )
				)
				( pin "U2D1.Y81"
					( objectStatus "vss(938)" )
				)
				( pin "U2D1.Y79"
					( objectStatus "vss(939)" )
				)
				( pin "U2D1.Y73"
					( objectStatus "vss(940)" )
				)
				( pin "U2D1.Y71"
					( objectStatus "vss(941)" )
				)
				( pin "U2D1.Y9"
					( objectStatus "vss(942)" )
				)
				( pin "U2D1.Y7"
					( objectStatus "vss(943)" )
				)
				( pin "U2D1.Y67"
					( objectStatus "vss(944)" )
				)
				( pin "U2D1.Y5"
					( objectStatus "vss(945)" )
				)
				( pin "U2D1.Y17"
					( objectStatus "vss(946)" )
				)
				( pin "U2D1.Y15"
					( objectStatus "vss(947)" )
				)
				( pin "U2D1.W82"
					( objectStatus "vss(948)" )
				)
				( pin "U2D1.W78"
					( objectStatus "vss(949)" )
				)
				( pin "U2D1.W74"
					( objectStatus "vss(950)" )
				)
				( pin "U2D1.W68"
					( objectStatus "vss(951)" )
				)
				( pin "U2D1.W42"
					( objectStatus "vss(952)" )
				)
				( pin "U2D1.W40"
					( objectStatus "vss(953)" )
				)
				( pin "U2D1.W38"
					( objectStatus "vss(954)" )
				)
				( pin "U2D1.W36"
					( objectStatus "vss(955)" )
				)
				( pin "U2D1.W34"
					( objectStatus "vss(956)" )
				)
				( pin "U2D1.W32"
					( objectStatus "vss(957)" )
				)
				( pin "U2D1.W30"
					( objectStatus "vss(958)" )
				)
				( pin "U2D1.W28"
					( objectStatus "vss(959)" )
				)
				( pin "U2D1.W26"
					( objectStatus "vss(960)" )
				)
				( pin "U2D1.W24"
					( objectStatus "vss(961)" )
				)
				( pin "U2D1.W22"
					( objectStatus "vss(962)" )
				)
				( pin "U2D1.W12"
					( objectStatus "vss(963)" )
				)
				( pin "U2D1.AC56"
					( objectStatus "vss(964)" )
				)
				( pin "U2D1.W8"
					( objectStatus "vss(965)" )
				)
				( pin "U2D1.V83"
					( objectStatus "vss(966)" )
				)
				( pin "U2D1.V77"
					( objectStatus "vss(967)" )
				)
				( pin "U2D1.V75"
					( objectStatus "vss(968)" )
				)
				( pin "U2D1.V73"
					( objectStatus "vss(969)" )
				)
				( pin "U2D1.V43"
					( objectStatus "vss(970)" )
				)
				( pin "U2D1.V23"
					( objectStatus "vss(971)" )
				)
				( pin "U2D1.V21"
					( objectStatus "vss(972)" )
				)
				( pin "U2D1.V15"
					( objectStatus "vss(973)" )
				)
				( pin "U2D1.V13"
					( objectStatus "vss(974)" )
				)
				( pin "U2D1.V9"
					( objectStatus "vss(975)" )
				)
				( pin "U2D1.V5"
					( objectStatus "vss(976)" )
				)
				( pin "U2D1.V1"
					( objectStatus "vss(977)" )
				)
				( pin "U2D1.U86"
					( objectStatus "vss(978)" )
				)
				( pin "U2D1.U80"
					( objectStatus "vss(979)" )
				)
				( pin "U2D1.U78"
					( objectStatus "vss(980)" )
				)
				( pin "U2D1.U76"
					( objectStatus "vss(981)" )
				)
				( pin "U2D1.U74"
					( objectStatus "vss(982)" )
				)
				( pin "U2D1.U70"
					( objectStatus "vss(983)" )
				)
				( pin "U2D1.U68"
					( objectStatus "vss(984)" )
				)
				( pin "U2D1.U42"
					( objectStatus "vss(985)" )
				)
				( pin "U2D1.U36"
					( objectStatus "vss(986)" )
				)
				( pin "U2D1.U30"
					( objectStatus "vss(987)" )
				)
				( pin "U2D1.U24"
					( objectStatus "vss(988)" )
				)
				( pin "U2D1.U22"
					( objectStatus "vss(989)" )
				)
				( pin "U2D1.U20"
					( objectStatus "vss(990)" )
				)
				( pin "U2D1.U6"
					( objectStatus "vss(991)" )
				)
				( pin "U2D1.U4"
					( objectStatus "vss(992)" )
				)
				( pin "U2D1.U2"
					( objectStatus "vss(993)" )
				)
				( pin "U2D1.T85"
					( objectStatus "vss(994)" )
				)
				( pin "U2D1.T83"
					( objectStatus "vss(995)" )
				)
				( pin "U2D1.T77"
					( objectStatus "vss(996)" )
				)
				( pin "U2D1.T73"
					( objectStatus "vss(997)" )
				)
				( pin "U2D1.T65"
					( objectStatus "vss(998)" )
				)
				( pin "U2D1.T41"
					( objectStatus "vss(999)" )
				)
				( pin "U2D1.T37"
					( objectStatus "vss(1000)" )
				)
				( pin "U2D1.T35"
					( objectStatus "vss(1001)" )
				)
				( pin "U2D1.T31"
					( objectStatus "vss(1002)" )
				)
				( pin "U2D1.T29"
					( objectStatus "vss(1003)" )
				)
				( pin "U2D1.T25"
					( objectStatus "vss(1004)" )
				)
				( pin "U2D1.T17"
					( objectStatus "vss(1005)" )
				)
				( pin "U2D1.T13"
					( objectStatus "vss(1006)" )
				)
				( pin "U2D1.R86"
					( objectStatus "vss(1007)" )
				)
				( pin "U2D1.R78"
					( objectStatus "vss(1008)" )
				)
				( pin "U2D1.R72"
					( objectStatus "vss(1009)" )
				)
				( pin "U2D1.R68"
					( objectStatus "vss(1010)" )
				)
				( pin "U2D1.R40"
					( objectStatus "vss(1011)" )
				)
				( pin "U2D1.R38"
					( objectStatus "vss(1012)" )
				)
				( pin "U2D1.R34"
					( objectStatus "vss(1013)" )
				)
				( pin "U2D1.R32"
					( objectStatus "vss(1014)" )
				)
				( pin "U2D1.R28"
					( objectStatus "vss(1015)" )
				)
				( pin "U2D1.R26"
					( objectStatus "vss(1016)" )
				)
				( pin "U2D1.R22"
					( objectStatus "vss(1017)" )
				)
				( pin "U2D1.R4"
					( objectStatus "vss(1018)" )
				)
				( pin "U2D1.R2"
					( objectStatus "vss(1019)" )
				)
				( pin "U2D1.R18"
					( objectStatus "vss(1020)" )
				)
				( pin "U2D1.R14"
					( objectStatus "vss(1021)" )
				)
				( pin "U2D1.P83"
					( objectStatus "vss(1022)" )
				)
				( pin "U2D1.P81"
					( objectStatus "vss(1023)" )
				)
				( pin "U2D1.P71"
					( objectStatus "vss(1024)" )
				)
				( pin "U2D1.P69"
					( objectStatus "vss(1025)" )
				)
				( pin "U2D1.P67"
					( objectStatus "vss(1026)" )
				)
				( pin "U2D1.P39"
					( objectStatus "vss(1027)" )
				)
				( pin "U2D1.P33"
					( objectStatus "vss(1028)" )
				)
				( pin "U2D1.P27"
					( objectStatus "vss(1029)" )
				)
				( pin "U2D1.P15"
					( objectStatus "vss(1030)" )
				)
				( pin "U2D1.P11"
					( objectStatus "vss(1031)" )
				)
				( pin "U2D1.N8"
					( objectStatus "vss(1032)" )
				)
				( pin "U2D1.N4"
					( objectStatus "vss(1033)" )
				)
				( pin "U2D1.N78"
					( objectStatus "vss(1034)" )
				)
				( pin "U2D1.N76"
					( objectStatus "vss(1035)" )
				)
				( pin "U2D1.N74"
					( objectStatus "vss(1036)" )
				)
				( pin "U2D1.N72"
					( objectStatus "vss(1037)" )
				)
				( pin "U2D1.N70"
					( objectStatus "vss(1038)" )
				)
				( pin "U2D1.N66"
					( objectStatus "vss(1039)" )
				)
				( pin "U2D1.N6"
					( objectStatus "vss(1040)" )
				)
				( pin "U2D1.N22"
					( objectStatus "vss(1041)" )
				)
				( pin "U2D1.N20"
					( objectStatus "vss(1042)" )
				)
				( pin "U2D1.DM19"
					( objectStatus "vss(1043)" )
				)
				( pin "U2D1.M85"
					( objectStatus "vss(1044)" )
				)
				( pin "U2D1.M83"
					( objectStatus "vss(1045)" )
				)
				( pin "U2D1.M79"
					( objectStatus "vss(1046)" )
				)
				( pin "U2D1.M71"
					( objectStatus "vss(1047)" )
				)
				( pin "U2D1.M65"
					( objectStatus "vss(1048)" )
				)
				( pin "U2D1.M43"
					( objectStatus "vss(1049)" )
				)
				( pin "U2D1.M41"
					( objectStatus "vss(1050)" )
				)
				( pin "U2D1.M39"
					( objectStatus "vss(1051)" )
				)
				( pin "U2D1.M37"
					( objectStatus "vss(1052)" )
				)
				( pin "U2D1.M35"
					( objectStatus "vss(1053)" )
				)
				( pin "U2D1.M33"
					( objectStatus "vss(1054)" )
				)
				( pin "U2D1.M31"
					( objectStatus "vss(1055)" )
				)
				( pin "U2D1.M29"
					( objectStatus "vss(1056)" )
				)
				( pin "U2D1.M27"
					( objectStatus "vss(1057)" )
				)
				( pin "U2D1.M25"
					( objectStatus "vss(1058)" )
				)
				( pin "U2D1.M23"
					( objectStatus "vss(1059)" )
				)
				( pin "U2D1.M19"
					( objectStatus "vss(1060)" )
				)
				( pin "U2D1.M17"
					( objectStatus "vss(1061)" )
				)
				( pin "U2D1.M15"
					( objectStatus "vss(1062)" )
				)
				( pin "U2D1.CT7"
					( objectStatus "vss(1063)" )
				)
				( pin "U2D1.BT9"
					( objectStatus "vss(1064)" )
				)
				( pin "U2D1.L82"
					( objectStatus "vss(1065)" )
				)
				( pin "U2D1.L80"
					( objectStatus "vss(1066)" )
				)
				( pin "U2D1.L78"
					( objectStatus "vss(1067)" )
				)
				( pin "U2D1.L72"
					( objectStatus "vss(1068)" )
				)
				( pin "U2D1.L22"
					( objectStatus "vss(1069)" )
				)
				( pin "U2D1.L20"
					( objectStatus "vss(1070)" )
				)
				( pin "U2D1.L6"
					( objectStatus "vss(1071)" )
				)
				( pin "U2D1.L2"
					( objectStatus "vss(1072)" )
				)
				( pin "U2D1.L10"
					( objectStatus "vss(1073)" )
				)
				( pin "U2D1.K85"
					( objectStatus "vss(1074)" )
				)
				( pin "U2D1.K83"
					( objectStatus "vss(1075)" )
				)
				( pin "U2D1.K81"
					( objectStatus "vss(1076)" )
				)
				( pin "U2D1.K77"
					( objectStatus "vss(1077)" )
				)
				( pin "U2D1.K73"
					( objectStatus "vss(1078)" )
				)
				( pin "U2D1.K71"
					( objectStatus "vss(1079)" )
				)
				( pin "U2D1.K69"
					( objectStatus "vss(1080)" )
				)
				( pin "U2D1.K67"
					( objectStatus "vss(1081)" )
				)
				( pin "U2D1.K65"
					( objectStatus "vss(1082)" )
				)
				( pin "U2D1.K39"
					( objectStatus "vss(1083)" )
				)
				( pin "U2D1.K33"
					( objectStatus "vss(1084)" )
				)
				( pin "U2D1.K27"
					( objectStatus "vss(1085)" )
				)
				( pin "U2D1.DB7"
					( objectStatus "vss(1086)" )
				)
				( pin "U2D1.K17"
					( objectStatus "vss(1087)" )
				)
				( pin "U2D1.K13"
					( objectStatus "vss(1088)" )
				)
				( pin "U2D1.K11"
					( objectStatus "vss(1089)" )
				)
				( pin "U2D1.K1"
					( objectStatus "vss(1090)" )
				)
				( pin "U2D1.J84"
					( objectStatus "vss(1091)" )
				)
				( pin "U2D1.J82"
					( objectStatus "vss(1092)" )
				)
				( pin "U2D1.J76"
					( objectStatus "vss(1093)" )
				)
			)
			( gate "U2D1"
				( objectStatus "@baseboard_fab2_lib.baseboard_fab2(sch_1):page74_i22" )
				( pin "U2D1.AL68"
					( objectStatus "vss(774)" )
				)
				( pin "U2D1.AL64"
					( objectStatus "vss(775)" )
				)
				( pin "U2D1.AL56"
					( objectStatus "vss(776)" )
				)
				( pin "U2D1.AL32"
					( objectStatus "vss(777)" )
				)
				( pin "U2D1.AL30"
					( objectStatus "vss(778)" )
				)
				( pin "U2D1.AL24"
					( objectStatus "vss(779)" )
				)
				( pin "U2D1.AL10"
					( objectStatus "vss(780)" )
				)
				( pin "U2D1.AL4"
					( objectStatus "vss(781)" )
				)
				( pin "U2D1.AK85"
					( objectStatus "vss(782)" )
				)
				( pin "U2D1.AK83"
					( objectStatus "vss(783)" )
				)
				( pin "U2D1.AK81"
					( objectStatus "vss(784)" )
				)
				( pin "U2D1.AK79"
					( objectStatus "vss(785)" )
				)
				( pin "U2D1.AK73"
					( objectStatus "vss(786)" )
				)
				( pin "U2D1.AK67"
					( objectStatus "vss(787)" )
				)
				( pin "U2D1.AK65"
					( objectStatus "vss(788)" )
				)
				( pin "U2D1.AK55"
					( objectStatus "vss(789)" )
				)
				( pin "U2D1.AK33"
					( objectStatus "vss(790)" )
				)
				( pin "U2D1.AK31"
					( objectStatus "vss(791)" )
				)
				( pin "U2D1.AK29"
					( objectStatus "vss(792)" )
				)
				( pin "U2D1.AK25"
					( objectStatus "vss(793)" )
				)
				( pin "U2D1.AK23"
					( objectStatus "vss(794)" )
				)
				( pin "U2D1.AK19"
					( objectStatus "vss(795)" )
				)
				( pin "U2D1.AK13"
					( objectStatus "vss(796)" )
				)
				( pin "U2D1.AK9"
					( objectStatus "vss(797)" )
				)
				( pin "U2D1.AJ86"
					( objectStatus "vss(798)" )
				)
				( pin "U2D1.AJ82"
					( objectStatus "vss(799)" )
				)
				( pin "U2D1.AJ78"
					( objectStatus "vss(800)" )
				)
				( pin "U2D1.AJ74"
					( objectStatus "vss(801)" )
				)
				( pin "U2D1.AJ68"
					( objectStatus "vss(802)" )
				)
				( pin "U2D1.AJ66"
					( objectStatus "vss(803)" )
				)
				( pin "U2D1.AJ54"
					( objectStatus "vss(804)" )
				)
				( pin "U2D1.AJ52"
					( objectStatus "vss(805)" )
				)
				( pin "U2D1.AJ50"
					( objectStatus "vss(806)" )
				)
				( pin "U2D1.AJ48"
					( objectStatus "vss(807)" )
				)
				( pin "U2D1.AJ46"
					( objectStatus "vss(808)" )
				)
				( pin "U2D1.AJ34"
					( objectStatus "vss(809)" )
				)
				( pin "U2D1.AJ32"
					( objectStatus "vss(810)" )
				)
				( pin "U2D1.AJ28"
					( objectStatus "vss(811)" )
				)
				( pin "U2D1.AJ26"
					( objectStatus "vss(812)" )
				)
				( pin "U2D1.AJ22"
					( objectStatus "vss(813)" )
				)
				( pin "U2D1.AJ8"
					( objectStatus "vss(814)" )
				)
				( pin "U2D1.AH83"
					( objectStatus "vss(815)" )
				)
				( pin "U2D1.AH77"
					( objectStatus "vss(816)" )
				)
				( pin "U2D1.AH75"
					( objectStatus "vss(817)" )
				)
				( pin "U2D1.AH69"
					( objectStatus "vss(818)" )
				)
				( pin "U2D1.AH65"
					( objectStatus "vss(819)" )
				)
				( pin "U2D1.AH61"
					( objectStatus "vss(820)" )
				)
				( pin "U2D1.AH59"
					( objectStatus "vss(821)" )
				)
				( pin "U2D1.AH53"
					( objectStatus "vss(822)" )
				)
				( pin "U2D1.AH51"
					( objectStatus "vss(823)" )
				)
				( pin "U2D1.AH49"
					( objectStatus "vss(824)" )
				)
				( pin "U2D1.AH47"
					( objectStatus "vss(825)" )
				)
				( pin "U2D1.AH45"
					( objectStatus "vss(826)" )
				)
				( pin "U2D1.AH35"
					( objectStatus "vss(827)" )
				)
				( pin "U2D1.AH33"
					( objectStatus "vss(828)" )
				)
				( pin "U2D1.AH27"
					( objectStatus "vss(829)" )
				)
				( pin "U2D1.AH21"
					( objectStatus "vss(830)" )
				)
				( pin "U2D1.AH5"
					( objectStatus "vss(831)" )
				)
				( pin "U2D1.AH1"
					( objectStatus "vss(832)" )
				)
				( pin "U2D1.AG80"
					( objectStatus "vss(833)" )
				)
				( pin "U2D1.AG78"
					( objectStatus "vss(834)" )
				)
				( pin "U2D1.AG76"
					( objectStatus "vss(835)" )
				)
				( pin "U2D1.AG74"
					( objectStatus "vss(836)" )
				)
				( pin "U2D1.AG70"
					( objectStatus "vss(837)" )
				)
				( pin "U2D1.AG64"
					( objectStatus "vss(838)" )
				)
				( pin "U2D1.AG36"
					( objectStatus "vss(839)" )
				)
				( pin "U2D1.AG18"
					( objectStatus "vss(840)" )
				)
				( pin "U2D1.AG14"
					( objectStatus "vss(841)" )
				)
				( pin "U2D1.AG12"
					( objectStatus "vss(842)" )
				)
				( pin "U2D1.AF85"
					( objectStatus "vss(843)" )
				)
				( pin "U2D1.AF83"
					( objectStatus "vss(844)" )
				)
				( pin "U2D1.AF77"
					( objectStatus "vss(845)" )
				)
				( pin "U2D1.AF73"
					( objectStatus "vss(846)" )
				)
				( pin "U2D1.AF41"
					( objectStatus "vss(847)" )
				)
				( pin "U2D1.AF39"
					( objectStatus "vss(848)" )
				)
				( pin "U2D1.AF37"
					( objectStatus "vss(849)" )
				)
				( pin "U2D1.AF33"
					( objectStatus "vss(850)" )
				)
				( pin "U2D1.AF31"
					( objectStatus "vss(851)" )
				)
				( pin "U2D1.AF29"
					( objectStatus "vss(852)" )
				)
				( pin "U2D1.AF27"
					( objectStatus "vss(853)" )
				)
				( pin "U2D1.AF25"
					( objectStatus "vss(854)" )
				)
				( pin "U2D1.AF23"
					( objectStatus "vss(855)" )
				)
				( pin "U2D1.AF21"
					( objectStatus "vss(856)" )
				)
				( pin "U2D1.AF9"
					( objectStatus "vss(857)" )
				)
				( pin "U2D1.AC52"
					( objectStatus "vss(858)" )
				)
				( pin "U2D1.AF1"
					( objectStatus "vss(859)" )
				)
				( pin "U2D1.AE78"
					( objectStatus "vss(860)" )
				)
				( pin "U2D1.AE70"
					( objectStatus "vss(861)" )
				)
				( pin "U2D1.AE68"
					( objectStatus "vss(862)" )
				)
				( pin "U2D1.AE66"
					( objectStatus "vss(863)" )
				)
				( pin "U2D1.AE64"
					( objectStatus "vss(864)" )
				)
				( pin "U2D1.AE42"
					( objectStatus "vss(865)" )
				)
				( pin "U2D1.AE40"
					( objectStatus "vss(866)" )
				)
				( pin "U2D1.AE38"
					( objectStatus "vss(867)" )
				)
				( pin "U2D1.AE16"
					( objectStatus "vss(868)" )
				)
				( pin "U2D1.AC54"
					( objectStatus "vss(869)" )
				)
				( pin "U2D1.AE8"
					( objectStatus "vss(870)" )
				)
				( pin "U2D1.AE4"
					( objectStatus "vss(871)" )
				)
				( pin "U2D1.AD85"
					( objectStatus "vss(872)" )
				)
				( pin "U2D1.AD83"
					( objectStatus "vss(873)" )
				)
				( pin "U2D1.AD81"
					( objectStatus "vss(874)" )
				)
				( pin "U2D1.AD75"
					( objectStatus "vss(875)" )
				)
				( pin "U2D1.AD73"
					( objectStatus "vss(876)" )
				)
				( pin "U2D1.AD71"
					( objectStatus "vss(877)" )
				)
				( pin "U2D1.AD43"
					( objectStatus "vss(878)" )
				)
				( pin "U2D1.AD39"
					( objectStatus "vss(879)" )
				)
				( pin "U2D1.AD33"
					( objectStatus "vss(880)" )
				)
				( pin "U2D1.AD27"
					( objectStatus "vss(881)" )
				)
				( pin "U2D1.AD21"
					( objectStatus "vss(882)" )
				)
				( pin "U2D1.AD19"
					( objectStatus "vss(883)" )
				)
				( pin "U2D1.AD15"
					( objectStatus "vss(884)" )
				)
				( pin "U2D1.AD13"
					( objectStatus "vss(885)" )
				)
				( pin "U2D1.AD11"
					( objectStatus "vss(886)" )
				)
				( pin "U2D1.AD9"
					( objectStatus "vss(887)" )
				)
				( pin "U2D1.AD7"
					( objectStatus "vss(888)" )
				)
				( pin "U2D1.AD3"
					( objectStatus "vss(889)" )
				)
				( pin "U2D1.AC86"
					( objectStatus "vss(890)" )
				)
				( pin "U2D1.AC84"
					( objectStatus "vss(891)" )
				)
				( pin "U2D1.AC78"
					( objectStatus "vss(892)" )
				)
				( pin "U2D1.AC72"
					( objectStatus "vss(893)" )
				)
				( pin "U2D1.AC70"
					( objectStatus "vss(894)" )
				)
				( pin "U2D1.AC64"
					( objectStatus "vss(895)" )
				)
				( pin "U2D1.AC40"
					( objectStatus "vss(896)" )
				)
				( pin "U2D1.AC38"
					( objectStatus "vss(897)" )
				)
				( pin "U2D1.AC34"
					( objectStatus "vss(898)" )
				)
				( pin "U2D1.AC32"
					( objectStatus "vss(899)" )
				)
				( pin "U2D1.AC28"
					( objectStatus "vss(900)" )
				)
				( pin "U2D1.AC26"
					( objectStatus "vss(901)" )
				)
				( pin "U2D1.AC22"
					( objectStatus "vss(902)" )
				)
				( pin "U2D1.AC18"
					( objectStatus "vss(903)" )
				)
				( pin "U2D1.AB85"
					( objectStatus "vss(904)" )
				)
				( pin "U2D1.AB83"
					( objectStatus "vss(905)" )
				)
				( pin "U2D1.AB79"
					( objectStatus "vss(906)" )
				)
				( pin "U2D1.AB73"
					( objectStatus "vss(907)" )
				)
				( pin "U2D1.AB69"
					( objectStatus "vss(908)" )
				)
				( pin "U2D1.AB65"
					( objectStatus "vss(909)" )
				)
				( pin "U2D1.AB41"
					( objectStatus "vss(910)" )
				)
				( pin "U2D1.AB37"
					( objectStatus "vss(911)" )
				)
				( pin "U2D1.AB35"
					( objectStatus "vss(912)" )
				)
				( pin "U2D1.AB31"
					( objectStatus "vss(913)" )
				)
				( pin "U2D1.AB29"
					( objectStatus "vss(914)" )
				)
				( pin "U2D1.AB25"
					( objectStatus "vss(915)" )
				)
				( pin "U2D1.AB23"
					( objectStatus "vss(916)" )
				)
				( pin "U2D1.AB21"
					( objectStatus "vss(917)" )
				)
				( pin "U2D1.AB11"
					( objectStatus "vss(918)" )
				)
				( pin "U2D1.AB5"
					( objectStatus "vss(919)" )
				)
				( pin "U2D1.AB1"
					( objectStatus "vss(920)" )
				)
				( pin "U2D1.AA82"
					( objectStatus "vss(921)" )
				)
				( pin "U2D1.AA80"
					( objectStatus "vss(922)" )
				)
				( pin "U2D1.AA78"
					( objectStatus "vss(923)" )
				)
				( pin "U2D1.AA76"
					( objectStatus "vss(924)" )
				)
				( pin "U2D1.AA68"
					( objectStatus "vss(925)" )
				)
				( pin "U2D1.AA66"
					( objectStatus "vss(926)" )
				)
				( pin "U2D1.AA64"
					( objectStatus "vss(927)" )
				)
				( pin "U2D1.AA42"
					( objectStatus "vss(928)" )
				)
				( pin "U2D1.AA36"
					( objectStatus "vss(929)" )
				)
				( pin "U2D1.AA30"
					( objectStatus "vss(930)" )
				)
				( pin "U2D1.AA24"
					( objectStatus "vss(931)" )
				)
				( pin "U2D1.AA22"
					( objectStatus "vss(932)" )
				)
				( pin "U2D1.AA18"
					( objectStatus "vss(933)" )
				)
			)
			( gate "U2D1"
				( objectStatus "@baseboard_fab2_lib.baseboard_fab2(sch_1):page74_i23" )
				( pin "U2D1.BG72"
					( objectStatus "vss(614)" )
				)
				( pin "U2D1.BG24"
					( objectStatus "vss(615)" )
				)
				( pin "U2D1.BG22"
					( objectStatus "vss(616)" )
				)
				( pin "U2D1.BG10"
					( objectStatus "vss(617)" )
				)
				( pin "U2D1.BG8"
					( objectStatus "vss(618)" )
				)
				( pin "U2D1.BG6"
					( objectStatus "vss(619)" )
				)
				( pin "U2D1.BF71"
					( objectStatus "vss(620)" )
				)
				( pin "U2D1.BF69"
					( objectStatus "vss(621)" )
				)
				( pin "U2D1.BF67"
					( objectStatus "vss(622)" )
				)
				( pin "U2D1.BF65"
					( objectStatus "vss(623)" )
				)
				( pin "U2D1.BF63"
					( objectStatus "vss(624)" )
				)
				( pin "U2D1.BF25"
					( objectStatus "vss(625)" )
				)
				( pin "U2D1.BF19"
					( objectStatus "vss(626)" )
				)
				( pin "U2D1.BF17"
					( objectStatus "vss(627)" )
				)
				( pin "U2D1.BF15"
					( objectStatus "vss(628)" )
				)
				( pin "U2D1.BF9"
					( objectStatus "vss(629)" )
				)
				( pin "U2D1.BE70"
					( objectStatus "vss(630)" )
				)
				( pin "U2D1.BE68"
					( objectStatus "vss(631)" )
				)
				( pin "U2D1.BE66"
					( objectStatus "vss(632)" )
				)
				( pin "U2D1.BE64"
					( objectStatus "vss(633)" )
				)
				( pin "U2D1.BE26"
					( objectStatus "vss(634)" )
				)
				( pin "U2D1.BE10"
					( objectStatus "vss(635)" )
				)
				( pin "U2D1.BE8"
					( objectStatus "vss(636)" )
				)
				( pin "U2D1.BE6"
					( objectStatus "vss(637)" )
				)
				( pin "U2D1.BE4"
					( objectStatus "vss(638)" )
				)
				( pin "U2D1.BD71"
					( objectStatus "vss(639)" )
				)
				( pin "U2D1.BD63"
					( objectStatus "vss(640)" )
				)
				( pin "U2D1.BD27"
					( objectStatus "vss(641)" )
				)
				( pin "U2D1.BD21"
					( objectStatus "vss(642)" )
				)
				( pin "U2D1.BD15"
					( objectStatus "vss(643)" )
				)
				( pin "U2D1.BD11"
					( objectStatus "vss(644)" )
				)
				( pin "U2D1.BD5"
					( objectStatus "vss(645)" )
				)
				( pin "U2D1.BC82"
					( objectStatus "vss(646)" )
				)
				( pin "U2D1.BC80"
					( objectStatus "vss(647)" )
				)
				( pin "U2D1.BC78"
					( objectStatus "vss(648)" )
				)
				( pin "U2D1.BC76"
					( objectStatus "vss(649)" )
				)
				( pin "U2D1.BC74"
					( objectStatus "vss(650)" )
				)
				( pin "U2D1.BC72"
					( objectStatus "vss(651)" )
				)
				( pin "U2D1.BC70"
					( objectStatus "vss(652)" )
				)
				( pin "U2D1.BC16"
					( objectStatus "vss(653)" )
				)
				( pin "U2D1.BC12"
					( objectStatus "vss(654)" )
				)
				( pin "U2D1.BC8"
					( objectStatus "vss(655)" )
				)
				( pin "U2D1.BC4"
					( objectStatus "vss(656)" )
				)
				( pin "U2D1.BB83"
					( objectStatus "vss(657)" )
				)
				( pin "U2D1.BB81"
					( objectStatus "vss(658)" )
				)
				( pin "U2D1.BB79"
					( objectStatus "vss(659)" )
				)
				( pin "U2D1.BB77"
					( objectStatus "vss(660)" )
				)
				( pin "U2D1.BB75"
					( objectStatus "vss(661)" )
				)
				( pin "U2D1.BB73"
					( objectStatus "vss(662)" )
				)
				( pin "U2D1.BB69"
					( objectStatus "vss(663)" )
				)
				( pin "U2D1.BB63"
					( objectStatus "vss(664)" )
				)
				( pin "U2D1.BB23"
					( objectStatus "vss(665)" )
				)
				( pin "U2D1.BB19"
					( objectStatus "vss(666)" )
				)
				( pin "U2D1.BA84"
					( objectStatus "vss(667)" )
				)
				( pin "U2D1.BA80"
					( objectStatus "vss(668)" )
				)
				( pin "U2D1.BA74"
					( objectStatus "vss(669)" )
				)
				( pin "U2D1.BA68"
					( objectStatus "vss(670)" )
				)
				( pin "U2D1.BA62"
					( objectStatus "vss(671)" )
				)
				( pin "U2D1.BA12"
					( objectStatus "vss(672)" )
				)
				( pin "U2D1.BA6"
					( objectStatus "vss(673)" )
				)
				( pin "U2D1.BA2"
					( objectStatus "vss(674)" )
				)
				( pin "U2D1.AY81"
					( objectStatus "vss(675)" )
				)
				( pin "U2D1.AY79"
					( objectStatus "vss(676)" )
				)
				( pin "U2D1.AY63"
					( objectStatus "vss(677)" )
				)
				( pin "U2D1.AY25"
					( objectStatus "vss(678)" )
				)
				( pin "U2D1.AY23"
					( objectStatus "vss(679)" )
				)
				( pin "U2D1.AY21"
					( objectStatus "vss(680)" )
				)
				( pin "U2D1.AY17"
					( objectStatus "vss(681)" )
				)
				( pin "U2D1.AY15"
					( objectStatus "vss(682)" )
				)
				( pin "U2D1.AY5"
					( objectStatus "vss(683)" )
				)
				( pin "U2D1.AW84"
					( objectStatus "vss(684)" )
				)
				( pin "U2D1.AW82"
					( objectStatus "vss(685)" )
				)
				( pin "U2D1.AW78"
					( objectStatus "vss(686)" )
				)
				( pin "U2D1.AW74"
					( objectStatus "vss(687)" )
				)
				( pin "U2D1.AW72"
					( objectStatus "vss(688)" )
				)
				( pin "U2D1.AW70"
					( objectStatus "vss(689)" )
				)
				( pin "U2D1.AW68"
					( objectStatus "vss(690)" )
				)
				( pin "U2D1.AW66"
					( objectStatus "vss(691)" )
				)
				( pin "U2D1.AW62"
					( objectStatus "vss(692)" )
				)
				( pin "U2D1.AW10"
					( objectStatus "vss(693)" )
				)
				( pin "U2D1.AW2"
					( objectStatus "vss(694)" )
				)
				( pin "U2D1.AV83"
					( objectStatus "vss(695)" )
				)
				( pin "U2D1.AV75"
					( objectStatus "vss(696)" )
				)
				( pin "U2D1.AV67"
					( objectStatus "vss(697)" )
				)
				( pin "U2D1.AV65"
					( objectStatus "vss(698)" )
				)
				( pin "U2D1.AV63"
					( objectStatus "vss(699)" )
				)
				( pin "U2D1.AV25"
					( objectStatus "vss(700)" )
				)
				( pin "U2D1.AV23"
					( objectStatus "vss(701)" )
				)
				( pin "U2D1.AV19"
					( objectStatus "vss(702)" )
				)
				( pin "U2D1.AV13"
					( objectStatus "vss(703)" )
				)
				( pin "U2D1.AV11"
					( objectStatus "vss(704)" )
				)
				( pin "U2D1.AV7"
					( objectStatus "vss(705)" )
				)
				( pin "U2D1.AV3"
					( objectStatus "vss(706)" )
				)
				( pin "U2D1.AV1"
					( objectStatus "vss(707)" )
				)
				( pin "U2D1.AU86"
					( objectStatus "vss(708)" )
				)
				( pin "U2D1.AU84"
					( objectStatus "vss(709)" )
				)
				( pin "U2D1.AU80"
					( objectStatus "vss(710)" )
				)
				( pin "U2D1.AU78"
					( objectStatus "vss(711)" )
				)
				( pin "U2D1.AU76"
					( objectStatus "vss(712)" )
				)
				( pin "U2D1.AU74"
					( objectStatus "vss(713)" )
				)
				( pin "U2D1.AU68"
					( objectStatus "vss(714)" )
				)
				( pin "U2D1.AU64"
					( objectStatus "vss(715)" )
				)
				( pin "U2D1.AU62"
					( objectStatus "vss(716)" )
				)
				( pin "U2D1.AU28"
					( objectStatus "vss(717)" )
				)
				( pin "U2D1.AU26"
					( objectStatus "vss(718)" )
				)
				( pin "U2D1.AU6"
					( objectStatus "vss(719)" )
				)
				( pin "U2D1.AU2"
					( objectStatus "vss(720)" )
				)
				( pin "U2D1.AT85"
					( objectStatus "vss(721)" )
				)
				( pin "U2D1.AT83"
					( objectStatus "vss(722)" )
				)
				( pin "U2D1.AT77"
					( objectStatus "vss(723)" )
				)
				( pin "U2D1.AT73"
					( objectStatus "vss(724)" )
				)
				( pin "U2D1.AT69"
					( objectStatus "vss(725)" )
				)
				( pin "U2D1.AT63"
					( objectStatus "vss(726)" )
				)
				( pin "U2D1.AT61"
					( objectStatus "vss(727)" )
				)
				( pin "U2D1.AT27"
					( objectStatus "vss(728)" )
				)
				( pin "U2D1.AT21"
					( objectStatus "vss(729)" )
				)
				( pin "U2D1.AT17"
					( objectStatus "vss(730)" )
				)
				( pin "U2D1.AT15"
					( objectStatus "vss(731)" )
				)
				( pin "U2D1.P63"
					( objectStatus "vss(732)" )
				)
				( pin "U2D1.AC48"
					( objectStatus "vss(733)" )
				)
				( pin "U2D1.AR78"
					( objectStatus "vss(734)" )
				)
				( pin "U2D1.AR72"
					( objectStatus "vss(735)" )
				)
				( pin "U2D1.AR60"
					( objectStatus "vss(736)" )
				)
				( pin "U2D1.AR30"
					( objectStatus "vss(737)" )
				)
				( pin "U2D1.AR24"
					( objectStatus "vss(738)" )
				)
				( pin "U2D1.AR10"
					( objectStatus "vss(739)" )
				)
				( pin "U2D1.AP85"
					( objectStatus "vss(740)" )
				)
				( pin "U2D1.AP83"
					( objectStatus "vss(741)" )
				)
				( pin "U2D1.AP81"
					( objectStatus "vss(742)" )
				)
				( pin "U2D1.AP75"
					( objectStatus "vss(743)" )
				)
				( pin "U2D1.AP73"
					( objectStatus "vss(744)" )
				)
				( pin "U2D1.AP69"
					( objectStatus "vss(745)" )
				)
				( pin "U2D1.AP67"
					( objectStatus "vss(746)" )
				)
				( pin "U2D1.AP65"
					( objectStatus "vss(747)" )
				)
				( pin "U2D1.AP63"
					( objectStatus "vss(748)" )
				)
				( pin "U2D1.AP59"
					( objectStatus "vss(749)" )
				)
				( pin "U2D1.AP31"
					( objectStatus "vss(750)" )
				)
				( pin "U2D1.AP19"
					( objectStatus "vss(751)" )
				)
				( pin "U2D1.AP13"
					( objectStatus "vss(752)" )
				)
				( pin "U2D1.AP9"
					( objectStatus "vss(753)" )
				)
				( pin "U2D1.AP5"
					( objectStatus "vss(754)" )
				)
				( pin "U2D1.AN78"
					( objectStatus "vss(755)" )
				)
				( pin "U2D1.AN58"
					( objectStatus "vss(756)" )
				)
				( pin "U2D1.AN28"
					( objectStatus "vss(757)" )
				)
				( pin "U2D1.AN6"
					( objectStatus "vss(758)" )
				)
				( pin "U2D1.AN2"
					( objectStatus "vss(759)" )
				)
				( pin "U2D1.AM83"
					( objectStatus "vss(760)" )
				)
				( pin "U2D1.AM79"
					( objectStatus "vss(761)" )
				)
				( pin "U2D1.AM73"
					( objectStatus "vss(762)" )
				)
				( pin "U2D1.AM69"
					( objectStatus "vss(763)" )
				)
				( pin "U2D1.AM63"
					( objectStatus "vss(764)" )
				)
				( pin "U2D1.AM57"
					( objectStatus "vss(765)" )
				)
				( pin "U2D1.AM31"
					( objectStatus "vss(766)" )
				)
				( pin "U2D1.AC50"
					( objectStatus "vss(767)" )
				)
				( pin "U2D1.AM1"
					( objectStatus "vss(768)" )
				)
				( pin "U2D1.AL86"
					( objectStatus "vss(769)" )
				)
				( pin "U2D1.AL82"
					( objectStatus "vss(770)" )
				)
				( pin "U2D1.AL80"
					( objectStatus "vss(771)" )
				)
				( pin "U2D1.AL78"
					( objectStatus "vss(772)" )
				)
				( pin "U2D1.AL76"
					( objectStatus "vss(773)" )
				)
			)
			( gate "U2D1"
				( objectStatus "@baseboard_fab2_lib.baseboard_fab2(sch_1):page75_i17" )
				( pin "U2D1.P49"
					( objectStatus "vss(454)" )
				)
				( pin "U2D1.CJ12"
					( objectStatus "vss(455)" )
				)
				( pin "U2D1.CJ10"
					( objectStatus "vss(456)" )
				)
				( pin "U2D1.CJ8"
					( objectStatus "vss(457)" )
				)
				( pin "U2D1.CJ6"
					( objectStatus "vss(458)" )
				)
				( pin "U2D1.CJ2"
					( objectStatus "vss(459)" )
				)
				( pin "U2D1.CH83"
					( objectStatus "vss(460)" )
				)
				( pin "U2D1.CH81"
					( objectStatus "vss(461)" )
				)
				( pin "U2D1.CH79"
					( objectStatus "vss(462)" )
				)
				( pin "U2D1.CH73"
					( objectStatus "vss(463)" )
				)
				( pin "U2D1.CH67"
					( objectStatus "vss(464)" )
				)
				( pin "U2D1.CH63"
					( objectStatus "vss(465)" )
				)
				( pin "U2D1.CH19"
					( objectStatus "vss(466)" )
				)
				( pin "U2D1.CH15"
					( objectStatus "vss(467)" )
				)
				( pin "U2D1.CH3"
					( objectStatus "vss(468)" )
				)
				( pin "U2D1.CH1"
					( objectStatus "vss(469)" )
				)
				( pin "U2D1.CG80"
					( objectStatus "vss(470)" )
				)
				( pin "U2D1.CG72"
					( objectStatus "vss(471)" )
				)
				( pin "U2D1.CG68"
					( objectStatus "vss(472)" )
				)
				( pin "U2D1.CG62"
					( objectStatus "vss(473)" )
				)
				( pin "U2D1.CG22"
					( objectStatus "vss(474)" )
				)
				( pin "U2D1.CG18"
					( objectStatus "vss(475)" )
				)
				( pin "U2D1.P51"
					( objectStatus "vss(476)" )
				)
				( pin "U2D1.CF83"
					( objectStatus "vss(477)" )
				)
				( pin "U2D1.CF77"
					( objectStatus "vss(478)" )
				)
				( pin "U2D1.CF71"
					( objectStatus "vss(479)" )
				)
				( pin "U2D1.CF69"
					( objectStatus "vss(480)" )
				)
				( pin "U2D1.CF63"
					( objectStatus "vss(481)" )
				)
				( pin "U2D1.CF9"
					( objectStatus "vss(482)" )
				)
				( pin "U2D1.P53"
					( objectStatus "vss(483)" )
				)
				( pin "U2D1.CE82"
					( objectStatus "vss(484)" )
				)
				( pin "U2D1.CE70"
					( objectStatus "vss(485)" )
				)
				( pin "U2D1.CE62"
					( objectStatus "vss(486)" )
				)
				( pin "U2D1.CE26"
					( objectStatus "vss(487)" )
				)
				( pin "U2D1.CE20"
					( objectStatus "vss(488)" )
				)
				( pin "U2D1.CE14"
					( objectStatus "vss(489)" )
				)
				( pin "U2D1.CE10"
					( objectStatus "vss(490)" )
				)
				( pin "U2D1.CD81"
					( objectStatus "vss(491)" )
				)
				( pin "U2D1.CD79"
					( objectStatus "vss(492)" )
				)
				( pin "U2D1.CD77"
					( objectStatus "vss(493)" )
				)
				( pin "U2D1.CD75"
					( objectStatus "vss(494)" )
				)
				( pin "U2D1.CD73"
					( objectStatus "vss(495)" )
				)
				( pin "U2D1.CD63"
					( objectStatus "vss(496)" )
				)
				( pin "U2D1.CD13"
					( objectStatus "vss(497)" )
				)
				( pin "U2D1.CD5"
					( objectStatus "vss(498)" )
				)
				( pin "U2D1.CC82"
					( objectStatus "vss(499)" )
				)
				( pin "U2D1.CC80"
					( objectStatus "vss(500)" )
				)
				( pin "U2D1.CC78"
					( objectStatus "vss(501)" )
				)
				( pin "U2D1.CC76"
					( objectStatus "vss(502)" )
				)
				( pin "U2D1.CC74"
					( objectStatus "vss(503)" )
				)
				( pin "U2D1.CC72"
					( objectStatus "vss(504)" )
				)
				( pin "U2D1.CC64"
					( objectStatus "vss(505)" )
				)
				( pin "U2D1.CC24"
					( objectStatus "vss(506)" )
				)
				( pin "U2D1.CC18"
					( objectStatus "vss(507)" )
				)
				( pin "U2D1.CC16"
					( objectStatus "vss(508)" )
				)
				( pin "U2D1.CC4"
					( objectStatus "vss(509)" )
				)
				( pin "U2D1.CB71"
					( objectStatus "vss(510)" )
				)
				( pin "U2D1.CB63"
					( objectStatus "vss(511)" )
				)
				( pin "U2D1.CB27"
					( objectStatus "vss(512)" )
				)
				( pin "U2D1.CB9"
					( objectStatus "vss(513)" )
				)
				( pin "U2D1.CB7"
					( objectStatus "vss(514)" )
				)
				( pin "U2D1.CA70"
					( objectStatus "vss(515)" )
				)
				( pin "U2D1.CA68"
					( objectStatus "vss(516)" )
				)
				( pin "U2D1.CA66"
					( objectStatus "vss(517)" )
				)
				( pin "U2D1.CA64"
					( objectStatus "vss(518)" )
				)
				( pin "U2D1.CA26"
					( objectStatus "vss(519)" )
				)
				( pin "U2D1.CA18"
					( objectStatus "vss(520)" )
				)
				( pin "U2D1.CA14"
					( objectStatus "vss(521)" )
				)
				( pin "U2D1.CA10"
					( objectStatus "vss(522)" )
				)
				( pin "U2D1.CA8"
					( objectStatus "vss(523)" )
				)
				( pin "U2D1.CA6"
					( objectStatus "vss(524)" )
				)
				( pin "U2D1.CA2"
					( objectStatus "vss(525)" )
				)
				( pin "U2D1.BY71"
					( objectStatus "vss(526)" )
				)
				( pin "U2D1.BY69"
					( objectStatus "vss(527)" )
				)
				( pin "U2D1.BY67"
					( objectStatus "vss(528)" )
				)
				( pin "U2D1.BY65"
					( objectStatus "vss(529)" )
				)
				( pin "U2D1.BY63"
					( objectStatus "vss(530)" )
				)
				( pin "U2D1.BY23"
					( objectStatus "vss(531)" )
				)
				( pin "U2D1.BY13"
					( objectStatus "vss(532)" )
				)
				( pin "U2D1.BY11"
					( objectStatus "vss(533)" )
				)
				( pin "U2D1.BW82"
					( objectStatus "vss(534)" )
				)
				( pin "U2D1.BW80"
					( objectStatus "vss(535)" )
				)
				( pin "U2D1.BW78"
					( objectStatus "vss(536)" )
				)
				( pin "U2D1.BW76"
					( objectStatus "vss(537)" )
				)
				( pin "U2D1.BW74"
					( objectStatus "vss(538)" )
				)
				( pin "U2D1.BW72"
					( objectStatus "vss(539)" )
				)
				( pin "U2D1.BW26"
					( objectStatus "vss(540)" )
				)
				( pin "U2D1.BW18"
					( objectStatus "vss(541)" )
				)
				( pin "U2D1.BW16"
					( objectStatus "vss(542)" )
				)
				( pin "U2D1.BW14"
					( objectStatus "vss(543)" )
				)
				( pin "U2D1.BW12"
					( objectStatus "vss(544)" )
				)
				( pin "U2D1.P55"
					( objectStatus "vss(545)" )
				)
				( pin "U2D1.BW6"
					( objectStatus "vss(546)" )
				)
				( pin "U2D1.BV25"
					( objectStatus "vss(547)" )
				)
				( pin "U2D1.BV17"
					( objectStatus "vss(548)" )
				)
				( pin "U2D1.BU10"
					( objectStatus "vss(549)" )
				)
				( pin "U2D1.BV5"
					( objectStatus "vss(550)" )
				)
				( pin "U2D1.BU8"
					( objectStatus "vss(551)" )
				)
				( pin "U2D1.BT25"
					( objectStatus "vss(552)" )
				)
				( pin "U2D1.BT23"
					( objectStatus "vss(553)" )
				)
				( pin "U2D1.BT21"
					( objectStatus "vss(554)" )
				)
				( pin "U2D1.BT5"
					( objectStatus "vss(555)" )
				)
				( pin "U2D1.BT3"
					( objectStatus "vss(556)" )
				)
				( pin "U2D1.BR82"
					( objectStatus "vss(557)" )
				)
				( pin "U2D1.BR80"
					( objectStatus "vss(558)" )
				)
				( pin "U2D1.BR78"
					( objectStatus "vss(559)" )
				)
				( pin "U2D1.BR76"
					( objectStatus "vss(560)" )
				)
				( pin "U2D1.BR74"
					( objectStatus "vss(561)" )
				)
				( pin "U2D1.BR72"
					( objectStatus "vss(562)" )
				)
				( pin "U2D1.BR70"
					( objectStatus "vss(563)" )
				)
				( pin "U2D1.BR68"
					( objectStatus "vss(564)" )
				)
				( pin "U2D1.BR66"
					( objectStatus "vss(565)" )
				)
				( pin "U2D1.BR64"
					( objectStatus "vss(566)" )
				)
				( pin "U2D1.P57"
					( objectStatus "vss(567)" )
				)
				( pin "U2D1.BR16"
					( objectStatus "vss(568)" )
				)
				( pin "U2D1.BR10"
					( objectStatus "vss(569)" )
				)
				( pin "U2D1.BR6"
					( objectStatus "vss(570)" )
				)
				( pin "U2D1.BP27"
					( objectStatus "vss(571)" )
				)
				( pin "U2D1.BP3"
					( objectStatus "vss(572)" )
				)
				( pin "U2D1.BN26"
					( objectStatus "vss(573)" )
				)
				( pin "U2D1.BN20"
					( objectStatus "vss(574)" )
				)
				( pin "U2D1.BN10"
					( objectStatus "vss(575)" )
				)
				( pin "U2D1.BN6"
					( objectStatus "vss(576)" )
				)
				( pin "U2D1.BM25"
					( objectStatus "vss(577)" )
				)
				( pin "U2D1.P59"
					( objectStatus "vss(578)" )
				)
				( pin "U2D1.BM15"
					( objectStatus "vss(579)" )
				)
				( pin "U2D1.BM13"
					( objectStatus "vss(580)" )
				)
				( pin "U2D1.BM9"
					( objectStatus "vss(581)" )
				)
				( pin "U2D1.BL82"
					( objectStatus "vss(582)" )
				)
				( pin "U2D1.BL80"
					( objectStatus "vss(583)" )
				)
				( pin "U2D1.BL78"
					( objectStatus "vss(584)" )
				)
				( pin "U2D1.BL76"
					( objectStatus "vss(585)" )
				)
				( pin "U2D1.BL74"
					( objectStatus "vss(586)" )
				)
				( pin "U2D1.BL72"
					( objectStatus "vss(587)" )
				)
				( pin "U2D1.BL70"
					( objectStatus "vss(588)" )
				)
				( pin "U2D1.BL68"
					( objectStatus "vss(589)" )
				)
				( pin "U2D1.BL66"
					( objectStatus "vss(590)" )
				)
				( pin "U2D1.BL64"
					( objectStatus "vss(591)" )
				)
				( pin "U2D1.BL24"
					( objectStatus "vss(592)" )
				)
				( pin "U2D1.BL22"
					( objectStatus "vss(593)" )
				)
				( pin "U2D1.P61"
					( objectStatus "vss(594)" )
				)
				( pin "U2D1.BL12"
					( objectStatus "vss(595)" )
				)
				( pin "U2D1.BL10"
					( objectStatus "vss(596)" )
				)
				( pin "U2D1.BL6"
					( objectStatus "vss(597)" )
				)
				( pin "U2D1.BK19"
					( objectStatus "vss(598)" )
				)
				( pin "U2D1.BK11"
					( objectStatus "vss(599)" )
				)
				( pin "U2D1.BK7"
					( objectStatus "vss(600)" )
				)
				( pin "U2D1.BK3"
					( objectStatus "vss(601)" )
				)
				( pin "U2D1.BJ6"
					( objectStatus "vss(602)" )
				)
				( pin "U2D1.BJ4"
					( objectStatus "vss(603)" )
				)
				( pin "U2D1.BH21"
					( objectStatus "vss(604)" )
				)
				( pin "U2D1.BH15"
					( objectStatus "vss(605)" )
				)
				( pin "U2D1.BH11"
					( objectStatus "vss(606)" )
				)
				( pin "U2D1.BH9"
					( objectStatus "vss(607)" )
				)
				( pin "U2D1.BH7"
					( objectStatus "vss(608)" )
				)
				( pin "U2D1.BG82"
					( objectStatus "vss(609)" )
				)
				( pin "U2D1.BG80"
					( objectStatus "vss(610)" )
				)
				( pin "U2D1.BG78"
					( objectStatus "vss(611)" )
				)
				( pin "U2D1.BG76"
					( objectStatus "vss(612)" )
				)
				( pin "U2D1.BG74"
					( objectStatus "vss(613)" )
				)
			)
			( gate "U2D1"
				( objectStatus "@baseboard_fab2_lib.baseboard_fab2(sch_1):page75_i18" )
				( pin "U2D1.DA46"
					( objectStatus "vss(294)" )
				)
				( pin "U2D1.DA44"
					( objectStatus "vss(295)" )
				)
				( pin "U2D1.DA38"
					( objectStatus "vss(296)" )
				)
				( pin "U2D1.DA36"
					( objectStatus "vss(297)" )
				)
				( pin "U2D1.DA34"
					( objectStatus "vss(298)" )
				)
				( pin "U2D1.DA32"
					( objectStatus "vss(299)" )
				)
				( pin "U2D1.DA30"
					( objectStatus "vss(300)" )
				)
				( pin "U2D1.DA28"
					( objectStatus "vss(301)" )
				)
				( pin "U2D1.DA26"
					( objectStatus "vss(302)" )
				)
				( pin "U2D1.DA18"
					( objectStatus "vss(303)" )
				)
				( pin "U2D1.H53"
					( objectStatus "vss(304)" )
				)
				( pin "U2D1.DA6"
					( objectStatus "vss(305)" )
				)
				( pin "U2D1.CY85"
					( objectStatus "vss(306)" )
				)
				( pin "U2D1.CY83"
					( objectStatus "vss(307)" )
				)
				( pin "U2D1.CY77"
					( objectStatus "vss(308)" )
				)
				( pin "U2D1.CY75"
					( objectStatus "vss(309)" )
				)
				( pin "U2D1.CY69"
					( objectStatus "vss(310)" )
				)
				( pin "U2D1.CY65"
					( objectStatus "vss(311)" )
				)
				( pin "U2D1.CY61"
					( objectStatus "vss(312)" )
				)
				( pin "U2D1.CY59"
					( objectStatus "vss(313)" )
				)
				( pin "U2D1.CY51"
					( objectStatus "vss(314)" )
				)
				( pin "U2D1.CY45"
					( objectStatus "vss(315)" )
				)
				( pin "U2D1.CY41"
					( objectStatus "vss(316)" )
				)
				( pin "U2D1.CY21"
					( objectStatus "vss(317)" )
				)
				( pin "U2D1.CY15"
					( objectStatus "vss(318)" )
				)
				( pin "U2D1.CY13"
					( objectStatus "vss(319)" )
				)
				( pin "U2D1.CY9"
					( objectStatus "vss(320)" )
				)
				( pin "U2D1.CY1"
					( objectStatus "vss(321)" )
				)
				( pin "U2D1.CW82"
					( objectStatus "vss(322)" )
				)
				( pin "U2D1.CW78"
					( objectStatus "vss(323)" )
				)
				( pin "U2D1.CW74"
					( objectStatus "vss(324)" )
				)
				( pin "U2D1.CW68"
					( objectStatus "vss(325)" )
				)
				( pin "U2D1.CW66"
					( objectStatus "vss(326)" )
				)
				( pin "U2D1.CW64"
					( objectStatus "vss(327)" )
				)
				( pin "U2D1.CW54"
					( objectStatus "vss(328)" )
				)
				( pin "U2D1.CW52"
					( objectStatus "vss(329)" )
				)
				( pin "U2D1.CW42"
					( objectStatus "vss(330)" )
				)
				( pin "U2D1.CW40"
					( objectStatus "vss(331)" )
				)
				( pin "U2D1.CW38"
					( objectStatus "vss(332)" )
				)
				( pin "U2D1.CW32"
					( objectStatus "vss(333)" )
				)
				( pin "U2D1.CW26"
					( objectStatus "vss(334)" )
				)
				( pin "U2D1.CW12"
					( objectStatus "vss(335)" )
				)
				( pin "U2D1.CV83"
					( objectStatus "vss(336)" )
				)
				( pin "U2D1.CV81"
					( objectStatus "vss(337)" )
				)
				( pin "U2D1.CV79"
					( objectStatus "vss(338)" )
				)
				( pin "U2D1.CV73"
					( objectStatus "vss(339)" )
				)
				( pin "U2D1.CV67"
					( objectStatus "vss(340)" )
				)
				( pin "U2D1.CV63"
					( objectStatus "vss(341)" )
				)
				( pin "U2D1.CV55"
					( objectStatus "vss(342)" )
				)
				( pin "U2D1.CV53"
					( objectStatus "vss(343)" )
				)
				( pin "U2D1.CV41"
					( objectStatus "vss(344)" )
				)
				( pin "U2D1.CV39"
					( objectStatus "vss(345)" )
				)
				( pin "U2D1.CV37"
					( objectStatus "vss(346)" )
				)
				( pin "U2D1.CV33"
					( objectStatus "vss(347)" )
				)
				( pin "U2D1.CV31"
					( objectStatus "vss(348)" )
				)
				( pin "U2D1.CV27"
					( objectStatus "vss(349)" )
				)
				( pin "U2D1.CV25"
					( objectStatus "vss(350)" )
				)
				( pin "U2D1.CV17"
					( objectStatus "vss(351)" )
				)
				( pin "U2D1.H55"
					( objectStatus "vss(352)" )
				)
				( pin "U2D1.CV1"
					( objectStatus "vss(353)" )
				)
				( pin "U2D1.CU86"
					( objectStatus "vss(354)" )
				)
				( pin "U2D1.CU82"
					( objectStatus "vss(355)" )
				)
				( pin "U2D1.CU80"
					( objectStatus "vss(356)" )
				)
				( pin "U2D1.CU78"
					( objectStatus "vss(357)" )
				)
				( pin "U2D1.CU76"
					( objectStatus "vss(358)" )
				)
				( pin "U2D1.CU68"
					( objectStatus "vss(359)" )
				)
				( pin "U2D1.CU62"
					( objectStatus "vss(360)" )
				)
				( pin "U2D1.CU56"
					( objectStatus "vss(361)" )
				)
				( pin "U2D1.CU36"
					( objectStatus "vss(362)" )
				)
				( pin "U2D1.CU34"
					( objectStatus "vss(363)" )
				)
				( pin "U2D1.CU30"
					( objectStatus "vss(364)" )
				)
				( pin "U2D1.CU28"
					( objectStatus "vss(365)" )
				)
				( pin "U2D1.CU22"
					( objectStatus "vss(366)" )
				)
				( pin "U2D1.CU4"
					( objectStatus "vss(367)" )
				)
				( pin "U2D1.CT85"
					( objectStatus "vss(368)" )
				)
				( pin "U2D1.CT83"
					( objectStatus "vss(369)" )
				)
				( pin "U2D1.CT79"
					( objectStatus "vss(370)" )
				)
				( pin "U2D1.CT73"
					( objectStatus "vss(371)" )
				)
				( pin "U2D1.CT57"
					( objectStatus "vss(372)" )
				)
				( pin "U2D1.CT35"
					( objectStatus "vss(373)" )
				)
				( pin "U2D1.CT33"
					( objectStatus "vss(374)" )
				)
				( pin "U2D1.CT29"
					( objectStatus "vss(375)" )
				)
				( pin "U2D1.CT27"
					( objectStatus "vss(376)" )
				)
				( pin "U2D1.CT19"
					( objectStatus "vss(377)" )
				)
				( pin "U2D1.CT13"
					( objectStatus "vss(378)" )
				)
				( pin "U2D1.H57"
					( objectStatus "vss(379)" )
				)
				( pin "U2D1.CR86"
					( objectStatus "vss(380)" )
				)
				( pin "U2D1.CR78"
					( objectStatus "vss(381)" )
				)
				( pin "U2D1.CR68"
					( objectStatus "vss(382)" )
				)
				( pin "U2D1.CR66"
					( objectStatus "vss(383)" )
				)
				( pin "U2D1.CR64"
					( objectStatus "vss(384)" )
				)
				( pin "U2D1.CR62"
					( objectStatus "vss(385)" )
				)
				( pin "U2D1.CR58"
					( objectStatus "vss(386)" )
				)
				( pin "U2D1.CR32"
					( objectStatus "vss(387)" )
				)
				( pin "U2D1.CR24"
					( objectStatus "vss(388)" )
				)
				( pin "U2D1.CR22"
					( objectStatus "vss(389)" )
				)
				( pin "U2D1.CR10"
					( objectStatus "vss(390)" )
				)
				( pin "U2D1.CR6"
					( objectStatus "vss(391)" )
				)
				( pin "U2D1.CP83"
					( objectStatus "vss(392)" )
				)
				( pin "U2D1.CP81"
					( objectStatus "vss(393)" )
				)
				( pin "U2D1.CP75"
					( objectStatus "vss(394)" )
				)
				( pin "U2D1.CP73"
					( objectStatus "vss(395)" )
				)
				( pin "U2D1.CP69"
					( objectStatus "vss(396)" )
				)
				( pin "U2D1.CP59"
					( objectStatus "vss(397)" )
				)
				( pin "U2D1.CP25"
					( objectStatus "vss(398)" )
				)
				( pin "U2D1.H59"
					( objectStatus "vss(399)" )
				)
				( pin "U2D1.CP1"
					( objectStatus "vss(400)" )
				)
				( pin "U2D1.CN78"
					( objectStatus "vss(401)" )
				)
				( pin "U2D1.CN68"
					( objectStatus "vss(402)" )
				)
				( pin "U2D1.CN62"
					( objectStatus "vss(403)" )
				)
				( pin "U2D1.CN60"
					( objectStatus "vss(404)" )
				)
				( pin "U2D1.CN32"
					( objectStatus "vss(405)" )
				)
				( pin "U2D1.CN26"
					( objectStatus "vss(406)" )
				)
				( pin "U2D1.H61"
					( objectStatus "vss(407)" )
				)
				( pin "U2D1.CN12"
					( objectStatus "vss(408)" )
				)
				( pin "U2D1.CN2"
					( objectStatus "vss(409)" )
				)
				( pin "U2D1.CM85"
					( objectStatus "vss(410)" )
				)
				( pin "U2D1.CM83"
					( objectStatus "vss(411)" )
				)
				( pin "U2D1.CM77"
					( objectStatus "vss(412)" )
				)
				( pin "U2D1.CM73"
					( objectStatus "vss(413)" )
				)
				( pin "U2D1.CM67"
					( objectStatus "vss(414)" )
				)
				( pin "U2D1.CM63"
					( objectStatus "vss(415)" )
				)
				( pin "U2D1.CM61"
					( objectStatus "vss(416)" )
				)
				( pin "U2D1.CM31"
					( objectStatus "vss(417)" )
				)
				( pin "U2D1.CM5"
					( objectStatus "vss(418)" )
				)
				( pin "U2D1.CM29"
					( objectStatus "vss(419)" )
				)
				( pin "U2D1.CM19"
					( objectStatus "vss(420)" )
				)
				( pin "U2D1.CL80"
					( objectStatus "vss(421)" )
				)
				( pin "U2D1.CL78"
					( objectStatus "vss(422)" )
				)
				( pin "U2D1.CL76"
					( objectStatus "vss(423)" )
				)
				( pin "U2D1.CL74"
					( objectStatus "vss(424)" )
				)
				( pin "U2D1.CL66"
					( objectStatus "vss(425)" )
				)
				( pin "U2D1.CL64"
					( objectStatus "vss(426)" )
				)
				( pin "U2D1.CL62"
					( objectStatus "vss(427)" )
				)
				( pin "U2D1.H63"
					( objectStatus "vss(428)" )
				)
				( pin "U2D1.P45"
					( objectStatus "vss(429)" )
				)
				( pin "U2D1.CL18"
					( objectStatus "vss(430)" )
				)
				( pin "U2D1.CL14"
					( objectStatus "vss(431)" )
				)
				( pin "U2D1.CL8"
					( objectStatus "vss(432)" )
				)
				( pin "U2D1.CK85"
					( objectStatus "vss(433)" )
				)
				( pin "U2D1.CK83"
					( objectStatus "vss(434)" )
				)
				( pin "U2D1.CK75"
					( objectStatus "vss(435)" )
				)
				( pin "U2D1.CK73"
					( objectStatus "vss(436)" )
				)
				( pin "U2D1.CK71"
					( objectStatus "vss(437)" )
				)
				( pin "U2D1.CK69"
					( objectStatus "vss(438)" )
				)
				( pin "U2D1.CK67"
					( objectStatus "vss(439)" )
				)
				( pin "U2D1.CK65"
					( objectStatus "vss(440)" )
				)
				( pin "U2D1.CK63"
					( objectStatus "vss(441)" )
				)
				( pin "U2D1.CK27"
					( objectStatus "vss(442)" )
				)
				( pin "U2D1.CK21"
					( objectStatus "vss(443)" )
				)
				( pin "U2D1.CK15"
					( objectStatus "vss(444)" )
				)
				( pin "U2D1.CK11"
					( objectStatus "vss(445)" )
				)
				( pin "U2D1.CJ86"
					( objectStatus "vss(446)" )
				)
				( pin "U2D1.CJ84"
					( objectStatus "vss(447)" )
				)
				( pin "U2D1.CJ82"
					( objectStatus "vss(448)" )
				)
				( pin "U2D1.CJ78"
					( objectStatus "vss(449)" )
				)
				( pin "U2D1.CJ76"
					( objectStatus "vss(450)" )
				)
				( pin "U2D1.CJ74"
					( objectStatus "vss(451)" )
				)
				( pin "U2D1.CJ62"
					( objectStatus "vss(452)" )
				)
				( pin "U2D1.P47"
					( objectStatus "vss(453)" )
				)
			)
			( gate "U2D1"
				( objectStatus "@baseboard_fab2_lib.baseboard_fab2(sch_1):page75_i19" )
				( pin "U2D1.DN72"
					( objectStatus "vss(134)" )
				)
				( pin "U2D1.DN68"
					( objectStatus "vss(135)" )
				)
				( pin "U2D1.DN38"
					( objectStatus "vss(136)" )
				)
				( pin "U2D1.DN32"
					( objectStatus "vss(137)" )
				)
				( pin "U2D1.DN26"
					( objectStatus "vss(138)" )
				)
				( pin "U2D1.DN22"
					( objectStatus "vss(139)" )
				)
				( pin "U2D1.DN12"
					( objectStatus "vss(140)" )
				)
				( pin "U2D1.BH17"
					( objectStatus "vss(141)" )
				)
				( pin "U2D1.DN2"
					( objectStatus "vss(142)" )
				)
				( pin "U2D1.DM83"
					( objectStatus "vss(143)" )
				)
				( pin "U2D1.DM77"
					( objectStatus "vss(144)" )
				)
				( pin "U2D1.DM73"
					( objectStatus "vss(145)" )
				)
				( pin "U2D1.DM65"
					( objectStatus "vss(146)" )
				)
				( pin "U2D1.DM39"
					( objectStatus "vss(147)" )
				)
				( pin "U2D1.DM37"
					( objectStatus "vss(148)" )
				)
				( pin "U2D1.DM33"
					( objectStatus "vss(149)" )
				)
				( pin "U2D1.DM31"
					( objectStatus "vss(150)" )
				)
				( pin "U2D1.DM27"
					( objectStatus "vss(151)" )
				)
				( pin "U2D1.DM25"
					( objectStatus "vss(152)" )
				)
				( pin "U2D1.H45"
					( objectStatus "vss(153)" )
				)
				( pin "U2D1.DM15"
					( objectStatus "vss(154)" )
				)
				( pin "U2D1.DL80"
					( objectStatus "vss(155)" )
				)
				( pin "U2D1.DL78"
					( objectStatus "vss(156)" )
				)
				( pin "U2D1.DL76"
					( objectStatus "vss(157)" )
				)
				( pin "U2D1.DL74"
					( objectStatus "vss(158)" )
				)
				( pin "U2D1.DL70"
					( objectStatus "vss(159)" )
				)
				( pin "U2D1.DL68"
					( objectStatus "vss(160)" )
				)
				( pin "U2D1.DL40"
					( objectStatus "vss(161)" )
				)
				( pin "U2D1.DL36"
					( objectStatus "vss(162)" )
				)
				( pin "U2D1.DL34"
					( objectStatus "vss(163)" )
				)
				( pin "U2D1.DL30"
					( objectStatus "vss(164)" )
				)
				( pin "U2D1.DL28"
					( objectStatus "vss(165)" )
				)
				( pin "U2D1.DL24"
					( objectStatus "vss(166)" )
				)
				( pin "U2D1.DL22"
					( objectStatus "vss(167)" )
				)
				( pin "U2D1.DL4"
					( objectStatus "vss(168)" )
				)
				( pin "U2D1.DL18"
					( objectStatus "vss(169)" )
				)
				( pin "U2D1.DL16"
					( objectStatus "vss(170)" )
				)
				( pin "U2D1.DK85"
					( objectStatus "vss(171)" )
				)
				( pin "U2D1.DK83"
					( objectStatus "vss(172)" )
				)
				( pin "U2D1.DK77"
					( objectStatus "vss(173)" )
				)
				( pin "U2D1.DK75"
					( objectStatus "vss(174)" )
				)
				( pin "U2D1.DK73"
					( objectStatus "vss(175)" )
				)
				( pin "U2D1.DK41"
					( objectStatus "vss(176)" )
				)
				( pin "U2D1.DK39"
					( objectStatus "vss(177)" )
				)
				( pin "U2D1.DK35"
					( objectStatus "vss(178)" )
				)
				( pin "U2D1.DK29"
					( objectStatus "vss(179)" )
				)
				( pin "U2D1.DK23"
					( objectStatus "vss(180)" )
				)
				( pin "U2D1.DK7"
					( objectStatus "vss(181)" )
				)
				( pin "U2D1.DJ84"
					( objectStatus "vss(182)" )
				)
				( pin "U2D1.DJ82"
					( objectStatus "vss(183)" )
				)
				( pin "U2D1.DJ78"
					( objectStatus "vss(184)" )
				)
				( pin "U2D1.DJ74"
					( objectStatus "vss(185)" )
				)
				( pin "U2D1.DJ68"
					( objectStatus "vss(186)" )
				)
				( pin "U2D1.DJ42"
					( objectStatus "vss(187)" )
				)
				( pin "U2D1.DJ38"
					( objectStatus "vss(188)" )
				)
				( pin "U2D1.DJ22"
					( objectStatus "vss(189)" )
				)
				( pin "U2D1.H47"
					( objectStatus "vss(190)" )
				)
				( pin "U2D1.DJ10"
					( objectStatus "vss(191)" )
				)
				( pin "U2D1.DJ2"
					( objectStatus "vss(192)" )
				)
				( pin "U2D1.DH83"
					( objectStatus "vss(193)" )
				)
				( pin "U2D1.DH81"
					( objectStatus "vss(194)" )
				)
				( pin "U2D1.DH79"
					( objectStatus "vss(195)" )
				)
				( pin "U2D1.DH73"
					( objectStatus "vss(196)" )
				)
				( pin "U2D1.DH71"
					( objectStatus "vss(197)" )
				)
				( pin "U2D1.DH67"
					( objectStatus "vss(198)" )
				)
				( pin "U2D1.DH41"
					( objectStatus "vss(199)" )
				)
				( pin "U2D1.DH37"
					( objectStatus "vss(200)" )
				)
				( pin "U2D1.DH35"
					( objectStatus "vss(201)" )
				)
				( pin "U2D1.DH33"
					( objectStatus "vss(202)" )
				)
				( pin "U2D1.DH31"
					( objectStatus "vss(203)" )
				)
				( pin "U2D1.DH29"
					( objectStatus "vss(204)" )
				)
				( pin "U2D1.DH27"
					( objectStatus "vss(205)" )
				)
				( pin "U2D1.DH25"
					( objectStatus "vss(206)" )
				)
				( pin "U2D1.DH23"
					( objectStatus "vss(207)" )
				)
				( pin "U2D1.DH15"
					( objectStatus "vss(208)" )
				)
				( pin "U2D1.DH13"
					( objectStatus "vss(209)" )
				)
				( pin "U2D1.DG82"
					( objectStatus "vss(210)" )
				)
				( pin "U2D1.DG80"
					( objectStatus "vss(211)" )
				)
				( pin "U2D1.DG78"
					( objectStatus "vss(212)" )
				)
				( pin "U2D1.DG76"
					( objectStatus "vss(213)" )
				)
				( pin "U2D1.DG68"
					( objectStatus "vss(214)" )
				)
				( pin "U2D1.DG66"
					( objectStatus "vss(215)" )
				)
				( pin "U2D1.DG24"
					( objectStatus "vss(216)" )
				)
				( pin "U2D1.DG16"
					( objectStatus "vss(217)" )
				)
				( pin "U2D1.DG14"
					( objectStatus "vss(218)" )
				)
				( pin "U2D1.H49"
					( objectStatus "vss(219)" )
				)
				( pin "U2D1.DG2"
					( objectStatus "vss(220)" )
				)
				( pin "U2D1.DF85"
					( objectStatus "vss(221)" )
				)
				( pin "U2D1.DF83"
					( objectStatus "vss(222)" )
				)
				( pin "U2D1.DF79"
					( objectStatus "vss(223)" )
				)
				( pin "U2D1.DF73"
					( objectStatus "vss(224)" )
				)
				( pin "U2D1.DF69"
					( objectStatus "vss(225)" )
				)
				( pin "U2D1.DF65"
					( objectStatus "vss(226)" )
				)
				( pin "U2D1.DF41"
					( objectStatus "vss(227)" )
				)
				( pin "U2D1.DF39"
					( objectStatus "vss(228)" )
				)
				( pin "U2D1.DF37"
					( objectStatus "vss(229)" )
				)
				( pin "U2D1.DF35"
					( objectStatus "vss(230)" )
				)
				( pin "U2D1.DF29"
					( objectStatus "vss(231)" )
				)
				( pin "U2D1.DF19"
					( objectStatus "vss(232)" )
				)
				( pin "U2D1.H51"
					( objectStatus "vss(233)" )
				)
				( pin "U2D1.DF7"
					( objectStatus "vss(234)" )
				)
				( pin "U2D1.DF5"
					( objectStatus "vss(235)" )
				)
				( pin "U2D1.DE78"
					( objectStatus "vss(236)" )
				)
				( pin "U2D1.DE72"
					( objectStatus "vss(237)" )
				)
				( pin "U2D1.DE70"
					( objectStatus "vss(238)" )
				)
				( pin "U2D1.DE64"
					( objectStatus "vss(239)" )
				)
				( pin "U2D1.DE36"
					( objectStatus "vss(240)" )
				)
				( pin "U2D1.DE34"
					( objectStatus "vss(241)" )
				)
				( pin "U2D1.DE30"
					( objectStatus "vss(242)" )
				)
				( pin "U2D1.DE28"
					( objectStatus "vss(243)" )
				)
				( pin "U2D1.DE24"
					( objectStatus "vss(244)" )
				)
				( pin "U2D1.DE20"
					( objectStatus "vss(245)" )
				)
				( pin "U2D1.DE18"
					( objectStatus "vss(246)" )
				)
				( pin "U2D1.DE8"
					( objectStatus "vss(247)" )
				)
				( pin "U2D1.DE6"
					( objectStatus "vss(248)" )
				)
				( pin "U2D1.DD83"
					( objectStatus "vss(249)" )
				)
				( pin "U2D1.DD81"
					( objectStatus "vss(250)" )
				)
				( pin "U2D1.DD75"
					( objectStatus "vss(251)" )
				)
				( pin "U2D1.DD73"
					( objectStatus "vss(252)" )
				)
				( pin "U2D1.DD71"
					( objectStatus "vss(253)" )
				)
				( pin "U2D1.DD37"
					( objectStatus "vss(254)" )
				)
				( pin "U2D1.DD33"
					( objectStatus "vss(255)" )
				)
				( pin "U2D1.DD31"
					( objectStatus "vss(256)" )
				)
				( pin "U2D1.DD27"
					( objectStatus "vss(257)" )
				)
				( pin "U2D1.DD23"
					( objectStatus "vss(258)" )
				)
				( pin "U2D1.DD11"
					( objectStatus "vss(259)" )
				)
				( pin "U2D1.DC86"
					( objectStatus "vss(260)" )
				)
				( pin "U2D1.DC84"
					( objectStatus "vss(261)" )
				)
				( pin "U2D1.DC78"
					( objectStatus "vss(262)" )
				)
				( pin "U2D1.DC70"
					( objectStatus "vss(263)" )
				)
				( pin "U2D1.DC68"
					( objectStatus "vss(264)" )
				)
				( pin "U2D1.DC66"
					( objectStatus "vss(265)" )
				)
				( pin "U2D1.DC64"
					( objectStatus "vss(266)" )
				)
				( pin "U2D1.DC42"
					( objectStatus "vss(267)" )
				)
				( pin "U2D1.DC38"
					( objectStatus "vss(268)" )
				)
				( pin "U2D1.DC32"
					( objectStatus "vss(269)" )
				)
				( pin "U2D1.DC26"
					( objectStatus "vss(270)" )
				)
				( pin "U2D1.DC24"
					( objectStatus "vss(271)" )
				)
				( pin "U2D1.DC14"
					( objectStatus "vss(272)" )
				)
				( pin "U2D1.DB85"
					( objectStatus "vss(273)" )
				)
				( pin "U2D1.DB83"
					( objectStatus "vss(274)" )
				)
				( pin "U2D1.DB77"
					( objectStatus "vss(275)" )
				)
				( pin "U2D1.DB73"
					( objectStatus "vss(276)" )
				)
				( pin "U2D1.DB49"
					( objectStatus "vss(277)" )
				)
				( pin "U2D1.DB47"
					( objectStatus "vss(278)" )
				)
				( pin "U2D1.DB41"
					( objectStatus "vss(279)" )
				)
				( pin "U2D1.DB39"
					( objectStatus "vss(280)" )
				)
				( pin "U2D1.DB25"
					( objectStatus "vss(281)" )
				)
				( pin "U2D1.DB23"
					( objectStatus "vss(282)" )
				)
				( pin "U2D1.DB17"
					( objectStatus "vss(283)" )
				)
				( pin "U2D1.DB13"
					( objectStatus "vss(284)" )
				)
				( pin "U2D1.DB3"
					( objectStatus "vss(285)" )
				)
				( pin "U2D1.DA80"
					( objectStatus "vss(286)" )
				)
				( pin "U2D1.DA78"
					( objectStatus "vss(287)" )
				)
				( pin "U2D1.DA76"
					( objectStatus "vss(288)" )
				)
				( pin "U2D1.DA74"
					( objectStatus "vss(289)" )
				)
				( pin "U2D1.DA70"
					( objectStatus "vss(290)" )
				)
				( pin "U2D1.DA64"
					( objectStatus "vss(291)" )
				)
				( pin "U2D1.DA50"
					( objectStatus "vss(292)" )
				)
				( pin "U2D1.DA48"
					( objectStatus "vss(293)" )
				)
			)
			( gate "U2D1"
				( objectStatus "@baseboard_fab2_lib.baseboard_fab2(sch_1):page75_i20" )
				( pin "U2D1.EF79"
					( objectStatus "vss(0)" )
				)
				( pin "U2D1.EF75"
					( objectStatus "vss(1)" )
				)
				( pin "U2D1.EF71"
					( objectStatus "vss(2)" )
				)
				( pin "U2D1.EE78"
					( objectStatus "vss(3)" )
				)
				( pin "U2D1.EE76"
					( objectStatus "vss(4)" )
				)
				( pin "U2D1.EE70"
					( objectStatus "vss(5)" )
				)
				( pin "U2D1.EE36"
					( objectStatus "vss(6)" )
				)
				( pin "U2D1.EE34"
					( objectStatus "vss(7)" )
				)
				( pin "U2D1.EE30"
					( objectStatus "vss(8)" )
				)
				( pin "U2D1.EE28"
					( objectStatus "vss(9)" )
				)
				( pin "U2D1.EE24"
					( objectStatus "vss(10)" )
				)
				( pin "U2D1.ED77"
					( objectStatus "vss(11)" )
				)
				( pin "U2D1.ED35"
					( objectStatus "vss(12)" )
				)
				( pin "U2D1.ED29"
					( objectStatus "vss(13)" )
				)
				( pin "U2D1.ED23"
					( objectStatus "vss(14)" )
				)
				( pin "U2D1.ED15"
					( objectStatus "vss(15)" )
				)
				( pin "U2D1.ED11"
					( objectStatus "vss(16)" )
				)
				( pin "U2D1.EC76"
					( objectStatus "vss(17)" )
				)
				( pin "U2D1.EC74"
					( objectStatus "vss(18)" )
				)
				( pin "U2D1.EC72"
					( objectStatus "vss(19)" )
				)
				( pin "U2D1.EC70"
					( objectStatus "vss(20)" )
				)
				( pin "U2D1.EC10"
					( objectStatus "vss(21)" )
				)
				( pin "U2D1.EB69"
					( objectStatus "vss(22)" )
				)
				( pin "U2D1.EB65"
					( objectStatus "vss(23)" )
				)
				( pin "U2D1.EB41"
					( objectStatus "vss(24)" )
				)
				( pin "U2D1.EB39"
					( objectStatus "vss(25)" )
				)
				( pin "U2D1.EB37"
					( objectStatus "vss(26)" )
				)
				( pin "U2D1.EB35"
					( objectStatus "vss(27)" )
				)
				( pin "U2D1.EB33"
					( objectStatus "vss(28)" )
				)
				( pin "U2D1.EB31"
					( objectStatus "vss(29)" )
				)
				( pin "U2D1.EB29"
					( objectStatus "vss(30)" )
				)
				( pin "U2D1.EB27"
					( objectStatus "vss(31)" )
				)
				( pin "U2D1.EB25"
					( objectStatus "vss(32)" )
				)
				( pin "U2D1.EB23"
					( objectStatus "vss(33)" )
				)
				( pin "U2D1.BR18"
					( objectStatus "vss(34)" )
				)
				( pin "U2D1.EB13"
					( objectStatus "vss(35)" )
				)
				( pin "U2D1.EA82"
					( objectStatus "vss(36)" )
				)
				( pin "U2D1.EA80"
					( objectStatus "vss(37)" )
				)
				( pin "U2D1.EA78"
					( objectStatus "vss(38)" )
				)
				( pin "U2D1.EA76"
					( objectStatus "vss(39)" )
				)
				( pin "U2D1.EA70"
					( objectStatus "vss(40)" )
				)
				( pin "U2D1.EA64"
					( objectStatus "vss(41)" )
				)
				( pin "U2D1.EA42"
					( objectStatus "vss(42)" )
				)
				( pin "U2D1.EA22"
					( objectStatus "vss(43)" )
				)
				( pin "U2D1.EA20"
					( objectStatus "vss(44)" )
				)
				( pin "U2D1.EA16"
					( objectStatus "vss(45)" )
				)
				( pin "U2D1.J16"
					( objectStatus "vss(46)" )
				)
				( pin "U2D1.EA6"
					( objectStatus "vss(47)" )
				)
				( pin "U2D1.DY75"
					( objectStatus "vss(48)" )
				)
				( pin "U2D1.DY71"
					( objectStatus "vss(49)" )
				)
				( pin "U2D1.DY41"
					( objectStatus "vss(50)" )
				)
				( pin "U2D1.DY35"
					( objectStatus "vss(51)" )
				)
				( pin "U2D1.DY29"
					( objectStatus "vss(52)" )
				)
				( pin "U2D1.DY23"
					( objectStatus "vss(53)" )
				)
				( pin "U2D1.DY19"
					( objectStatus "vss(54)" )
				)
				( pin "U2D1.DY5"
					( objectStatus "vss(55)" )
				)
				( pin "U2D1.DW84"
					( objectStatus "vss(56)" )
				)
				( pin "U2D1.DW82"
					( objectStatus "vss(57)" )
				)
				( pin "U2D1.DW8"
					( objectStatus "vss(58)" )
				)
				( pin "U2D1.DW76"
					( objectStatus "vss(59)" )
				)
				( pin "U2D1.DW74"
					( objectStatus "vss(60)" )
				)
				( pin "U2D1.DW72"
					( objectStatus "vss(61)" )
				)
				( pin "U2D1.DW70"
					( objectStatus "vss(62)" )
				)
				( pin "U2D1.DW68"
					( objectStatus "vss(63)" )
				)
				( pin "U2D1.DW66"
					( objectStatus "vss(64)" )
				)
				( pin "U2D1.DW64"
					( objectStatus "vss(65)" )
				)
				( pin "U2D1.DW40"
					( objectStatus "vss(66)" )
				)
				( pin "U2D1.DW36"
					( objectStatus "vss(67)" )
				)
				( pin "U2D1.DW34"
					( objectStatus "vss(68)" )
				)
				( pin "U2D1.DW30"
					( objectStatus "vss(69)" )
				)
				( pin "U2D1.DW28"
					( objectStatus "vss(70)" )
				)
				( pin "U2D1.DW24"
					( objectStatus "vss(71)" )
				)
				( pin "U2D1.DW20"
					( objectStatus "vss(72)" )
				)
				( pin "U2D1.DW12"
					( objectStatus "vss(73)" )
				)
				( pin "U2D1.DV81"
					( objectStatus "vss(74)" )
				)
				( pin "U2D1.DV77"
					( objectStatus "vss(75)" )
				)
				( pin "U2D1.DV73"
					( objectStatus "vss(76)" )
				)
				( pin "U2D1.DV39"
					( objectStatus "vss(77)" )
				)
				( pin "U2D1.DV37"
					( objectStatus "vss(78)" )
				)
				( pin "U2D1.DV33"
					( objectStatus "vss(79)" )
				)
				( pin "U2D1.DV31"
					( objectStatus "vss(80)" )
				)
				( pin "U2D1.DV27"
					( objectStatus "vss(81)" )
				)
				( pin "U2D1.DV25"
					( objectStatus "vss(82)" )
				)
				( pin "U2D1.DV21"
					( objectStatus "vss(83)" )
				)
				( pin "U2D1.DU84"
					( objectStatus "vss(84)" )
				)
				( pin "U2D1.DU82"
					( objectStatus "vss(85)" )
				)
				( pin "U2D1.DU80"
					( objectStatus "vss(86)" )
				)
				( pin "U2D1.DU78"
					( objectStatus "vss(87)" )
				)
				( pin "U2D1.DU72"
					( objectStatus "vss(88)" )
				)
				( pin "U2D1.DU70"
					( objectStatus "vss(89)" )
				)
				( pin "U2D1.DU38"
					( objectStatus "vss(90)" )
				)
				( pin "U2D1.DU32"
					( objectStatus "vss(91)" )
				)
				( pin "U2D1.DU26"
					( objectStatus "vss(92)" )
				)
				( pin "U2D1.DU22"
					( objectStatus "vss(93)" )
				)
				( pin "U2D1.CN14"
					( objectStatus "vss(94)" )
				)
				( pin "U2D1.DU14"
					( objectStatus "vss(95)" )
				)
				( pin "U2D1.DU10"
					( objectStatus "vss(96)" )
				)
				( pin "U2D1.DT85"
					( objectStatus "vss(97)" )
				)
				( pin "U2D1.DT83"
					( objectStatus "vss(98)" )
				)
				( pin "U2D1.DT79"
					( objectStatus "vss(99)" )
				)
				( pin "U2D1.DT69"
					( objectStatus "vss(100)" )
				)
				( pin "U2D1.DT65"
					( objectStatus "vss(101)" )
				)
				( pin "U2D1.DH21"
					( objectStatus "vss(102)" )
				)
				( pin "U2D1.DT17"
					( objectStatus "vss(103)" )
				)
				( pin "U2D1.DT3"
					( objectStatus "vss(104)" )
				)
				( pin "U2D1.DR78"
					( objectStatus "vss(105)" )
				)
				( pin "U2D1.DR76"
					( objectStatus "vss(106)" )
				)
				( pin "U2D1.DR74"
					( objectStatus "vss(107)" )
				)
				( pin "U2D1.DR72"
					( objectStatus "vss(108)" )
				)
				( pin "U2D1.DR70"
					( objectStatus "vss(109)" )
				)
				( pin "U2D1.DR68"
					( objectStatus "vss(110)" )
				)
				( pin "U2D1.DR66"
					( objectStatus "vss(111)" )
				)
				( pin "U2D1.DR42"
					( objectStatus "vss(112)" )
				)
				( pin "U2D1.DR40"
					( objectStatus "vss(113)" )
				)
				( pin "U2D1.DR38"
					( objectStatus "vss(114)" )
				)
				( pin "U2D1.DR36"
					( objectStatus "vss(115)" )
				)
				( pin "U2D1.DR34"
					( objectStatus "vss(116)" )
				)
				( pin "U2D1.DR32"
					( objectStatus "vss(117)" )
				)
				( pin "U2D1.DR30"
					( objectStatus "vss(118)" )
				)
				( pin "U2D1.DR28"
					( objectStatus "vss(119)" )
				)
				( pin "U2D1.DR26"
					( objectStatus "vss(120)" )
				)
				( pin "U2D1.DR24"
					( objectStatus "vss(121)" )
				)
				( pin "U2D1.DR22"
					( objectStatus "vss(122)" )
				)
				( pin "U2D1.DR20"
					( objectStatus "vss(123)" )
				)
				( pin "U2D1.CL22"
					( objectStatus "vss(124)" )
				)
				( pin "U2D1.CA20"
					( objectStatus "vss(125)" )
				)
				( pin "U2D1.DR6"
					( objectStatus "vss(126)" )
				)
				( pin "U2D1.BR26"
					( objectStatus "vss(127)" )
				)
				( pin "U2D1.DP83"
					( objectStatus "vss(128)" )
				)
				( pin "U2D1.DP81"
					( objectStatus "vss(129)" )
				)
				( pin "U2D1.DP71"
					( objectStatus "vss(130)" )
				)
				( pin "U2D1.DP69"
					( objectStatus "vss(131)" )
				)
				( pin "U2D1.DP67"
					( objectStatus "vss(132)" )
				)
				( pin "U2D1.DN78"
					( objectStatus "vss(133)" )
				)
			)
			( gate "C3D21"
				( objectStatus "@baseboard_fab2_lib.baseboard_fab2(sch_1):page76_i1" )
				( pin "C3D21.1"
					( objectStatus "a" )
				)
				( pin "C3D21.2"
					( objectStatus "b" )
				)
			)
			( gate "C3D5"
				( objectStatus "@baseboard_fab2_lib.baseboard_fab2(sch_1):page76_i3" )
				( pin "C3D5.1"
					( objectStatus "a" )
				)
				( pin "C3D5.2"
					( objectStatus "b" )
				)
			)
			( gate "C3D12"
				( objectStatus "@baseboard_fab2_lib.baseboard_fab2(sch_1):page76_i4" )
				( pin "C3D12.1"
					( objectStatus "a" )
				)
				( pin "C3D12.2"
					( objectStatus "b" )
				)
			)
			( gate "C3D4"
				( objectStatus "@baseboard_fab2_lib.baseboard_fab2(sch_1):page76_i5" )
				( pin "C3D4.1"
					( objectStatus "a" )
				)
				( pin "C3D4.2"
					( objectStatus "b" )
				)
			)
			( gate "C3D11"
				( objectStatus "@baseboard_fab2_lib.baseboard_fab2(sch_1):page76_i7" )
				( pin "C3D11.1"
					( objectStatus "a" )
				)
				( pin "C3D11.2"
					( objectStatus "b" )
				)
			)
			( gate "C3D13"
				( objectStatus "@baseboard_fab2_lib.baseboard_fab2(sch_1):page76_i8" )
				( pin "C3D13.1"
					( objectStatus "a" )
				)
				( pin "C3D13.2"
					( objectStatus "b" )
				)
			)
			( gate "C2D40"
				( objectStatus "@baseboard_fab2_lib.baseboard_fab2(sch_1):page76_i10" )
				( pin "C2D40.1"
					( objectStatus "a" )
				)
				( pin "C2D40.2"
					( objectStatus "b" )
				)
			)
			( gate "C3D9"
				( objectStatus "@baseboard_fab2_lib.baseboard_fab2(sch_1):page76_i15" )
				( pin "C3D9.1"
					( objectStatus "a" )
				)
				( pin "C3D9.2"
					( objectStatus "b" )
				)
			)
			( gate "C3D8"
				( objectStatus "@baseboard_fab2_lib.baseboard_fab2(sch_1):page76_i18" )
				( pin "C3D8.1"
					( objectStatus "a" )
				)
				( pin "C3D8.2"
					( objectStatus "b" )
				)
			)
			( gate "C7P6"
				( objectStatus "@baseboard_fab2_lib.baseboard_fab2(sch_1):page76_i23" )
				( pin "C7P6.1"
					( objectStatus "a" )
				)
				( pin "C7P6.2"
					( objectStatus "b" )
				)
			)
			( gate "C7P13"
				( objectStatus "@baseboard_fab2_lib.baseboard_fab2(sch_1):page76_i25" )
				( pin "C7P13.1"
					( objectStatus "a" )
				)
				( pin "C7P13.2"
					( objectStatus "b" )
				)
			)
			( gate "C7P10"
				( objectStatus "@baseboard_fab2_lib.baseboard_fab2(sch_1):page76_i26" )
				( pin "C7P10.1"
					( objectStatus "a" )
				)
				( pin "C7P10.2"
					( objectStatus "b" )
				)
			)
			( gate "C7P7"
				( objectStatus "@baseboard_fab2_lib.baseboard_fab2(sch_1):page76_i27" )
				( pin "C7P7.1"
					( objectStatus "a" )
				)
				( pin "C7P7.2"
					( objectStatus "b" )
				)
			)
			( gate "C8P22"
				( objectStatus "@baseboard_fab2_lib.baseboard_fab2(sch_1):page76_i28" )
				( pin "C8P22.1"
					( objectStatus "a" )
				)
				( pin "C8P22.2"
					( objectStatus "b" )
				)
			)
			( gate "C7P17"
				( objectStatus "@baseboard_fab2_lib.baseboard_fab2(sch_1):page76_i29" )
				( pin "C7P17.1"
					( objectStatus "a" )
				)
				( pin "C7P17.2"
					( objectStatus "b" )
				)
			)
			( gate "C2D8"
				( objectStatus "@baseboard_fab2_lib.baseboard_fab2(sch_1):page76_i33" )
				( pin "C2D8.1"
					( objectStatus "a" )
				)
				( pin "C2D8.2"
					( objectStatus "b" )
				)
			)
			( gate "C2D10"
				( objectStatus "@baseboard_fab2_lib.baseboard_fab2(sch_1):page76_i37" )
				( pin "C2D10.1"
					( objectStatus "a" )
				)
				( pin "C2D10.2"
					( objectStatus "b" )
				)
			)
			( gate "C2D11"
				( objectStatus "@baseboard_fab2_lib.baseboard_fab2(sch_1):page76_i42" )
				( pin "C2D11.1"
					( objectStatus "a" )
				)
				( pin "C2D11.2"
					( objectStatus "b" )
				)
			)
			( gate "C2D9"
				( objectStatus "@baseboard_fab2_lib.baseboard_fab2(sch_1):page76_i43" )
				( pin "C2D9.1"
					( objectStatus "a" )
				)
				( pin "C2D9.2"
					( objectStatus "b" )
				)
			)
			( gate "C7P15"
				( objectStatus "@baseboard_fab2_lib.baseboard_fab2(sch_1):page76_i45" )
				( pin "C7P15.1"
					( objectStatus "a" )
				)
				( pin "C7P15.2"
					( objectStatus "b" )
				)
			)
			( gate "C8P23"
				( objectStatus "@baseboard_fab2_lib.baseboard_fab2(sch_1):page76_i48" )
				( pin "C8P23.1"
					( objectStatus "a" )
				)
				( pin "C8P23.2"
					( objectStatus "b" )
				)
			)
			( gate "C7P14"
				( objectStatus "@baseboard_fab2_lib.baseboard_fab2(sch_1):page76_i49" )
				( pin "C7P14.1"
					( objectStatus "a" )
				)
				( pin "C7P14.2"
					( objectStatus "b" )
				)
			)
			( gate "C8P7"
				( objectStatus "@baseboard_fab2_lib.baseboard_fab2(sch_1):page76_i50" )
				( pin "C8P7.1"
					( objectStatus "a" )
				)
				( pin "C8P7.2"
					( objectStatus "b" )
				)
			)
			( gate "C7P18"
				( objectStatus "@baseboard_fab2_lib.baseboard_fab2(sch_1):page76_i51" )
				( pin "C7P18.1"
					( objectStatus "a" )
				)
				( pin "C7P18.2"
					( objectStatus "b" )
				)
			)
			( gate "C7P3"
				( objectStatus "@baseboard_fab2_lib.baseboard_fab2(sch_1):page76_i52" )
				( pin "C7P3.1"
					( objectStatus "a" )
				)
				( pin "C7P3.2"
					( objectStatus "b" )
				)
			)
			( gate "C8P6"
				( objectStatus "@baseboard_fab2_lib.baseboard_fab2(sch_1):page76_i55" )
				( pin "C8P6.1"
					( objectStatus "a" )
				)
				( pin "C8P6.2"
					( objectStatus "b" )
				)
			)
			( gate "C8P5"
				( objectStatus "@baseboard_fab2_lib.baseboard_fab2(sch_1):page76_i58" )
				( pin "C8P5.1"
					( objectStatus "a" )
				)
				( pin "C8P5.2"
					( objectStatus "b" )
				)
			)
			( gate "C2D12"
				( objectStatus "@baseboard_fab2_lib.baseboard_fab2(sch_1):page76_i59" )
				( pin "C2D12.1"
					( objectStatus "a" )
				)
				( pin "C2D12.2"
					( objectStatus "b" )
				)
			)
			( gate "C2D22"
				( objectStatus "@baseboard_fab2_lib.baseboard_fab2(sch_1):page76_i61" )
				( pin "C2D22.1"
					( objectStatus "a" )
				)
				( pin "C2D22.2"
					( objectStatus "b" )
				)
			)
			( gate "C2D31"
				( objectStatus "@baseboard_fab2_lib.baseboard_fab2(sch_1):page76_i63" )
				( pin "C2D31.1"
					( objectStatus "a" )
				)
				( pin "C2D31.2"
					( objectStatus "b" )
				)
			)
			( gate "C2D21"
				( objectStatus "@baseboard_fab2_lib.baseboard_fab2(sch_1):page76_i65" )
				( pin "C2D21.1"
					( objectStatus "a" )
				)
				( pin "C2D21.2"
					( objectStatus "b" )
				)
			)
			( gate "C2D27"
				( objectStatus "@baseboard_fab2_lib.baseboard_fab2(sch_1):page76_i66" )
				( pin "C2D27.1"
					( objectStatus "a" )
				)
				( pin "C2D27.2"
					( objectStatus "b" )
				)
			)
			( gate "C3D2"
				( objectStatus "@baseboard_fab2_lib.baseboard_fab2(sch_1):page76_i69" )
				( pin "C3D2.1"
					( objectStatus "a" )
				)
				( pin "C3D2.2"
					( objectStatus "b" )
				)
			)
			( gate "C2D36"
				( objectStatus "@baseboard_fab2_lib.baseboard_fab2(sch_1):page76_i70" )
				( pin "C2D36.1"
					( objectStatus "a" )
				)
				( pin "C2D36.2"
					( objectStatus "b" )
				)
			)
			( gate "C2D13"
				( objectStatus "@baseboard_fab2_lib.baseboard_fab2(sch_1):page76_i73" )
				( pin "C2D13.1"
					( objectStatus "a" )
				)
				( pin "C2D13.2"
					( objectStatus "b" )
				)
			)
			( gate "C2D19"
				( objectStatus "@baseboard_fab2_lib.baseboard_fab2(sch_1):page76_i75" )
				( pin "C2D19.1"
					( objectStatus "a" )
				)
				( pin "C2D19.2"
					( objectStatus "b" )
				)
			)
			( gate "C2D14"
				( objectStatus "@baseboard_fab2_lib.baseboard_fab2(sch_1):page76_i76" )
				( pin "C2D14.1"
					( objectStatus "a" )
				)
				( pin "C2D14.2"
					( objectStatus "b" )
				)
			)
			( gate "C2D20"
				( objectStatus "@baseboard_fab2_lib.baseboard_fab2(sch_1):page76_i79" )
				( pin "C2D20.1"
					( objectStatus "a" )
				)
				( pin "C2D20.2"
					( objectStatus "b" )
				)
			)
			( gate "C2D24"
				( objectStatus "@baseboard_fab2_lib.baseboard_fab2(sch_1):page76_i80" )
				( pin "C2D24.1"
					( objectStatus "a" )
				)
				( pin "C2D24.2"
					( objectStatus "b" )
				)
			)
			( gate "C2D25"
				( objectStatus "@baseboard_fab2_lib.baseboard_fab2(sch_1):page76_i82" )
				( pin "C2D25.1"
					( objectStatus "a" )
				)
				( pin "C2D25.2"
					( objectStatus "b" )
				)
			)
			( gate "C2D30"
				( objectStatus "@baseboard_fab2_lib.baseboard_fab2(sch_1):page76_i83" )
				( pin "C2D30.1"
					( objectStatus "a" )
				)
				( pin "C2D30.2"
					( objectStatus "b" )
				)
			)
			( gate "C2D33"
				( objectStatus "@baseboard_fab2_lib.baseboard_fab2(sch_1):page76_i85" )
				( pin "C2D33.1"
					( objectStatus "a" )
				)
				( pin "C2D33.2"
					( objectStatus "b" )
				)
			)
			( gate "C8P4"
				( objectStatus "@baseboard_fab2_lib.baseboard_fab2(sch_1):page76_i88" )
				( pin "C8P4.1"
					( objectStatus "a" )
				)
				( pin "C8P4.2"
					( objectStatus "b" )
				)
			)
			( gate "C8P20"
				( objectStatus "@baseboard_fab2_lib.baseboard_fab2(sch_1):page76_i89" )
				( pin "C8P20.1"
					( objectStatus "a" )
				)
				( pin "C8P20.2"
					( objectStatus "b" )
				)
			)
			( gate "C2D32"
				( objectStatus "@baseboard_fab2_lib.baseboard_fab2(sch_1):page76_i90" )
				( pin "C2D32.1"
					( objectStatus "a" )
				)
				( pin "C2D32.2"
					( objectStatus "b" )
				)
			)
			( gate "C8P18"
				( objectStatus "@baseboard_fab2_lib.baseboard_fab2(sch_1):page76_i92" )
				( pin "C8P18.1"
					( objectStatus "a" )
				)
				( pin "C8P18.2"
					( objectStatus "b" )
				)
			)
			( gate "C7P2"
				( objectStatus "@baseboard_fab2_lib.baseboard_fab2(sch_1):page76_i100" )
				( pin "C7P2.1"
					( objectStatus "a" )
				)
				( pin "C7P2.2"
					( objectStatus "b" )
				)
			)
			( gate "C8P3"
				( objectStatus "@baseboard_fab2_lib.baseboard_fab2(sch_1):page76_i101" )
				( pin "C8P3.1"
					( objectStatus "a" )
				)
				( pin "C8P3.2"
					( objectStatus "b" )
				)
			)
			( gate "C8P19"
				( objectStatus "@baseboard_fab2_lib.baseboard_fab2(sch_1):page76_i103" )
				( pin "C8P19.1"
					( objectStatus "a" )
				)
				( pin "C8P19.2"
					( objectStatus "b" )
				)
			)
			( gate "C7P1"
				( objectStatus "@baseboard_fab2_lib.baseboard_fab2(sch_1):page76_i105" )
				( pin "C7P1.1"
					( objectStatus "a" )
				)
				( pin "C7P1.2"
					( objectStatus "b" )
				)
			)
			( gate "C8P34"
				( objectStatus "@baseboard_fab2_lib.baseboard_fab2(sch_1):page76_i106" )
				( pin "C8P34.1"
					( objectStatus "a" )
				)
				( pin "C8P34.2"
					( objectStatus "b" )
				)
			)
			( gate "C8P12"
				( objectStatus "@baseboard_fab2_lib.baseboard_fab2(sch_1):page76_i107" )
				( pin "C8P12.1"
					( objectStatus "a" )
				)
				( pin "C8P12.2"
					( objectStatus "b" )
				)
			)
			( gate "C2D26"
				( objectStatus "@baseboard_fab2_lib.baseboard_fab2(sch_1):page76_i108" )
				( pin "C2D26.1"
					( objectStatus "a" )
				)
				( pin "C2D26.2"
					( objectStatus "b" )
				)
			)
			( gate "C3D1"
				( objectStatus "@baseboard_fab2_lib.baseboard_fab2(sch_1):page76_i111" )
				( pin "C3D1.1"
					( objectStatus "a" )
				)
				( pin "C3D1.2"
					( objectStatus "b" )
				)
			)
			( gate "C2D23"
				( objectStatus "@baseboard_fab2_lib.baseboard_fab2(sch_1):page76_i112" )
				( pin "C2D23.1"
					( objectStatus "a" )
				)
				( pin "C2D23.2"
					( objectStatus "b" )
				)
			)
			( gate "C2D17"
				( objectStatus "@baseboard_fab2_lib.baseboard_fab2(sch_1):page76_i114" )
				( pin "C2D17.1"
					( objectStatus "a" )
				)
				( pin "C2D17.2"
					( objectStatus "b" )
				)
			)
			( gate "C2D1"
				( objectStatus "@baseboard_fab2_lib.baseboard_fab2(sch_1):page76_i116" )
				( pin "C2D1.1"
					( objectStatus "a" )
				)
				( pin "C2D1.2"
					( objectStatus "b" )
				)
			)
			( gate "C8P26"
				( objectStatus "@baseboard_fab2_lib.baseboard_fab2(sch_1):page76_i118" )
				( pin "C8P26.1"
					( objectStatus "a" )
				)
				( pin "C8P26.2"
					( objectStatus "b" )
				)
			)
			( gate "C2D37"
				( objectStatus "@baseboard_fab2_lib.baseboard_fab2(sch_1):page76_i119" )
				( pin "C2D37.1"
					( objectStatus "a" )
				)
				( pin "C2D37.2"
					( objectStatus "b" )
				)
			)
			( gate "C2D34"
				( objectStatus "@baseboard_fab2_lib.baseboard_fab2(sch_1):page76_i122" )
				( pin "C2D34.1"
					( objectStatus "a" )
				)
				( pin "C2D34.2"
					( objectStatus "b" )
				)
			)
			( gate "C2D45"
				( objectStatus "@baseboard_fab2_lib.baseboard_fab2(sch_1):page76_i123" )
				( pin "C2D45.1"
					( objectStatus "a" )
				)
				( pin "C2D45.2"
					( objectStatus "b" )
				)
			)
			( gate "C2D16"
				( objectStatus "@baseboard_fab2_lib.baseboard_fab2(sch_1):page76_i124" )
				( pin "C2D16.1"
					( objectStatus "a" )
				)
				( pin "C2D16.2"
					( objectStatus "b" )
				)
			)
			( gate "C8P29"
				( objectStatus "@baseboard_fab2_lib.baseboard_fab2(sch_1):page76_i125" )
				( pin "C8P29.1"
					( objectStatus "a" )
				)
				( pin "C8P29.2"
					( objectStatus "b" )
				)
			)
			( gate "C8P10"
				( objectStatus "@baseboard_fab2_lib.baseboard_fab2(sch_1):page76_i127" )
				( pin "C8P10.1"
					( objectStatus "a" )
				)
				( pin "C8P10.2"
					( objectStatus "b" )
				)
			)
			( gate "C8P16"
				( objectStatus "@baseboard_fab2_lib.baseboard_fab2(sch_1):page76_i129" )
				( pin "C8P16.1"
					( objectStatus "a" )
				)
				( pin "C8P16.2"
					( objectStatus "b" )
				)
			)
			( gate "C8P33"
				( objectStatus "@baseboard_fab2_lib.baseboard_fab2(sch_1):page76_i131" )
				( pin "C8P33.1"
					( objectStatus "a" )
				)
				( pin "C8P33.2"
					( objectStatus "b" )
				)
			)
			( gate "C8P13"
				( objectStatus "@baseboard_fab2_lib.baseboard_fab2(sch_1):page76_i132" )
				( pin "C8P13.1"
					( objectStatus "a" )
				)
				( pin "C8P13.2"
					( objectStatus "b" )
				)
			)
			( gate "C8P17"
				( objectStatus "@baseboard_fab2_lib.baseboard_fab2(sch_1):page76_i133" )
				( pin "C8P17.1"
					( objectStatus "a" )
				)
				( pin "C8P17.2"
					( objectStatus "b" )
				)
			)
			( gate "C8P21"
				( objectStatus "@baseboard_fab2_lib.baseboard_fab2(sch_1):page76_i135" )
				( pin "C8P21.1"
					( objectStatus "a" )
				)
				( pin "C8P21.2"
					( objectStatus "b" )
				)
			)
			( gate "C8P25"
				( objectStatus "@baseboard_fab2_lib.baseboard_fab2(sch_1):page76_i136" )
				( pin "C8P25.1"
					( objectStatus "a" )
				)
				( pin "C8P25.2"
					( objectStatus "b" )
				)
			)
			( gate "C8P28"
				( objectStatus "@baseboard_fab2_lib.baseboard_fab2(sch_1):page76_i137" )
				( pin "C8P28.1"
					( objectStatus "a" )
				)
				( pin "C8P28.2"
					( objectStatus "b" )
				)
			)
			( gate "C8P11"
				( objectStatus "@baseboard_fab2_lib.baseboard_fab2(sch_1):page76_i139" )
				( pin "C8P11.1"
					( objectStatus "a" )
				)
				( pin "C8P11.2"
					( objectStatus "b" )
				)
			)
			( gate "C8P27"
				( objectStatus "@baseboard_fab2_lib.baseboard_fab2(sch_1):page76_i141" )
				( pin "C8P27.1"
					( objectStatus "a" )
				)
				( pin "C8P27.2"
					( objectStatus "b" )
				)
			)
			( gate "C2D15"
				( objectStatus "@baseboard_fab2_lib.baseboard_fab2(sch_1):page76_i159" )
				( pin "C2D15.1"
					( objectStatus "a" )
				)
				( pin "C2D15.2"
					( objectStatus "b" )
				)
			)
			( gate "C2D38"
				( objectStatus "@baseboard_fab2_lib.baseboard_fab2(sch_1):page76_i160" )
				( pin "C2D38.1"
					( objectStatus "a" )
				)
				( pin "C2D38.2"
					( objectStatus "b" )
				)
			)
			( gate "C2D35"
				( objectStatus "@baseboard_fab2_lib.baseboard_fab2(sch_1):page76_i161" )
				( pin "C2D35.1"
					( objectStatus "a" )
				)
				( pin "C2D35.2"
					( objectStatus "b" )
				)
			)
			( gate "C3D7"
				( objectStatus "@baseboard_fab2_lib.baseboard_fab2(sch_1):page76_i164" )
				( pin "C3D7.1"
					( objectStatus "a" )
				)
				( pin "C3D7.2"
					( objectStatus "b" )
				)
			)
			( gate "C2D39"
				( objectStatus "@baseboard_fab2_lib.baseboard_fab2(sch_1):page76_i165" )
				( pin "C2D39.1"
					( objectStatus "a" )
				)
				( pin "C2D39.2"
					( objectStatus "b" )
				)
			)
			( gate "C3D17"
				( objectStatus "@baseboard_fab2_lib.baseboard_fab2(sch_1):page76_i166" )
				( pin "C3D17.1"
					( objectStatus "a" )
				)
				( pin "C3D17.2"
					( objectStatus "b" )
				)
			)
			( gate "C3D18"
				( objectStatus "@baseboard_fab2_lib.baseboard_fab2(sch_1):page76_i169" )
				( pin "C3D18.1"
					( objectStatus "a" )
				)
				( pin "C3D18.2"
					( objectStatus "b" )
				)
			)
			( gate "C3D6"
				( objectStatus "@baseboard_fab2_lib.baseboard_fab2(sch_1):page76_i170" )
				( pin "C3D6.1"
					( objectStatus "a" )
				)
				( pin "C3D6.2"
					( objectStatus "b" )
				)
			)
			( gate "C3D14"
				( objectStatus "@baseboard_fab2_lib.baseboard_fab2(sch_1):page76_i171" )
				( pin "C3D14.1"
					( objectStatus "a" )
				)
				( pin "C3D14.2"
					( objectStatus "b" )
				)
			)
			( gate "C3D23"
				( objectStatus "@baseboard_fab2_lib.baseboard_fab2(sch_1):page76_i172" )
				( pin "C3D23.1"
					( objectStatus "a" )
				)
				( pin "C3D23.2"
					( objectStatus "b" )
				)
			)
			( gate "C3D15"
				( objectStatus "@baseboard_fab2_lib.baseboard_fab2(sch_1):page76_i174" )
				( pin "C3D15.1"
					( objectStatus "a" )
				)
				( pin "C3D15.2"
					( objectStatus "b" )
				)
			)
			( gate "C3D24"
				( objectStatus "@baseboard_fab2_lib.baseboard_fab2(sch_1):page76_i175" )
				( pin "C3D24.1"
					( objectStatus "a" )
				)
				( pin "C3D24.2"
					( objectStatus "b" )
				)
			)
			( gate "C3D16"
				( objectStatus "@baseboard_fab2_lib.baseboard_fab2(sch_1):page76_i176" )
				( pin "C3D16.1"
					( objectStatus "a" )
				)
				( pin "C3D16.2"
					( objectStatus "b" )
				)
			)
			( gate "C7P12"
				( objectStatus "@baseboard_fab2_lib.baseboard_fab2(sch_1):page76_i179" )
				( pin "C7P12.1"
					( objectStatus "a" )
				)
				( pin "C7P12.2"
					( objectStatus "b" )
				)
			)
			( gate "C7P9"
				( objectStatus "@baseboard_fab2_lib.baseboard_fab2(sch_1):page76_i181" )
				( pin "C7P9.1"
					( objectStatus "a" )
				)
				( pin "C7P9.2"
					( objectStatus "b" )
				)
			)
			( gate "C7P5"
				( objectStatus "@baseboard_fab2_lib.baseboard_fab2(sch_1):page76_i182" )
				( pin "C7P5.1"
					( objectStatus "a" )
				)
				( pin "C7P5.2"
					( objectStatus "b" )
				)
			)
			( gate "C7P11"
				( objectStatus "@baseboard_fab2_lib.baseboard_fab2(sch_1):page76_i183" )
				( pin "C7P11.1"
					( objectStatus "a" )
				)
				( pin "C7P11.2"
					( objectStatus "b" )
				)
			)
			( gate "C7P8"
				( objectStatus "@baseboard_fab2_lib.baseboard_fab2(sch_1):page76_i184" )
				( pin "C7P8.1"
					( objectStatus "a" )
				)
				( pin "C7P8.2"
					( objectStatus "b" )
				)
			)
			( gate "C7P4"
				( objectStatus "@baseboard_fab2_lib.baseboard_fab2(sch_1):page76_i195" )
				( pin "C7P4.1"
					( objectStatus "a" )
				)
				( pin "C7P4.2"
					( objectStatus "b" )
				)
			)
			( gate "C3D10"
				( objectStatus "@baseboard_fab2_lib.baseboard_fab2(sch_1):page76_i196" )
				( pin "C3D10.1"
					( objectStatus "a" )
				)
				( pin "C3D10.2"
					( objectStatus "b" )
				)
			)
			( gate "C2D18"
				( objectStatus "@baseboard_fab2_lib.baseboard_fab2(sch_1):page76_i197" )
				( pin "C2D18.1"
					( objectStatus "a" )
				)
				( pin "C2D18.2"
					( objectStatus "b" )
				)
			)
			( gate "C2D28"
				( objectStatus "@baseboard_fab2_lib.baseboard_fab2(sch_1):page76_i198" )
				( pin "C2D28.1"
					( objectStatus "a" )
				)
				( pin "C2D28.2"
					( objectStatus "b" )
				)
			)
			( gate "C2D29"
				( objectStatus "@baseboard_fab2_lib.baseboard_fab2(sch_1):page76_i199" )
				( pin "C2D29.1"
					( objectStatus "a" )
				)
				( pin "C2D29.2"
					( objectStatus "b" )
				)
			)
			( gate "C2D2"
				( objectStatus "@baseboard_fab2_lib.baseboard_fab2(sch_1):page76_i201" )
				( pin "C2D2.1"
					( objectStatus "a" )
				)
				( pin "C2D2.2"
					( objectStatus "b" )
				)
			)
			( gate "C2D3"
				( objectStatus "@baseboard_fab2_lib.baseboard_fab2(sch_1):page76_i202" )
				( pin "C2D3.1"
					( objectStatus "a" )
				)
				( pin "C2D3.2"
					( objectStatus "b" )
				)
			)
			( gate "C2D47"
				( objectStatus "@baseboard_fab2_lib.baseboard_fab2(sch_1):page76_i203" )
				( pin "C2D47.1"
					( objectStatus "a" )
				)
				( pin "C2D47.2"
					( objectStatus "b" )
				)
			)
			( gate "C2D46"
				( objectStatus "@baseboard_fab2_lib.baseboard_fab2(sch_1):page76_i204" )
				( pin "C2D46.1"
					( objectStatus "a" )
				)
				( pin "C2D46.2"
					( objectStatus "b" )
				)
			)
			( gate "C3D25"
				( objectStatus "@baseboard_fab2_lib.baseboard_fab2(sch_1):page76_i205" )
				( pin "C3D25.1"
					( objectStatus "a" )
				)
				( pin "C3D25.2"
					( objectStatus "b" )
				)
			)
			( gate "C7P16"
				( objectStatus "@baseboard_fab2_lib.baseboard_fab2(sch_1):page76_i206" )
				( pin "C7P16.1"
					( objectStatus "a" )
				)
				( pin "C7P16.2"
					( objectStatus "b" )
				)
			)
			( gate "C3D20"
				( objectStatus "@baseboard_fab2_lib.baseboard_fab2(sch_1):page76_i207" )
				( pin "C3D20.1"
					( objectStatus "a" )
				)
				( pin "C3D20.2"
					( objectStatus "b" )
				)
			)
			( gate "C3D19"
				( objectStatus "@baseboard_fab2_lib.baseboard_fab2(sch_1):page76_i208" )
				( pin "C3D19.1"
					( objectStatus "a" )
				)
				( pin "C3D19.2"
					( objectStatus "b" )
				)
			)
			( gate "C8P14"
				( objectStatus "@baseboard_fab2_lib.baseboard_fab2(sch_1):page76_i211" )
				( pin "C8P14.1"
					( objectStatus "a" )
				)
				( pin "C8P14.2"
					( objectStatus "b" )
				)
			)
			( gate "C8P15"
				( objectStatus "@baseboard_fab2_lib.baseboard_fab2(sch_1):page76_i212" )
				( pin "C8P15.1"
					( objectStatus "a" )
				)
				( pin "C8P15.2"
					( objectStatus "b" )
				)
			)
			( gate "C8P8"
				( objectStatus "@baseboard_fab2_lib.baseboard_fab2(sch_1):page76_i213" )
				( pin "C8P8.1"
					( objectStatus "a" )
				)
				( pin "C8P8.2"
					( objectStatus "b" )
				)
			)
			( gate "C8P9"
				( objectStatus "@baseboard_fab2_lib.baseboard_fab2(sch_1):page76_i214" )
				( pin "C8P9.1"
					( objectStatus "a" )
				)
				( pin "C8P9.2"
					( objectStatus "b" )
				)
			)
			( gate "C7P19"
				( objectStatus "@baseboard_fab2_lib.baseboard_fab2(sch_1):page76_i215" )
				( pin "C7P19.1"
					( objectStatus "a" )
				)
				( pin "C7P19.2"
					( objectStatus "b" )
				)
			)
			( gate "C8P32"
				( objectStatus "@baseboard_fab2_lib.baseboard_fab2(sch_1):page76_i216" )
				( pin "C8P32.1"
					( objectStatus "a" )
				)
				( pin "C8P32.2"
					( objectStatus "b" )
				)
			)
			( gate "C8P24"
				( objectStatus "@baseboard_fab2_lib.baseboard_fab2(sch_1):page76_i217" )
				( pin "C8P24.1"
					( objectStatus "a" )
				)
				( pin "C8P24.2"
					( objectStatus "b" )
				)
			)
			( gate "C7P20"
				( objectStatus "@baseboard_fab2_lib.baseboard_fab2(sch_1):page76_i218" )
				( pin "C7P20.1"
					( objectStatus "a" )
				)
				( pin "C7P20.2"
					( objectStatus "b" )
				)
			)
			( gate "J1G1"
				( objectStatus "@baseboard_fab2_lib.baseboard_fab2(sch_1):page77_i43" )
				( pin "J1G1.283"
					( objectStatus "vss(0)" )
				)
				( pin "J1G1.281"
					( objectStatus "vss(1)" )
				)
				( pin "J1G1.279"
					( objectStatus "vss(2)" )
				)
				( pin "J1G1.276"
					( objectStatus "vss(3)" )
				)
				( pin "J1G1.274"
					( objectStatus "vss(4)" )
				)
				( pin "J1G1.272"
					( objectStatus "vss(5)" )
				)
				( pin "J1G1.270"
					( objectStatus "vss(6)" )
				)
				( pin "J1G1.268"
					( objectStatus "vss(7)" )
				)
				( pin "J1G1.265"
					( objectStatus "vss(8)" )
				)
				( pin "J1G1.263"
					( objectStatus "vss(9)" )
				)
				( pin "J1G1.261"
					( objectStatus "vss(10)" )
				)
				( pin "J1G1.259"
					( objectStatus "vss(11)" )
				)
				( pin "J1G1.257"
					( objectStatus "vss(12)" )
				)
				( pin "J1G1.254"
					( objectStatus "vss(13)" )
				)
				( pin "J1G1.252"
					( objectStatus "vss(14)" )
				)
				( pin "J1G1.250"
					( objectStatus "vss(15)" )
				)
				( pin "J1G1.248"
					( objectStatus "vss(16)" )
				)
				( pin "J1G1.246"
					( objectStatus "vss(17)" )
				)
				( pin "J1G1.243"
					( objectStatus "vss(18)" )
				)
				( pin "J1G1.241"
					( objectStatus "vss(19)" )
				)
				( pin "J1G1.239"
					( objectStatus "vss(20)" )
				)
				( pin "J1G1.202"
					( objectStatus "vss(21)" )
				)
				( pin "J1G1.200"
					( objectStatus "vss(22)" )
				)
				( pin "J1G1.198"
					( objectStatus "vss(23)" )
				)
				( pin "J1G1.195"
					( objectStatus "vss(24)" )
				)
				( pin "J1G1.193"
					( objectStatus "vss(25)" )
				)
				( pin "J1G1.191"
					( objectStatus "vss(26)" )
				)
				( pin "J1G1.189"
					( objectStatus "vss(27)" )
				)
				( pin "J1G1.187"
					( objectStatus "vss(28)" )
				)
				( pin "J1G1.184"
					( objectStatus "vss(29)" )
				)
				( pin "J1G1.182"
					( objectStatus "vss(30)" )
				)
				( pin "J1G1.180"
					( objectStatus "vss(31)" )
				)
				( pin "J1G1.178"
					( objectStatus "vss(32)" )
				)
				( pin "J1G1.176"
					( objectStatus "vss(33)" )
				)
				( pin "J1G1.173"
					( objectStatus "vss(34)" )
				)
				( pin "J1G1.171"
					( objectStatus "vss(35)" )
				)
				( pin "J1G1.169"
					( objectStatus "vss(36)" )
				)
				( pin "J1G1.167"
					( objectStatus "vss(37)" )
				)
				( pin "J1G1.165"
					( objectStatus "vss(38)" )
				)
				( pin "J1G1.162"
					( objectStatus "vss(39)" )
				)
				( pin "J1G1.160"
					( objectStatus "vss(40)" )
				)
				( pin "J1G1.158"
					( objectStatus "vss(41)" )
				)
				( pin "J1G1.156"
					( objectStatus "vss(42)" )
				)
				( pin "J1G1.154"
					( objectStatus "vss(43)" )
				)
				( pin "J1G1.151"
					( objectStatus "vss(44)" )
				)
				( pin "J1G1.149"
					( objectStatus "vss(45)" )
				)
				( pin "J1G1.147"
					( objectStatus "vss(46)" )
				)
				( pin "J1G1.138"
					( objectStatus "vss(47)" )
				)
				( pin "J1G1.136"
					( objectStatus "vss(48)" )
				)
				( pin "J1G1.134"
					( objectStatus "vss(49)" )
				)
				( pin "J1G1.131"
					( objectStatus "vss(50)" )
				)
				( pin "J1G1.129"
					( objectStatus "vss(51)" )
				)
				( pin "J1G1.127"
					( objectStatus "vss(52)" )
				)
				( pin "J1G1.125"
					( objectStatus "vss(53)" )
				)
				( pin "J1G1.123"
					( objectStatus "vss(54)" )
				)
				( pin "J1G1.120"
					( objectStatus "vss(55)" )
				)
				( pin "J1G1.118"
					( objectStatus "vss(56)" )
				)
				( pin "J1G1.116"
					( objectStatus "vss(57)" )
				)
				( pin "J1G1.114"
					( objectStatus "vss(58)" )
				)
				( pin "J1G1.112"
					( objectStatus "vss(59)" )
				)
				( pin "J1G1.109"
					( objectStatus "vss(60)" )
				)
				( pin "J1G1.107"
					( objectStatus "vss(61)" )
				)
				( pin "J1G1.105"
					( objectStatus "vss(62)" )
				)
				( pin "J1G1.103"
					( objectStatus "vss(63)" )
				)
				( pin "J1G1.101"
					( objectStatus "vss(64)" )
				)
				( pin "J1G1.98"
					( objectStatus "vss(65)" )
				)
				( pin "J1G1.96"
					( objectStatus "vss(66)" )
				)
				( pin "J1G1.94"
					( objectStatus "vss(67)" )
				)
				( pin "J1G1.57"
					( objectStatus "vss(68)" )
				)
				( pin "J1G1.55"
					( objectStatus "vss(69)" )
				)
				( pin "J1G1.53"
					( objectStatus "vss(70)" )
				)
				( pin "J1G1.50"
					( objectStatus "vss(71)" )
				)
				( pin "J1G1.48"
					( objectStatus "vss(72)" )
				)
				( pin "J1G1.46"
					( objectStatus "vss(73)" )
				)
				( pin "J1G1.44"
					( objectStatus "vss(74)" )
				)
				( pin "J1G1.42"
					( objectStatus "vss(75)" )
				)
				( pin "J1G1.39"
					( objectStatus "vss(76)" )
				)
				( pin "J1G1.37"
					( objectStatus "vss(77)" )
				)
				( pin "J1G1.35"
					( objectStatus "vss(78)" )
				)
				( pin "J1G1.33"
					( objectStatus "vss(79)" )
				)
				( pin "J1G1.31"
					( objectStatus "vss(80)" )
				)
				( pin "J1G1.28"
					( objectStatus "vss(81)" )
				)
				( pin "J1G1.26"
					( objectStatus "vss(82)" )
				)
				( pin "J1G1.24"
					( objectStatus "vss(83)" )
				)
				( pin "J1G1.22"
					( objectStatus "vss(84)" )
				)
				( pin "J1G1.20"
					( objectStatus "vss(85)" )
				)
				( pin "J1G1.17"
					( objectStatus "vss(86)" )
				)
				( pin "J1G1.15"
					( objectStatus "vss(87)" )
				)
				( pin "J1G1.13"
					( objectStatus "vss(88)" )
				)
				( pin "J1G1.11"
					( objectStatus "vss(89)" )
				)
				( pin "J1G1.9"
					( objectStatus "vss(90)" )
				)
				( pin "J1G1.6"
					( objectStatus "vss(91)" )
				)
				( pin "J1G1.4"
					( objectStatus "vss(92)" )
				)
				( pin "J1G1.2"
					( objectStatus "vss(93)" )
				)
			)
			( gate "J1G1"
				( objectStatus "@baseboard_fab2_lib.baseboard_fab2(sch_1):page77_i66" )
				( pin "J1G1.152"
					( objectStatus "dqs0n" )
				)
				( pin "J1G1.153"
					( objectStatus "dqs0p" )
				)
				( pin "J1G1.163"
					( objectStatus "dqs1n" )
				)
				( pin "J1G1.164"
					( objectStatus "dqs1p" )
				)
				( pin "J1G1.174"
					( objectStatus "dqs2n" )
				)
				( pin "J1G1.175"
					( objectStatus "dqs2p" )
				)
				( pin "J1G1.185"
					( objectStatus "dqs3n" )
				)
				( pin "J1G1.186"
					( objectStatus "dqs3p" )
				)
				( pin "J1G1.244"
					( objectStatus "dqs4n" )
				)
				( pin "J1G1.245"
					( objectStatus "dqs4p" )
				)
				( pin "J1G1.255"
					( objectStatus "dqs5n" )
				)
				( pin "J1G1.256"
					( objectStatus "dqs5p" )
				)
				( pin "J1G1.266"
					( objectStatus "dqs6n" )
				)
				( pin "J1G1.267"
					( objectStatus "dqs6p" )
				)
				( pin "J1G1.277"
					( objectStatus "dqs7n" )
				)
				( pin "J1G1.278"
					( objectStatus "dqs7p" )
				)
				( pin "J1G1.196"
					( objectStatus "dqs8n" )
				)
				( pin "J1G1.197"
					( objectStatus "dqs8p" )
				)
				( pin "J1G1.8"
					( objectStatus "dqs9n" )
				)
				( pin "J1G1.7"
					( objectStatus "dqs9p" )
				)
				( pin "J1G1.19"
					( objectStatus "dqs10n" )
				)
				( pin "J1G1.18"
					( objectStatus "dqs10p" )
				)
				( pin "J1G1.30"
					( objectStatus "dqs11n" )
				)
				( pin "J1G1.29"
					( objectStatus "dqs11p" )
				)
				( pin "J1G1.41"
					( objectStatus "dqs12n" )
				)
				( pin "J1G1.40"
					( objectStatus "dqs12p" )
				)
				( pin "J1G1.100"
					( objectStatus "dqs13n" )
				)
				( pin "J1G1.99"
					( objectStatus "dqs13p" )
				)
				( pin "J1G1.111"
					( objectStatus "dqs14n" )
				)
				( pin "J1G1.110"
					( objectStatus "dqs14p" )
				)
				( pin "J1G1.122"
					( objectStatus "dqs15n" )
				)
				( pin "J1G1.121"
					( objectStatus "dqs15p" )
				)
				( pin "J1G1.133"
					( objectStatus "dqs16n" )
				)
				( pin "J1G1.132"
					( objectStatus "dqs16p" )
				)
				( pin "J1G1.52"
					( objectStatus "dqs17n" )
				)
				( pin "J1G1.51"
					( objectStatus "dqs17p" )
				)
			)
			( gate "J1G1"
				( objectStatus "@baseboard_fab2_lib.baseboard_fab2(sch_1):page77_i111" )
				( pin "J1G1.79"
					( objectStatus "a0" )
				)
				( pin "J1G1.72"
					( objectStatus "a1" )
				)
				( pin "J1G1.216"
					( objectStatus "a2" )
				)
				( pin "J1G1.71"
					( objectStatus "a3" )
				)
				( pin "J1G1.214"
					( objectStatus "a4" )
				)
				( pin "J1G1.213"
					( objectStatus "a5" )
				)
				( pin "J1G1.69"
					( objectStatus "a6" )
				)
				( pin "J1G1.211"
					( objectStatus "a7" )
				)
				( pin "J1G1.68"
					( objectStatus "a8" )
				)
				( pin "J1G1.66"
					( objectStatus "a9" )
				)
				( pin "J1G1.225"
					( objectStatus "a10" )
				)
				( pin "J1G1.210"
					( objectStatus "a11" )
				)
				( pin "J1G1.65"
					( objectStatus "a12" )
				)
				( pin "J1G1.232"
					( objectStatus "a13" )
				)
				( pin "J1G1.228"
					( objectStatus "a14_we_n" )
				)
				( pin "J1G1.86"
					( objectStatus "a15_cas_n" )
				)
				( pin "J1G1.82"
					( objectStatus "a16_ras_n" )
				)
				( pin "J1G1.234"
					( objectStatus "a17" )
				)
				( pin "J1G1.62"
					( objectStatus "act_n" )
				)
				( pin "J1G1.208"
					( objectStatus "alert_n" )
				)
				( pin "J1G1.81"
					( objectStatus "ba(0)" )
				)
				( pin "J1G1.224"
					( objectStatus "ba(1)" )
				)
				( pin "J1G1.63"
					( objectStatus "bg(0)" )
				)
				( pin "J1G1.207"
					( objectStatus "bg(1)" )
				)
				( pin "J1G1.235"
					( objectStatus "c(2)" )
				)
				( pin "J1G1.49"
					( objectStatus "cb(0)" )
				)
				( pin "J1G1.194"
					( objectStatus "cb(1)" )
				)
				( pin "J1G1.56"
					( objectStatus "cb(2)" )
				)
				( pin "J1G1.201"
					( objectStatus "cb(3)" )
				)
				( pin "J1G1.47"
					( objectStatus "cb(4)" )
				)
				( pin "J1G1.192"
					( objectStatus "cb(5)" )
				)
				( pin "J1G1.54"
					( objectStatus "cb(6)" )
				)
				( pin "J1G1.199"
					( objectStatus "cb(7)" )
				)
				( pin "J1G1.75"
					( objectStatus "ck0n" )
				)
				( pin "J1G1.74"
					( objectStatus "ck0p" )
				)
				( pin "J1G1.219"
					( objectStatus "ck1n" )
				)
				( pin "J1G1.218"
					( objectStatus "ck1p" )
				)
				( pin "J1G1.60"
					( objectStatus "cke(0)" )
				)
				( pin "J1G1.203"
					( objectStatus "cke(1)" )
				)
				( pin "J1G1.5"
					( objectStatus "dq(0)" )
				)
				( pin "J1G1.150"
					( objectStatus "dq(1)" )
				)
				( pin "J1G1.12"
					( objectStatus "dq(2)" )
				)
				( pin "J1G1.157"
					( objectStatus "dq(3)" )
				)
				( pin "J1G1.3"
					( objectStatus "dq(4)" )
				)
				( pin "J1G1.148"
					( objectStatus "dq(5)" )
				)
				( pin "J1G1.10"
					( objectStatus "dq(6)" )
				)
				( pin "J1G1.155"
					( objectStatus "dq(7)" )
				)
				( pin "J1G1.16"
					( objectStatus "dq(8)" )
				)
				( pin "J1G1.161"
					( objectStatus "dq(9)" )
				)
				( pin "J1G1.23"
					( objectStatus "dq(10)" )
				)
				( pin "J1G1.168"
					( objectStatus "dq(11)" )
				)
				( pin "J1G1.14"
					( objectStatus "dq(12)" )
				)
				( pin "J1G1.159"
					( objectStatus "dq(13)" )
				)
				( pin "J1G1.21"
					( objectStatus "dq(14)" )
				)
				( pin "J1G1.166"
					( objectStatus "dq(15)" )
				)
				( pin "J1G1.27"
					( objectStatus "dq(16)" )
				)
				( pin "J1G1.172"
					( objectStatus "dq(17)" )
				)
				( pin "J1G1.34"
					( objectStatus "dq(18)" )
				)
				( pin "J1G1.179"
					( objectStatus "dq(19)" )
				)
				( pin "J1G1.25"
					( objectStatus "dq(20)" )
				)
				( pin "J1G1.170"
					( objectStatus "dq(21)" )
				)
				( pin "J1G1.32"
					( objectStatus "dq(22)" )
				)
				( pin "J1G1.177"
					( objectStatus "dq(23)" )
				)
				( pin "J1G1.38"
					( objectStatus "dq(24)" )
				)
				( pin "J1G1.183"
					( objectStatus "dq(25)" )
				)
				( pin "J1G1.45"
					( objectStatus "dq(26)" )
				)
				( pin "J1G1.190"
					( objectStatus "dq(27)" )
				)
				( pin "J1G1.36"
					( objectStatus "dq(28)" )
				)
				( pin "J1G1.181"
					( objectStatus "dq(29)" )
				)
				( pin "J1G1.43"
					( objectStatus "dq(30)" )
				)
				( pin "J1G1.188"
					( objectStatus "dq(31)" )
				)
				( pin "J1G1.97"
					( objectStatus "dq(32)" )
				)
				( pin "J1G1.242"
					( objectStatus "dq(33)" )
				)
				( pin "J1G1.104"
					( objectStatus "dq(34)" )
				)
				( pin "J1G1.249"
					( objectStatus "dq(35)" )
				)
				( pin "J1G1.95"
					( objectStatus "dq(36)" )
				)
				( pin "J1G1.240"
					( objectStatus "dq(37)" )
				)
				( pin "J1G1.102"
					( objectStatus "dq(38)" )
				)
				( pin "J1G1.247"
					( objectStatus "dq(39)" )
				)
				( pin "J1G1.108"
					( objectStatus "dq(40)" )
				)
				( pin "J1G1.253"
					( objectStatus "dq(41)" )
				)
				( pin "J1G1.115"
					( objectStatus "dq(42)" )
				)
				( pin "J1G1.260"
					( objectStatus "dq(43)" )
				)
				( pin "J1G1.106"
					( objectStatus "dq(44)" )
				)
				( pin "J1G1.251"
					( objectStatus "dq(45)" )
				)
				( pin "J1G1.113"
					( objectStatus "dq(46)" )
				)
				( pin "J1G1.258"
					( objectStatus "dq(47)" )
				)
				( pin "J1G1.119"
					( objectStatus "dq(48)" )
				)
				( pin "J1G1.264"
					( objectStatus "dq(49)" )
				)
				( pin "J1G1.126"
					( objectStatus "dq(50)" )
				)
				( pin "J1G1.271"
					( objectStatus "dq(51)" )
				)
				( pin "J1G1.117"
					( objectStatus "dq(52)" )
				)
				( pin "J1G1.262"
					( objectStatus "dq(53)" )
				)
				( pin "J1G1.124"
					( objectStatus "dq(54)" )
				)
				( pin "J1G1.269"
					( objectStatus "dq(55)" )
				)
				( pin "J1G1.130"
					( objectStatus "dq(56)" )
				)
				( pin "J1G1.275"
					( objectStatus "dq(57)" )
				)
				( pin "J1G1.137"
					( objectStatus "dq(58)" )
				)
				( pin "J1G1.282"
					( objectStatus "dq(59)" )
				)
				( pin "J1G1.128"
					( objectStatus "dq(60)" )
				)
				( pin "J1G1.273"
					( objectStatus "dq(61)" )
				)
				( pin "J1G1.135"
					( objectStatus "dq(62)" )
				)
				( pin "J1G1.280"
					( objectStatus "dq(63)" )
				)
				( pin "J1G1.78"
					( objectStatus "event_n" )
				)
				( pin "J1G1.87"
					( objectStatus "odt(0)" )
				)
				( pin "J1G1.91"
					( objectStatus "odt(1)" )
				)
				( pin "J1G1.222"
					( objectStatus "par" )
				)
				( pin "J1G1.58"
					( objectStatus "reset_n" )
				)
				( pin "J1G1.205"
					( objectStatus "rfu(0)" )
				)
				( pin "J1G1.227"
					( objectStatus "rfu(1)" )
				)
				( pin "J1G1.144"
					( objectStatus "rfu(2)" )
				)
				( pin "J1G1.84"
					( objectStatus "s0_n" )
				)
				( pin "J1G1.89"
					( objectStatus "s1_n" )
				)
				( pin "J1G1.93"
					( objectStatus "s2_n_c(0)" )
				)
				( pin "J1G1.237"
					( objectStatus "s3_n_c(1)" )
				)
				( pin "J1G1.139"
					( objectStatus "sa(0)" )
				)
				( pin "J1G1.140"
					( objectStatus "sa(1)" )
				)
				( pin "J1G1.238"
					( objectStatus "sa(2)" )
				)
				( pin "J1G1.230"
					( objectStatus "save_n_nc" )
				)
				( pin "J1G1.141"
					( objectStatus "scl" )
				)
				( pin "J1G1.285"
					( objectStatus "sda" )
				)
				( pin "J1G1.284"
					( objectStatus "vddspd" )
				)
				( pin "J1G1.146"
					( objectStatus "vrefca" )
				)
			)
			( gate "J1G1"
				( objectStatus "@baseboard_fab2_lib.baseboard_fab2(sch_1):page77_i171" )
				( pin "J1G1.145"
					( objectStatus "\12v\(0)" )
				)
				( pin "J1G1.1"
					( objectStatus "\12v\(1)" )
				)
				( pin "J1G1.236"
					( objectStatus "vdd(0)" )
				)
				( pin "J1G1.233"
					( objectStatus "vdd(1)" )
				)
				( pin "J1G1.231"
					( objectStatus "vdd(2)" )
				)
				( pin "J1G1.229"
					( objectStatus "vdd(3)" )
				)
				( pin "J1G1.226"
					( objectStatus "vdd(4)" )
				)
				( pin "J1G1.223"
					( objectStatus "vdd(5)" )
				)
				( pin "J1G1.220"
					( objectStatus "vdd(6)" )
				)
				( pin "J1G1.217"
					( objectStatus "vdd(7)" )
				)
				( pin "J1G1.215"
					( objectStatus "vdd(8)" )
				)
				( pin "J1G1.212"
					( objectStatus "vdd(9)" )
				)
				( pin "J1G1.209"
					( objectStatus "vdd(10)" )
				)
				( pin "J1G1.206"
					( objectStatus "vdd(11)" )
				)
				( pin "J1G1.204"
					( objectStatus "vdd(12)" )
				)
				( pin "J1G1.92"
					( objectStatus "vdd(13)" )
				)
				( pin "J1G1.90"
					( objectStatus "vdd(14)" )
				)
				( pin "J1G1.88"
					( objectStatus "vdd(15)" )
				)
				( pin "J1G1.85"
					( objectStatus "vdd(16)" )
				)
				( pin "J1G1.83"
					( objectStatus "vdd(17)" )
				)
				( pin "J1G1.80"
					( objectStatus "vdd(18)" )
				)
				( pin "J1G1.76"
					( objectStatus "vdd(19)" )
				)
				( pin "J1G1.73"
					( objectStatus "vdd(20)" )
				)
				( pin "J1G1.70"
					( objectStatus "vdd(21)" )
				)
				( pin "J1G1.67"
					( objectStatus "vdd(22)" )
				)
				( pin "J1G1.64"
					( objectStatus "vdd(23)" )
				)
				( pin "J1G1.61"
					( objectStatus "vdd(24)" )
				)
				( pin "J1G1.59"
					( objectStatus "vdd(25)" )
				)
				( pin "J1G1.287"
					( objectStatus "vpp(0)" )
				)
				( pin "J1G1.286"
					( objectStatus "vpp(1)" )
				)
				( pin "J1G1.288"
					( objectStatus "vpp(2)" )
				)
				( pin "J1G1.143"
					( objectStatus "vpp(3)" )
				)
				( pin "J1G1.142"
					( objectStatus "vpp(4)" )
				)
				( pin "J1G1.221"
					( objectStatus "vtt(0)" )
				)
				( pin "J1G1.77"
					( objectStatus "vtt(1)" )
				)
			)
			( gate "C1F22"
				( objectStatus "@baseboard_fab2_lib.baseboard_fab2(sch_1):page77_i181" )
				( pin "C1F22.1"
					( objectStatus "a" )
				)
				( pin "C1F22.2"
					( objectStatus "b" )
				)
			)
			( gate "C9T7"
				( objectStatus "@baseboard_fab2_lib.baseboard_fab2(sch_1):page78_i2" )
				( pin "C9T7.1"
					( objectStatus "a" )
				)
				( pin "C9T7.2"
					( objectStatus "b" )
				)
			)
			( gate "J9T1"
				( objectStatus "@baseboard_fab2_lib.baseboard_fab2(sch_1):page78_i13" )
				( pin "J9T1.79"
					( objectStatus "a0" )
				)
				( pin "J9T1.72"
					( objectStatus "a1" )
				)
				( pin "J9T1.216"
					( objectStatus "a2" )
				)
				( pin "J9T1.71"
					( objectStatus "a3" )
				)
				( pin "J9T1.214"
					( objectStatus "a4" )
				)
				( pin "J9T1.213"
					( objectStatus "a5" )
				)
				( pin "J9T1.69"
					( objectStatus "a6" )
				)
				( pin "J9T1.211"
					( objectStatus "a7" )
				)
				( pin "J9T1.68"
					( objectStatus "a8" )
				)
				( pin "J9T1.66"
					( objectStatus "a9" )
				)
				( pin "J9T1.225"
					( objectStatus "a10" )
				)
				( pin "J9T1.210"
					( objectStatus "a11" )
				)
				( pin "J9T1.65"
					( objectStatus "a12" )
				)
				( pin "J9T1.232"
					( objectStatus "a13" )
				)
				( pin "J9T1.228"
					( objectStatus "a14_we_n" )
				)
				( pin "J9T1.86"
					( objectStatus "a15_cas_n" )
				)
				( pin "J9T1.82"
					( objectStatus "a16_ras_n" )
				)
				( pin "J9T1.234"
					( objectStatus "a17" )
				)
				( pin "J9T1.62"
					( objectStatus "act_n" )
				)
				( pin "J9T1.208"
					( objectStatus "alert_n" )
				)
				( pin "J9T1.81"
					( objectStatus "ba(0)" )
				)
				( pin "J9T1.224"
					( objectStatus "ba(1)" )
				)
				( pin "J9T1.63"
					( objectStatus "bg(0)" )
				)
				( pin "J9T1.207"
					( objectStatus "bg(1)" )
				)
				( pin "J9T1.235"
					( objectStatus "c(2)" )
				)
				( pin "J9T1.49"
					( objectStatus "cb(0)" )
				)
				( pin "J9T1.194"
					( objectStatus "cb(1)" )
				)
				( pin "J9T1.56"
					( objectStatus "cb(2)" )
				)
				( pin "J9T1.201"
					( objectStatus "cb(3)" )
				)
				( pin "J9T1.47"
					( objectStatus "cb(4)" )
				)
				( pin "J9T1.192"
					( objectStatus "cb(5)" )
				)
				( pin "J9T1.54"
					( objectStatus "cb(6)" )
				)
				( pin "J9T1.199"
					( objectStatus "cb(7)" )
				)
				( pin "J9T1.75"
					( objectStatus "ck0n" )
				)
				( pin "J9T1.74"
					( objectStatus "ck0p" )
				)
				( pin "J9T1.219"
					( objectStatus "ck1n" )
				)
				( pin "J9T1.218"
					( objectStatus "ck1p" )
				)
				( pin "J9T1.60"
					( objectStatus "cke(0)" )
				)
				( pin "J9T1.203"
					( objectStatus "cke(1)" )
				)
				( pin "J9T1.5"
					( objectStatus "dq(0)" )
				)
				( pin "J9T1.150"
					( objectStatus "dq(1)" )
				)
				( pin "J9T1.12"
					( objectStatus "dq(2)" )
				)
				( pin "J9T1.157"
					( objectStatus "dq(3)" )
				)
				( pin "J9T1.3"
					( objectStatus "dq(4)" )
				)
				( pin "J9T1.148"
					( objectStatus "dq(5)" )
				)
				( pin "J9T1.10"
					( objectStatus "dq(6)" )
				)
				( pin "J9T1.155"
					( objectStatus "dq(7)" )
				)
				( pin "J9T1.16"
					( objectStatus "dq(8)" )
				)
				( pin "J9T1.161"
					( objectStatus "dq(9)" )
				)
				( pin "J9T1.23"
					( objectStatus "dq(10)" )
				)
				( pin "J9T1.168"
					( objectStatus "dq(11)" )
				)
				( pin "J9T1.14"
					( objectStatus "dq(12)" )
				)
				( pin "J9T1.159"
					( objectStatus "dq(13)" )
				)
				( pin "J9T1.21"
					( objectStatus "dq(14)" )
				)
				( pin "J9T1.166"
					( objectStatus "dq(15)" )
				)
				( pin "J9T1.27"
					( objectStatus "dq(16)" )
				)
				( pin "J9T1.172"
					( objectStatus "dq(17)" )
				)
				( pin "J9T1.34"
					( objectStatus "dq(18)" )
				)
				( pin "J9T1.179"
					( objectStatus "dq(19)" )
				)
				( pin "J9T1.25"
					( objectStatus "dq(20)" )
				)
				( pin "J9T1.170"
					( objectStatus "dq(21)" )
				)
				( pin "J9T1.32"
					( objectStatus "dq(22)" )
				)
				( pin "J9T1.177"
					( objectStatus "dq(23)" )
				)
				( pin "J9T1.38"
					( objectStatus "dq(24)" )
				)
				( pin "J9T1.183"
					( objectStatus "dq(25)" )
				)
				( pin "J9T1.45"
					( objectStatus "dq(26)" )
				)
				( pin "J9T1.190"
					( objectStatus "dq(27)" )
				)
				( pin "J9T1.36"
					( objectStatus "dq(28)" )
				)
				( pin "J9T1.181"
					( objectStatus "dq(29)" )
				)
				( pin "J9T1.43"
					( objectStatus "dq(30)" )
				)
				( pin "J9T1.188"
					( objectStatus "dq(31)" )
				)
				( pin "J9T1.97"
					( objectStatus "dq(32)" )
				)
				( pin "J9T1.242"
					( objectStatus "dq(33)" )
				)
				( pin "J9T1.104"
					( objectStatus "dq(34)" )
				)
				( pin "J9T1.249"
					( objectStatus "dq(35)" )
				)
				( pin "J9T1.95"
					( objectStatus "dq(36)" )
				)
				( pin "J9T1.240"
					( objectStatus "dq(37)" )
				)
				( pin "J9T1.102"
					( objectStatus "dq(38)" )
				)
				( pin "J9T1.247"
					( objectStatus "dq(39)" )
				)
				( pin "J9T1.108"
					( objectStatus "dq(40)" )
				)
				( pin "J9T1.253"
					( objectStatus "dq(41)" )
				)
				( pin "J9T1.115"
					( objectStatus "dq(42)" )
				)
				( pin "J9T1.260"
					( objectStatus "dq(43)" )
				)
				( pin "J9T1.106"
					( objectStatus "dq(44)" )
				)
				( pin "J9T1.251"
					( objectStatus "dq(45)" )
				)
				( pin "J9T1.113"
					( objectStatus "dq(46)" )
				)
				( pin "J9T1.258"
					( objectStatus "dq(47)" )
				)
				( pin "J9T1.119"
					( objectStatus "dq(48)" )
				)
				( pin "J9T1.264"
					( objectStatus "dq(49)" )
				)
				( pin "J9T1.126"
					( objectStatus "dq(50)" )
				)
				( pin "J9T1.271"
					( objectStatus "dq(51)" )
				)
				( pin "J9T1.117"
					( objectStatus "dq(52)" )
				)
				( pin "J9T1.262"
					( objectStatus "dq(53)" )
				)
				( pin "J9T1.124"
					( objectStatus "dq(54)" )
				)
				( pin "J9T1.269"
					( objectStatus "dq(55)" )
				)
				( pin "J9T1.130"
					( objectStatus "dq(56)" )
				)
				( pin "J9T1.275"
					( objectStatus "dq(57)" )
				)
				( pin "J9T1.137"
					( objectStatus "dq(58)" )
				)
				( pin "J9T1.282"
					( objectStatus "dq(59)" )
				)
				( pin "J9T1.128"
					( objectStatus "dq(60)" )
				)
				( pin "J9T1.273"
					( objectStatus "dq(61)" )
				)
				( pin "J9T1.135"
					( objectStatus "dq(62)" )
				)
				( pin "J9T1.280"
					( objectStatus "dq(63)" )
				)
				( pin "J9T1.78"
					( objectStatus "event_n" )
				)
				( pin "J9T1.87"
					( objectStatus "odt(0)" )
				)
				( pin "J9T1.91"
					( objectStatus "odt(1)" )
				)
				( pin "J9T1.222"
					( objectStatus "par" )
				)
				( pin "J9T1.58"
					( objectStatus "reset_n" )
				)
				( pin "J9T1.205"
					( objectStatus "rfu(0)" )
				)
				( pin "J9T1.227"
					( objectStatus "rfu(1)" )
				)
				( pin "J9T1.144"
					( objectStatus "rfu(2)" )
				)
				( pin "J9T1.84"
					( objectStatus "s0_n" )
				)
				( pin "J9T1.89"
					( objectStatus "s1_n" )
				)
				( pin "J9T1.93"
					( objectStatus "s2_n_c(0)" )
				)
				( pin "J9T1.237"
					( objectStatus "s3_n_c(1)" )
				)
				( pin "J9T1.139"
					( objectStatus "sa(0)" )
				)
				( pin "J9T1.140"
					( objectStatus "sa(1)" )
				)
				( pin "J9T1.238"
					( objectStatus "sa(2)" )
				)
				( pin "J9T1.230"
					( objectStatus "save_n_nc" )
				)
				( pin "J9T1.141"
					( objectStatus "scl" )
				)
				( pin "J9T1.285"
					( objectStatus "sda" )
				)
				( pin "J9T1.284"
					( objectStatus "vddspd" )
				)
				( pin "J9T1.146"
					( objectStatus "vrefca" )
				)
			)
			( gate "J9T1"
				( objectStatus "@baseboard_fab2_lib.baseboard_fab2(sch_1):page78_i75" )
				( pin "J9T1.145"
					( objectStatus "\12v\(0)" )
				)
				( pin "J9T1.1"
					( objectStatus "\12v\(1)" )
				)
				( pin "J9T1.236"
					( objectStatus "vdd(0)" )
				)
				( pin "J9T1.233"
					( objectStatus "vdd(1)" )
				)
				( pin "J9T1.231"
					( objectStatus "vdd(2)" )
				)
				( pin "J9T1.229"
					( objectStatus "vdd(3)" )
				)
				( pin "J9T1.226"
					( objectStatus "vdd(4)" )
				)
				( pin "J9T1.223"
					( objectStatus "vdd(5)" )
				)
				( pin "J9T1.220"
					( objectStatus "vdd(6)" )
				)
				( pin "J9T1.217"
					( objectStatus "vdd(7)" )
				)
				( pin "J9T1.215"
					( objectStatus "vdd(8)" )
				)
				( pin "J9T1.212"
					( objectStatus "vdd(9)" )
				)
				( pin "J9T1.209"
					( objectStatus "vdd(10)" )
				)
				( pin "J9T1.206"
					( objectStatus "vdd(11)" )
				)
				( pin "J9T1.204"
					( objectStatus "vdd(12)" )
				)
				( pin "J9T1.92"
					( objectStatus "vdd(13)" )
				)
				( pin "J9T1.90"
					( objectStatus "vdd(14)" )
				)
				( pin "J9T1.88"
					( objectStatus "vdd(15)" )
				)
				( pin "J9T1.85"
					( objectStatus "vdd(16)" )
				)
				( pin "J9T1.83"
					( objectStatus "vdd(17)" )
				)
				( pin "J9T1.80"
					( objectStatus "vdd(18)" )
				)
				( pin "J9T1.76"
					( objectStatus "vdd(19)" )
				)
				( pin "J9T1.73"
					( objectStatus "vdd(20)" )
				)
				( pin "J9T1.70"
					( objectStatus "vdd(21)" )
				)
				( pin "J9T1.67"
					( objectStatus "vdd(22)" )
				)
				( pin "J9T1.64"
					( objectStatus "vdd(23)" )
				)
				( pin "J9T1.61"
					( objectStatus "vdd(24)" )
				)
				( pin "J9T1.59"
					( objectStatus "vdd(25)" )
				)
				( pin "J9T1.287"
					( objectStatus "vpp(0)" )
				)
				( pin "J9T1.286"
					( objectStatus "vpp(1)" )
				)
				( pin "J9T1.288"
					( objectStatus "vpp(2)" )
				)
				( pin "J9T1.143"
					( objectStatus "vpp(3)" )
				)
				( pin "J9T1.142"
					( objectStatus "vpp(4)" )
				)
				( pin "J9T1.221"
					( objectStatus "vtt(0)" )
				)
				( pin "J9T1.77"
					( objectStatus "vtt(1)" )
				)
			)
			( gate "J9T1"
				( objectStatus "@baseboard_fab2_lib.baseboard_fab2(sch_1):page78_i120" )
				( pin "J9T1.152"
					( objectStatus "dqs0n" )
				)
				( pin "J9T1.153"
					( objectStatus "dqs0p" )
				)
				( pin "J9T1.163"
					( objectStatus "dqs1n" )
				)
				( pin "J9T1.164"
					( objectStatus "dqs1p" )
				)
				( pin "J9T1.174"
					( objectStatus "dqs2n" )
				)
				( pin "J9T1.175"
					( objectStatus "dqs2p" )
				)
				( pin "J9T1.185"
					( objectStatus "dqs3n" )
				)
				( pin "J9T1.186"
					( objectStatus "dqs3p" )
				)
				( pin "J9T1.244"
					( objectStatus "dqs4n" )
				)
				( pin "J9T1.245"
					( objectStatus "dqs4p" )
				)
				( pin "J9T1.255"
					( objectStatus "dqs5n" )
				)
				( pin "J9T1.256"
					( objectStatus "dqs5p" )
				)
				( pin "J9T1.266"
					( objectStatus "dqs6n" )
				)
				( pin "J9T1.267"
					( objectStatus "dqs6p" )
				)
				( pin "J9T1.277"
					( objectStatus "dqs7n" )
				)
				( pin "J9T1.278"
					( objectStatus "dqs7p" )
				)
				( pin "J9T1.196"
					( objectStatus "dqs8n" )
				)
				( pin "J9T1.197"
					( objectStatus "dqs8p" )
				)
				( pin "J9T1.8"
					( objectStatus "dqs9n" )
				)
				( pin "J9T1.7"
					( objectStatus "dqs9p" )
				)
				( pin "J9T1.19"
					( objectStatus "dqs10n" )
				)
				( pin "J9T1.18"
					( objectStatus "dqs10p" )
				)
				( pin "J9T1.30"
					( objectStatus "dqs11n" )
				)
				( pin "J9T1.29"
					( objectStatus "dqs11p" )
				)
				( pin "J9T1.41"
					( objectStatus "dqs12n" )
				)
				( pin "J9T1.40"
					( objectStatus "dqs12p" )
				)
				( pin "J9T1.100"
					( objectStatus "dqs13n" )
				)
				( pin "J9T1.99"
					( objectStatus "dqs13p" )
				)
				( pin "J9T1.111"
					( objectStatus "dqs14n" )
				)
				( pin "J9T1.110"
					( objectStatus "dqs14p" )
				)
				( pin "J9T1.122"
					( objectStatus "dqs15n" )
				)
				( pin "J9T1.121"
					( objectStatus "dqs15p" )
				)
				( pin "J9T1.133"
					( objectStatus "dqs16n" )
				)
				( pin "J9T1.132"
					( objectStatus "dqs16p" )
				)
				( pin "J9T1.52"
					( objectStatus "dqs17n" )
				)
				( pin "J9T1.51"
					( objectStatus "dqs17p" )
				)
			)
			( gate "J9T1"
				( objectStatus "@baseboard_fab2_lib.baseboard_fab2(sch_1):page78_i144" )
				( pin "J9T1.283"
					( objectStatus "vss(0)" )
				)
				( pin "J9T1.281"
					( objectStatus "vss(1)" )
				)
				( pin "J9T1.279"
					( objectStatus "vss(2)" )
				)
				( pin "J9T1.276"
					( objectStatus "vss(3)" )
				)
				( pin "J9T1.274"
					( objectStatus "vss(4)" )
				)
				( pin "J9T1.272"
					( objectStatus "vss(5)" )
				)
				( pin "J9T1.270"
					( objectStatus "vss(6)" )
				)
				( pin "J9T1.268"
					( objectStatus "vss(7)" )
				)
				( pin "J9T1.265"
					( objectStatus "vss(8)" )
				)
				( pin "J9T1.263"
					( objectStatus "vss(9)" )
				)
				( pin "J9T1.261"
					( objectStatus "vss(10)" )
				)
				( pin "J9T1.259"
					( objectStatus "vss(11)" )
				)
				( pin "J9T1.257"
					( objectStatus "vss(12)" )
				)
				( pin "J9T1.254"
					( objectStatus "vss(13)" )
				)
				( pin "J9T1.252"
					( objectStatus "vss(14)" )
				)
				( pin "J9T1.250"
					( objectStatus "vss(15)" )
				)
				( pin "J9T1.248"
					( objectStatus "vss(16)" )
				)
				( pin "J9T1.246"
					( objectStatus "vss(17)" )
				)
				( pin "J9T1.243"
					( objectStatus "vss(18)" )
				)
				( pin "J9T1.241"
					( objectStatus "vss(19)" )
				)
				( pin "J9T1.239"
					( objectStatus "vss(20)" )
				)
				( pin "J9T1.202"
					( objectStatus "vss(21)" )
				)
				( pin "J9T1.200"
					( objectStatus "vss(22)" )
				)
				( pin "J9T1.198"
					( objectStatus "vss(23)" )
				)
				( pin "J9T1.195"
					( objectStatus "vss(24)" )
				)
				( pin "J9T1.193"
					( objectStatus "vss(25)" )
				)
				( pin "J9T1.191"
					( objectStatus "vss(26)" )
				)
				( pin "J9T1.189"
					( objectStatus "vss(27)" )
				)
				( pin "J9T1.187"
					( objectStatus "vss(28)" )
				)
				( pin "J9T1.184"
					( objectStatus "vss(29)" )
				)
				( pin "J9T1.182"
					( objectStatus "vss(30)" )
				)
				( pin "J9T1.180"
					( objectStatus "vss(31)" )
				)
				( pin "J9T1.178"
					( objectStatus "vss(32)" )
				)
				( pin "J9T1.176"
					( objectStatus "vss(33)" )
				)
				( pin "J9T1.173"
					( objectStatus "vss(34)" )
				)
				( pin "J9T1.171"
					( objectStatus "vss(35)" )
				)
				( pin "J9T1.169"
					( objectStatus "vss(36)" )
				)
				( pin "J9T1.167"
					( objectStatus "vss(37)" )
				)
				( pin "J9T1.165"
					( objectStatus "vss(38)" )
				)
				( pin "J9T1.162"
					( objectStatus "vss(39)" )
				)
				( pin "J9T1.160"
					( objectStatus "vss(40)" )
				)
				( pin "J9T1.158"
					( objectStatus "vss(41)" )
				)
				( pin "J9T1.156"
					( objectStatus "vss(42)" )
				)
				( pin "J9T1.154"
					( objectStatus "vss(43)" )
				)
				( pin "J9T1.151"
					( objectStatus "vss(44)" )
				)
				( pin "J9T1.149"
					( objectStatus "vss(45)" )
				)
				( pin "J9T1.147"
					( objectStatus "vss(46)" )
				)
				( pin "J9T1.138"
					( objectStatus "vss(47)" )
				)
				( pin "J9T1.136"
					( objectStatus "vss(48)" )
				)
				( pin "J9T1.134"
					( objectStatus "vss(49)" )
				)
				( pin "J9T1.131"
					( objectStatus "vss(50)" )
				)
				( pin "J9T1.129"
					( objectStatus "vss(51)" )
				)
				( pin "J9T1.127"
					( objectStatus "vss(52)" )
				)
				( pin "J9T1.125"
					( objectStatus "vss(53)" )
				)
				( pin "J9T1.123"
					( objectStatus "vss(54)" )
				)
				( pin "J9T1.120"
					( objectStatus "vss(55)" )
				)
				( pin "J9T1.118"
					( objectStatus "vss(56)" )
				)
				( pin "J9T1.116"
					( objectStatus "vss(57)" )
				)
				( pin "J9T1.114"
					( objectStatus "vss(58)" )
				)
				( pin "J9T1.112"
					( objectStatus "vss(59)" )
				)
				( pin "J9T1.109"
					( objectStatus "vss(60)" )
				)
				( pin "J9T1.107"
					( objectStatus "vss(61)" )
				)
				( pin "J9T1.105"
					( objectStatus "vss(62)" )
				)
				( pin "J9T1.103"
					( objectStatus "vss(63)" )
				)
				( pin "J9T1.101"
					( objectStatus "vss(64)" )
				)
				( pin "J9T1.98"
					( objectStatus "vss(65)" )
				)
				( pin "J9T1.96"
					( objectStatus "vss(66)" )
				)
				( pin "J9T1.94"
					( objectStatus "vss(67)" )
				)
				( pin "J9T1.57"
					( objectStatus "vss(68)" )
				)
				( pin "J9T1.55"
					( objectStatus "vss(69)" )
				)
				( pin "J9T1.53"
					( objectStatus "vss(70)" )
				)
				( pin "J9T1.50"
					( objectStatus "vss(71)" )
				)
				( pin "J9T1.48"
					( objectStatus "vss(72)" )
				)
				( pin "J9T1.46"
					( objectStatus "vss(73)" )
				)
				( pin "J9T1.44"
					( objectStatus "vss(74)" )
				)
				( pin "J9T1.42"
					( objectStatus "vss(75)" )
				)
				( pin "J9T1.39"
					( objectStatus "vss(76)" )
				)
				( pin "J9T1.37"
					( objectStatus "vss(77)" )
				)
				( pin "J9T1.35"
					( objectStatus "vss(78)" )
				)
				( pin "J9T1.33"
					( objectStatus "vss(79)" )
				)
				( pin "J9T1.31"
					( objectStatus "vss(80)" )
				)
				( pin "J9T1.28"
					( objectStatus "vss(81)" )
				)
				( pin "J9T1.26"
					( objectStatus "vss(82)" )
				)
				( pin "J9T1.24"
					( objectStatus "vss(83)" )
				)
				( pin "J9T1.22"
					( objectStatus "vss(84)" )
				)
				( pin "J9T1.20"
					( objectStatus "vss(85)" )
				)
				( pin "J9T1.17"
					( objectStatus "vss(86)" )
				)
				( pin "J9T1.15"
					( objectStatus "vss(87)" )
				)
				( pin "J9T1.13"
					( objectStatus "vss(88)" )
				)
				( pin "J9T1.11"
					( objectStatus "vss(89)" )
				)
				( pin "J9T1.9"
					( objectStatus "vss(90)" )
				)
				( pin "J9T1.6"
					( objectStatus "vss(91)" )
				)
				( pin "J9T1.4"
					( objectStatus "vss(92)" )
				)
				( pin "J9T1.2"
					( objectStatus "vss(93)" )
				)
			)
			( gate "J1G2"
				( objectStatus "@baseboard_fab2_lib.baseboard_fab2(sch_1):page79_i43" )
				( pin "J1G2.283"
					( objectStatus "vss(0)" )
				)
				( pin "J1G2.281"
					( objectStatus "vss(1)" )
				)
				( pin "J1G2.279"
					( objectStatus "vss(2)" )
				)
				( pin "J1G2.276"
					( objectStatus "vss(3)" )
				)
				( pin "J1G2.274"
					( objectStatus "vss(4)" )
				)
				( pin "J1G2.272"
					( objectStatus "vss(5)" )
				)
				( pin "J1G2.270"
					( objectStatus "vss(6)" )
				)
				( pin "J1G2.268"
					( objectStatus "vss(7)" )
				)
				( pin "J1G2.265"
					( objectStatus "vss(8)" )
				)
				( pin "J1G2.263"
					( objectStatus "vss(9)" )
				)
				( pin "J1G2.261"
					( objectStatus "vss(10)" )
				)
				( pin "J1G2.259"
					( objectStatus "vss(11)" )
				)
				( pin "J1G2.257"
					( objectStatus "vss(12)" )
				)
				( pin "J1G2.254"
					( objectStatus "vss(13)" )
				)
				( pin "J1G2.252"
					( objectStatus "vss(14)" )
				)
				( pin "J1G2.250"
					( objectStatus "vss(15)" )
				)
				( pin "J1G2.248"
					( objectStatus "vss(16)" )
				)
				( pin "J1G2.246"
					( objectStatus "vss(17)" )
				)
				( pin "J1G2.243"
					( objectStatus "vss(18)" )
				)
				( pin "J1G2.241"
					( objectStatus "vss(19)" )
				)
				( pin "J1G2.239"
					( objectStatus "vss(20)" )
				)
				( pin "J1G2.202"
					( objectStatus "vss(21)" )
				)
				( pin "J1G2.200"
					( objectStatus "vss(22)" )
				)
				( pin "J1G2.198"
					( objectStatus "vss(23)" )
				)
				( pin "J1G2.195"
					( objectStatus "vss(24)" )
				)
				( pin "J1G2.193"
					( objectStatus "vss(25)" )
				)
				( pin "J1G2.191"
					( objectStatus "vss(26)" )
				)
				( pin "J1G2.189"
					( objectStatus "vss(27)" )
				)
				( pin "J1G2.187"
					( objectStatus "vss(28)" )
				)
				( pin "J1G2.184"
					( objectStatus "vss(29)" )
				)
				( pin "J1G2.182"
					( objectStatus "vss(30)" )
				)
				( pin "J1G2.180"
					( objectStatus "vss(31)" )
				)
				( pin "J1G2.178"
					( objectStatus "vss(32)" )
				)
				( pin "J1G2.176"
					( objectStatus "vss(33)" )
				)
				( pin "J1G2.173"
					( objectStatus "vss(34)" )
				)
				( pin "J1G2.171"
					( objectStatus "vss(35)" )
				)
				( pin "J1G2.169"
					( objectStatus "vss(36)" )
				)
				( pin "J1G2.167"
					( objectStatus "vss(37)" )
				)
				( pin "J1G2.165"
					( objectStatus "vss(38)" )
				)
				( pin "J1G2.162"
					( objectStatus "vss(39)" )
				)
				( pin "J1G2.160"
					( objectStatus "vss(40)" )
				)
				( pin "J1G2.158"
					( objectStatus "vss(41)" )
				)
				( pin "J1G2.156"
					( objectStatus "vss(42)" )
				)
				( pin "J1G2.154"
					( objectStatus "vss(43)" )
				)
				( pin "J1G2.151"
					( objectStatus "vss(44)" )
				)
				( pin "J1G2.149"
					( objectStatus "vss(45)" )
				)
				( pin "J1G2.147"
					( objectStatus "vss(46)" )
				)
				( pin "J1G2.138"
					( objectStatus "vss(47)" )
				)
				( pin "J1G2.136"
					( objectStatus "vss(48)" )
				)
				( pin "J1G2.134"
					( objectStatus "vss(49)" )
				)
				( pin "J1G2.131"
					( objectStatus "vss(50)" )
				)
				( pin "J1G2.129"
					( objectStatus "vss(51)" )
				)
				( pin "J1G2.127"
					( objectStatus "vss(52)" )
				)
				( pin "J1G2.125"
					( objectStatus "vss(53)" )
				)
				( pin "J1G2.123"
					( objectStatus "vss(54)" )
				)
				( pin "J1G2.120"
					( objectStatus "vss(55)" )
				)
				( pin "J1G2.118"
					( objectStatus "vss(56)" )
				)
				( pin "J1G2.116"
					( objectStatus "vss(57)" )
				)
				( pin "J1G2.114"
					( objectStatus "vss(58)" )
				)
				( pin "J1G2.112"
					( objectStatus "vss(59)" )
				)
				( pin "J1G2.109"
					( objectStatus "vss(60)" )
				)
				( pin "J1G2.107"
					( objectStatus "vss(61)" )
				)
				( pin "J1G2.105"
					( objectStatus "vss(62)" )
				)
				( pin "J1G2.103"
					( objectStatus "vss(63)" )
				)
				( pin "J1G2.101"
					( objectStatus "vss(64)" )
				)
				( pin "J1G2.98"
					( objectStatus "vss(65)" )
				)
				( pin "J1G2.96"
					( objectStatus "vss(66)" )
				)
				( pin "J1G2.94"
					( objectStatus "vss(67)" )
				)
				( pin "J1G2.57"
					( objectStatus "vss(68)" )
				)
				( pin "J1G2.55"
					( objectStatus "vss(69)" )
				)
				( pin "J1G2.53"
					( objectStatus "vss(70)" )
				)
				( pin "J1G2.50"
					( objectStatus "vss(71)" )
				)
				( pin "J1G2.48"
					( objectStatus "vss(72)" )
				)
				( pin "J1G2.46"
					( objectStatus "vss(73)" )
				)
				( pin "J1G2.44"
					( objectStatus "vss(74)" )
				)
				( pin "J1G2.42"
					( objectStatus "vss(75)" )
				)
				( pin "J1G2.39"
					( objectStatus "vss(76)" )
				)
				( pin "J1G2.37"
					( objectStatus "vss(77)" )
				)
				( pin "J1G2.35"
					( objectStatus "vss(78)" )
				)
				( pin "J1G2.33"
					( objectStatus "vss(79)" )
				)
				( pin "J1G2.31"
					( objectStatus "vss(80)" )
				)
				( pin "J1G2.28"
					( objectStatus "vss(81)" )
				)
				( pin "J1G2.26"
					( objectStatus "vss(82)" )
				)
				( pin "J1G2.24"
					( objectStatus "vss(83)" )
				)
				( pin "J1G2.22"
					( objectStatus "vss(84)" )
				)
				( pin "J1G2.20"
					( objectStatus "vss(85)" )
				)
				( pin "J1G2.17"
					( objectStatus "vss(86)" )
				)
				( pin "J1G2.15"
					( objectStatus "vss(87)" )
				)
				( pin "J1G2.13"
					( objectStatus "vss(88)" )
				)
				( pin "J1G2.11"
					( objectStatus "vss(89)" )
				)
				( pin "J1G2.9"
					( objectStatus "vss(90)" )
				)
				( pin "J1G2.6"
					( objectStatus "vss(91)" )
				)
				( pin "J1G2.4"
					( objectStatus "vss(92)" )
				)
				( pin "J1G2.2"
					( objectStatus "vss(93)" )
				)
			)
			( gate "J1G2"
				( objectStatus "@baseboard_fab2_lib.baseboard_fab2(sch_1):page79_i64" )
				( pin "J1G2.152"
					( objectStatus "dqs0n" )
				)
				( pin "J1G2.153"
					( objectStatus "dqs0p" )
				)
				( pin "J1G2.163"
					( objectStatus "dqs1n" )
				)
				( pin "J1G2.164"
					( objectStatus "dqs1p" )
				)
				( pin "J1G2.174"
					( objectStatus "dqs2n" )
				)
				( pin "J1G2.175"
					( objectStatus "dqs2p" )
				)
				( pin "J1G2.185"
					( objectStatus "dqs3n" )
				)
				( pin "J1G2.186"
					( objectStatus "dqs3p" )
				)
				( pin "J1G2.244"
					( objectStatus "dqs4n" )
				)
				( pin "J1G2.245"
					( objectStatus "dqs4p" )
				)
				( pin "J1G2.255"
					( objectStatus "dqs5n" )
				)
				( pin "J1G2.256"
					( objectStatus "dqs5p" )
				)
				( pin "J1G2.266"
					( objectStatus "dqs6n" )
				)
				( pin "J1G2.267"
					( objectStatus "dqs6p" )
				)
				( pin "J1G2.277"
					( objectStatus "dqs7n" )
				)
				( pin "J1G2.278"
					( objectStatus "dqs7p" )
				)
				( pin "J1G2.196"
					( objectStatus "dqs8n" )
				)
				( pin "J1G2.197"
					( objectStatus "dqs8p" )
				)
				( pin "J1G2.8"
					( objectStatus "dqs9n" )
				)
				( pin "J1G2.7"
					( objectStatus "dqs9p" )
				)
				( pin "J1G2.19"
					( objectStatus "dqs10n" )
				)
				( pin "J1G2.18"
					( objectStatus "dqs10p" )
				)
				( pin "J1G2.30"
					( objectStatus "dqs11n" )
				)
				( pin "J1G2.29"
					( objectStatus "dqs11p" )
				)
				( pin "J1G2.41"
					( objectStatus "dqs12n" )
				)
				( pin "J1G2.40"
					( objectStatus "dqs12p" )
				)
				( pin "J1G2.100"
					( objectStatus "dqs13n" )
				)
				( pin "J1G2.99"
					( objectStatus "dqs13p" )
				)
				( pin "J1G2.111"
					( objectStatus "dqs14n" )
				)
				( pin "J1G2.110"
					( objectStatus "dqs14p" )
				)
				( pin "J1G2.122"
					( objectStatus "dqs15n" )
				)
				( pin "J1G2.121"
					( objectStatus "dqs15p" )
				)
				( pin "J1G2.133"
					( objectStatus "dqs16n" )
				)
				( pin "J1G2.132"
					( objectStatus "dqs16p" )
				)
				( pin "J1G2.52"
					( objectStatus "dqs17n" )
				)
				( pin "J1G2.51"
					( objectStatus "dqs17p" )
				)
			)
			( gate "J1G2"
				( objectStatus "@baseboard_fab2_lib.baseboard_fab2(sch_1):page79_i111" )
				( pin "J1G2.79"
					( objectStatus "a0" )
				)
				( pin "J1G2.72"
					( objectStatus "a1" )
				)
				( pin "J1G2.216"
					( objectStatus "a2" )
				)
				( pin "J1G2.71"
					( objectStatus "a3" )
				)
				( pin "J1G2.214"
					( objectStatus "a4" )
				)
				( pin "J1G2.213"
					( objectStatus "a5" )
				)
				( pin "J1G2.69"
					( objectStatus "a6" )
				)
				( pin "J1G2.211"
					( objectStatus "a7" )
				)
				( pin "J1G2.68"
					( objectStatus "a8" )
				)
				( pin "J1G2.66"
					( objectStatus "a9" )
				)
				( pin "J1G2.225"
					( objectStatus "a10" )
				)
				( pin "J1G2.210"
					( objectStatus "a11" )
				)
				( pin "J1G2.65"
					( objectStatus "a12" )
				)
				( pin "J1G2.232"
					( objectStatus "a13" )
				)
				( pin "J1G2.228"
					( objectStatus "a14_we_n" )
				)
				( pin "J1G2.86"
					( objectStatus "a15_cas_n" )
				)
				( pin "J1G2.82"
					( objectStatus "a16_ras_n" )
				)
				( pin "J1G2.234"
					( objectStatus "a17" )
				)
				( pin "J1G2.62"
					( objectStatus "act_n" )
				)
				( pin "J1G2.208"
					( objectStatus "alert_n" )
				)
				( pin "J1G2.81"
					( objectStatus "ba(0)" )
				)
				( pin "J1G2.224"
					( objectStatus "ba(1)" )
				)
				( pin "J1G2.63"
					( objectStatus "bg(0)" )
				)
				( pin "J1G2.207"
					( objectStatus "bg(1)" )
				)
				( pin "J1G2.235"
					( objectStatus "c(2)" )
				)
				( pin "J1G2.49"
					( objectStatus "cb(0)" )
				)
				( pin "J1G2.194"
					( objectStatus "cb(1)" )
				)
				( pin "J1G2.56"
					( objectStatus "cb(2)" )
				)
				( pin "J1G2.201"
					( objectStatus "cb(3)" )
				)
				( pin "J1G2.47"
					( objectStatus "cb(4)" )
				)
				( pin "J1G2.192"
					( objectStatus "cb(5)" )
				)
				( pin "J1G2.54"
					( objectStatus "cb(6)" )
				)
				( pin "J1G2.199"
					( objectStatus "cb(7)" )
				)
				( pin "J1G2.75"
					( objectStatus "ck0n" )
				)
				( pin "J1G2.74"
					( objectStatus "ck0p" )
				)
				( pin "J1G2.219"
					( objectStatus "ck1n" )
				)
				( pin "J1G2.218"
					( objectStatus "ck1p" )
				)
				( pin "J1G2.60"
					( objectStatus "cke(0)" )
				)
				( pin "J1G2.203"
					( objectStatus "cke(1)" )
				)
				( pin "J1G2.5"
					( objectStatus "dq(0)" )
				)
				( pin "J1G2.150"
					( objectStatus "dq(1)" )
				)
				( pin "J1G2.12"
					( objectStatus "dq(2)" )
				)
				( pin "J1G2.157"
					( objectStatus "dq(3)" )
				)
				( pin "J1G2.3"
					( objectStatus "dq(4)" )
				)
				( pin "J1G2.148"
					( objectStatus "dq(5)" )
				)
				( pin "J1G2.10"
					( objectStatus "dq(6)" )
				)
				( pin "J1G2.155"
					( objectStatus "dq(7)" )
				)
				( pin "J1G2.16"
					( objectStatus "dq(8)" )
				)
				( pin "J1G2.161"
					( objectStatus "dq(9)" )
				)
				( pin "J1G2.23"
					( objectStatus "dq(10)" )
				)
				( pin "J1G2.168"
					( objectStatus "dq(11)" )
				)
				( pin "J1G2.14"
					( objectStatus "dq(12)" )
				)
				( pin "J1G2.159"
					( objectStatus "dq(13)" )
				)
				( pin "J1G2.21"
					( objectStatus "dq(14)" )
				)
				( pin "J1G2.166"
					( objectStatus "dq(15)" )
				)
				( pin "J1G2.27"
					( objectStatus "dq(16)" )
				)
				( pin "J1G2.172"
					( objectStatus "dq(17)" )
				)
				( pin "J1G2.34"
					( objectStatus "dq(18)" )
				)
				( pin "J1G2.179"
					( objectStatus "dq(19)" )
				)
				( pin "J1G2.25"
					( objectStatus "dq(20)" )
				)
				( pin "J1G2.170"
					( objectStatus "dq(21)" )
				)
				( pin "J1G2.32"
					( objectStatus "dq(22)" )
				)
				( pin "J1G2.177"
					( objectStatus "dq(23)" )
				)
				( pin "J1G2.38"
					( objectStatus "dq(24)" )
				)
				( pin "J1G2.183"
					( objectStatus "dq(25)" )
				)
				( pin "J1G2.45"
					( objectStatus "dq(26)" )
				)
				( pin "J1G2.190"
					( objectStatus "dq(27)" )
				)
				( pin "J1G2.36"
					( objectStatus "dq(28)" )
				)
				( pin "J1G2.181"
					( objectStatus "dq(29)" )
				)
				( pin "J1G2.43"
					( objectStatus "dq(30)" )
				)
				( pin "J1G2.188"
					( objectStatus "dq(31)" )
				)
				( pin "J1G2.97"
					( objectStatus "dq(32)" )
				)
				( pin "J1G2.242"
					( objectStatus "dq(33)" )
				)
				( pin "J1G2.104"
					( objectStatus "dq(34)" )
				)
				( pin "J1G2.249"
					( objectStatus "dq(35)" )
				)
				( pin "J1G2.95"
					( objectStatus "dq(36)" )
				)
				( pin "J1G2.240"
					( objectStatus "dq(37)" )
				)
				( pin "J1G2.102"
					( objectStatus "dq(38)" )
				)
				( pin "J1G2.247"
					( objectStatus "dq(39)" )
				)
				( pin "J1G2.108"
					( objectStatus "dq(40)" )
				)
				( pin "J1G2.253"
					( objectStatus "dq(41)" )
				)
				( pin "J1G2.115"
					( objectStatus "dq(42)" )
				)
				( pin "J1G2.260"
					( objectStatus "dq(43)" )
				)
				( pin "J1G2.106"
					( objectStatus "dq(44)" )
				)
				( pin "J1G2.251"
					( objectStatus "dq(45)" )
				)
				( pin "J1G2.113"
					( objectStatus "dq(46)" )
				)
				( pin "J1G2.258"
					( objectStatus "dq(47)" )
				)
				( pin "J1G2.119"
					( objectStatus "dq(48)" )
				)
				( pin "J1G2.264"
					( objectStatus "dq(49)" )
				)
				( pin "J1G2.126"
					( objectStatus "dq(50)" )
				)
				( pin "J1G2.271"
					( objectStatus "dq(51)" )
				)
				( pin "J1G2.117"
					( objectStatus "dq(52)" )
				)
				( pin "J1G2.262"
					( objectStatus "dq(53)" )
				)
				( pin "J1G2.124"
					( objectStatus "dq(54)" )
				)
				( pin "J1G2.269"
					( objectStatus "dq(55)" )
				)
				( pin "J1G2.130"
					( objectStatus "dq(56)" )
				)
				( pin "J1G2.275"
					( objectStatus "dq(57)" )
				)
				( pin "J1G2.137"
					( objectStatus "dq(58)" )
				)
				( pin "J1G2.282"
					( objectStatus "dq(59)" )
				)
				( pin "J1G2.128"
					( objectStatus "dq(60)" )
				)
				( pin "J1G2.273"
					( objectStatus "dq(61)" )
				)
				( pin "J1G2.135"
					( objectStatus "dq(62)" )
				)
				( pin "J1G2.280"
					( objectStatus "dq(63)" )
				)
				( pin "J1G2.78"
					( objectStatus "event_n" )
				)
				( pin "J1G2.87"
					( objectStatus "odt(0)" )
				)
				( pin "J1G2.91"
					( objectStatus "odt(1)" )
				)
				( pin "J1G2.222"
					( objectStatus "par" )
				)
				( pin "J1G2.58"
					( objectStatus "reset_n" )
				)
				( pin "J1G2.205"
					( objectStatus "rfu(0)" )
				)
				( pin "J1G2.227"
					( objectStatus "rfu(1)" )
				)
				( pin "J1G2.144"
					( objectStatus "rfu(2)" )
				)
				( pin "J1G2.84"
					( objectStatus "s0_n" )
				)
				( pin "J1G2.89"
					( objectStatus "s1_n" )
				)
				( pin "J1G2.93"
					( objectStatus "s2_n_c(0)" )
				)
				( pin "J1G2.237"
					( objectStatus "s3_n_c(1)" )
				)
				( pin "J1G2.139"
					( objectStatus "sa(0)" )
				)
				( pin "J1G2.140"
					( objectStatus "sa(1)" )
				)
				( pin "J1G2.238"
					( objectStatus "sa(2)" )
				)
				( pin "J1G2.230"
					( objectStatus "save_n_nc" )
				)
				( pin "J1G2.141"
					( objectStatus "scl" )
				)
				( pin "J1G2.285"
					( objectStatus "sda" )
				)
				( pin "J1G2.284"
					( objectStatus "vddspd" )
				)
				( pin "J1G2.146"
					( objectStatus "vrefca" )
				)
			)
			( gate "J1G2"
				( objectStatus "@baseboard_fab2_lib.baseboard_fab2(sch_1):page79_i169" )
				( pin "J1G2.145"
					( objectStatus "\12v\(0)" )
				)
				( pin "J1G2.1"
					( objectStatus "\12v\(1)" )
				)
				( pin "J1G2.236"
					( objectStatus "vdd(0)" )
				)
				( pin "J1G2.233"
					( objectStatus "vdd(1)" )
				)
				( pin "J1G2.231"
					( objectStatus "vdd(2)" )
				)
				( pin "J1G2.229"
					( objectStatus "vdd(3)" )
				)
				( pin "J1G2.226"
					( objectStatus "vdd(4)" )
				)
				( pin "J1G2.223"
					( objectStatus "vdd(5)" )
				)
				( pin "J1G2.220"
					( objectStatus "vdd(6)" )
				)
				( pin "J1G2.217"
					( objectStatus "vdd(7)" )
				)
				( pin "J1G2.215"
					( objectStatus "vdd(8)" )
				)
				( pin "J1G2.212"
					( objectStatus "vdd(9)" )
				)
				( pin "J1G2.209"
					( objectStatus "vdd(10)" )
				)
				( pin "J1G2.206"
					( objectStatus "vdd(11)" )
				)
				( pin "J1G2.204"
					( objectStatus "vdd(12)" )
				)
				( pin "J1G2.92"
					( objectStatus "vdd(13)" )
				)
				( pin "J1G2.90"
					( objectStatus "vdd(14)" )
				)
				( pin "J1G2.88"
					( objectStatus "vdd(15)" )
				)
				( pin "J1G2.85"
					( objectStatus "vdd(16)" )
				)
				( pin "J1G2.83"
					( objectStatus "vdd(17)" )
				)
				( pin "J1G2.80"
					( objectStatus "vdd(18)" )
				)
				( pin "J1G2.76"
					( objectStatus "vdd(19)" )
				)
				( pin "J1G2.73"
					( objectStatus "vdd(20)" )
				)
				( pin "J1G2.70"
					( objectStatus "vdd(21)" )
				)
				( pin "J1G2.67"
					( objectStatus "vdd(22)" )
				)
				( pin "J1G2.64"
					( objectStatus "vdd(23)" )
				)
				( pin "J1G2.61"
					( objectStatus "vdd(24)" )
				)
				( pin "J1G2.59"
					( objectStatus "vdd(25)" )
				)
				( pin "J1G2.287"
					( objectStatus "vpp(0)" )
				)
				( pin "J1G2.286"
					( objectStatus "vpp(1)" )
				)
				( pin "J1G2.288"
					( objectStatus "vpp(2)" )
				)
				( pin "J1G2.143"
					( objectStatus "vpp(3)" )
				)
				( pin "J1G2.142"
					( objectStatus "vpp(4)" )
				)
				( pin "J1G2.221"
					( objectStatus "vtt(0)" )
				)
				( pin "J1G2.77"
					( objectStatus "vtt(1)" )
				)
			)
			( gate "C9U7"
				( objectStatus "@baseboard_fab2_lib.baseboard_fab2(sch_1):page79_i178" )
				( pin "C9U7.1"
					( objectStatus "a" )
				)
				( pin "C9U7.2"
					( objectStatus "b" )
				)
			)
			( gate "C1G10"
				( objectStatus "@baseboard_fab2_lib.baseboard_fab2(sch_1):page80_i3" )
				( pin "C1G10.1"
					( objectStatus "a" )
				)
				( pin "C1G10.2"
					( objectStatus "b" )
				)
			)
			( gate "J9U1"
				( objectStatus "@baseboard_fab2_lib.baseboard_fab2(sch_1):page80_i24" )
				( pin "J9U1.79"
					( objectStatus "a0" )
				)
				( pin "J9U1.72"
					( objectStatus "a1" )
				)
				( pin "J9U1.216"
					( objectStatus "a2" )
				)
				( pin "J9U1.71"
					( objectStatus "a3" )
				)
				( pin "J9U1.214"
					( objectStatus "a4" )
				)
				( pin "J9U1.213"
					( objectStatus "a5" )
				)
				( pin "J9U1.69"
					( objectStatus "a6" )
				)
				( pin "J9U1.211"
					( objectStatus "a7" )
				)
				( pin "J9U1.68"
					( objectStatus "a8" )
				)
				( pin "J9U1.66"
					( objectStatus "a9" )
				)
				( pin "J9U1.225"
					( objectStatus "a10" )
				)
				( pin "J9U1.210"
					( objectStatus "a11" )
				)
				( pin "J9U1.65"
					( objectStatus "a12" )
				)
				( pin "J9U1.232"
					( objectStatus "a13" )
				)
				( pin "J9U1.228"
					( objectStatus "a14_we_n" )
				)
				( pin "J9U1.86"
					( objectStatus "a15_cas_n" )
				)
				( pin "J9U1.82"
					( objectStatus "a16_ras_n" )
				)
				( pin "J9U1.234"
					( objectStatus "a17" )
				)
				( pin "J9U1.62"
					( objectStatus "act_n" )
				)
				( pin "J9U1.208"
					( objectStatus "alert_n" )
				)
				( pin "J9U1.81"
					( objectStatus "ba(0)" )
				)
				( pin "J9U1.224"
					( objectStatus "ba(1)" )
				)
				( pin "J9U1.63"
					( objectStatus "bg(0)" )
				)
				( pin "J9U1.207"
					( objectStatus "bg(1)" )
				)
				( pin "J9U1.235"
					( objectStatus "c(2)" )
				)
				( pin "J9U1.49"
					( objectStatus "cb(0)" )
				)
				( pin "J9U1.194"
					( objectStatus "cb(1)" )
				)
				( pin "J9U1.56"
					( objectStatus "cb(2)" )
				)
				( pin "J9U1.201"
					( objectStatus "cb(3)" )
				)
				( pin "J9U1.47"
					( objectStatus "cb(4)" )
				)
				( pin "J9U1.192"
					( objectStatus "cb(5)" )
				)
				( pin "J9U1.54"
					( objectStatus "cb(6)" )
				)
				( pin "J9U1.199"
					( objectStatus "cb(7)" )
				)
				( pin "J9U1.75"
					( objectStatus "ck0n" )
				)
				( pin "J9U1.74"
					( objectStatus "ck0p" )
				)
				( pin "J9U1.219"
					( objectStatus "ck1n" )
				)
				( pin "J9U1.218"
					( objectStatus "ck1p" )
				)
				( pin "J9U1.60"
					( objectStatus "cke(0)" )
				)
				( pin "J9U1.203"
					( objectStatus "cke(1)" )
				)
				( pin "J9U1.5"
					( objectStatus "dq(0)" )
				)
				( pin "J9U1.150"
					( objectStatus "dq(1)" )
				)
				( pin "J9U1.12"
					( objectStatus "dq(2)" )
				)
				( pin "J9U1.157"
					( objectStatus "dq(3)" )
				)
				( pin "J9U1.3"
					( objectStatus "dq(4)" )
				)
				( pin "J9U1.148"
					( objectStatus "dq(5)" )
				)
				( pin "J9U1.10"
					( objectStatus "dq(6)" )
				)
				( pin "J9U1.155"
					( objectStatus "dq(7)" )
				)
				( pin "J9U1.16"
					( objectStatus "dq(8)" )
				)
				( pin "J9U1.161"
					( objectStatus "dq(9)" )
				)
				( pin "J9U1.23"
					( objectStatus "dq(10)" )
				)
				( pin "J9U1.168"
					( objectStatus "dq(11)" )
				)
				( pin "J9U1.14"
					( objectStatus "dq(12)" )
				)
				( pin "J9U1.159"
					( objectStatus "dq(13)" )
				)
				( pin "J9U1.21"
					( objectStatus "dq(14)" )
				)
				( pin "J9U1.166"
					( objectStatus "dq(15)" )
				)
				( pin "J9U1.27"
					( objectStatus "dq(16)" )
				)
				( pin "J9U1.172"
					( objectStatus "dq(17)" )
				)
				( pin "J9U1.34"
					( objectStatus "dq(18)" )
				)
				( pin "J9U1.179"
					( objectStatus "dq(19)" )
				)
				( pin "J9U1.25"
					( objectStatus "dq(20)" )
				)
				( pin "J9U1.170"
					( objectStatus "dq(21)" )
				)
				( pin "J9U1.32"
					( objectStatus "dq(22)" )
				)
				( pin "J9U1.177"
					( objectStatus "dq(23)" )
				)
				( pin "J9U1.38"
					( objectStatus "dq(24)" )
				)
				( pin "J9U1.183"
					( objectStatus "dq(25)" )
				)
				( pin "J9U1.45"
					( objectStatus "dq(26)" )
				)
				( pin "J9U1.190"
					( objectStatus "dq(27)" )
				)
				( pin "J9U1.36"
					( objectStatus "dq(28)" )
				)
				( pin "J9U1.181"
					( objectStatus "dq(29)" )
				)
				( pin "J9U1.43"
					( objectStatus "dq(30)" )
				)
				( pin "J9U1.188"
					( objectStatus "dq(31)" )
				)
				( pin "J9U1.97"
					( objectStatus "dq(32)" )
				)
				( pin "J9U1.242"
					( objectStatus "dq(33)" )
				)
				( pin "J9U1.104"
					( objectStatus "dq(34)" )
				)
				( pin "J9U1.249"
					( objectStatus "dq(35)" )
				)
				( pin "J9U1.95"
					( objectStatus "dq(36)" )
				)
				( pin "J9U1.240"
					( objectStatus "dq(37)" )
				)
				( pin "J9U1.102"
					( objectStatus "dq(38)" )
				)
				( pin "J9U1.247"
					( objectStatus "dq(39)" )
				)
				( pin "J9U1.108"
					( objectStatus "dq(40)" )
				)
				( pin "J9U1.253"
					( objectStatus "dq(41)" )
				)
				( pin "J9U1.115"
					( objectStatus "dq(42)" )
				)
				( pin "J9U1.260"
					( objectStatus "dq(43)" )
				)
				( pin "J9U1.106"
					( objectStatus "dq(44)" )
				)
				( pin "J9U1.251"
					( objectStatus "dq(45)" )
				)
				( pin "J9U1.113"
					( objectStatus "dq(46)" )
				)
				( pin "J9U1.258"
					( objectStatus "dq(47)" )
				)
				( pin "J9U1.119"
					( objectStatus "dq(48)" )
				)
				( pin "J9U1.264"
					( objectStatus "dq(49)" )
				)
				( pin "J9U1.126"
					( objectStatus "dq(50)" )
				)
				( pin "J9U1.271"
					( objectStatus "dq(51)" )
				)
				( pin "J9U1.117"
					( objectStatus "dq(52)" )
				)
				( pin "J9U1.262"
					( objectStatus "dq(53)" )
				)
				( pin "J9U1.124"
					( objectStatus "dq(54)" )
				)
				( pin "J9U1.269"
					( objectStatus "dq(55)" )
				)
				( pin "J9U1.130"
					( objectStatus "dq(56)" )
				)
				( pin "J9U1.275"
					( objectStatus "dq(57)" )
				)
				( pin "J9U1.137"
					( objectStatus "dq(58)" )
				)
				( pin "J9U1.282"
					( objectStatus "dq(59)" )
				)
				( pin "J9U1.128"
					( objectStatus "dq(60)" )
				)
				( pin "J9U1.273"
					( objectStatus "dq(61)" )
				)
				( pin "J9U1.135"
					( objectStatus "dq(62)" )
				)
				( pin "J9U1.280"
					( objectStatus "dq(63)" )
				)
				( pin "J9U1.78"
					( objectStatus "event_n" )
				)
				( pin "J9U1.87"
					( objectStatus "odt(0)" )
				)
				( pin "J9U1.91"
					( objectStatus "odt(1)" )
				)
				( pin "J9U1.222"
					( objectStatus "par" )
				)
				( pin "J9U1.58"
					( objectStatus "reset_n" )
				)
				( pin "J9U1.205"
					( objectStatus "rfu(0)" )
				)
				( pin "J9U1.227"
					( objectStatus "rfu(1)" )
				)
				( pin "J9U1.144"
					( objectStatus "rfu(2)" )
				)
				( pin "J9U1.84"
					( objectStatus "s0_n" )
				)
				( pin "J9U1.89"
					( objectStatus "s1_n" )
				)
				( pin "J9U1.93"
					( objectStatus "s2_n_c(0)" )
				)
				( pin "J9U1.237"
					( objectStatus "s3_n_c(1)" )
				)
				( pin "J9U1.139"
					( objectStatus "sa(0)" )
				)
				( pin "J9U1.140"
					( objectStatus "sa(1)" )
				)
				( pin "J9U1.238"
					( objectStatus "sa(2)" )
				)
				( pin "J9U1.230"
					( objectStatus "save_n_nc" )
				)
				( pin "J9U1.141"
					( objectStatus "scl" )
				)
				( pin "J9U1.285"
					( objectStatus "sda" )
				)
				( pin "J9U1.284"
					( objectStatus "vddspd" )
				)
				( pin "J9U1.146"
					( objectStatus "vrefca" )
				)
			)
			( gate "J9U1"
				( objectStatus "@baseboard_fab2_lib.baseboard_fab2(sch_1):page80_i56" )
				( pin "J9U1.145"
					( objectStatus "\12v\(0)" )
				)
				( pin "J9U1.1"
					( objectStatus "\12v\(1)" )
				)
				( pin "J9U1.236"
					( objectStatus "vdd(0)" )
				)
				( pin "J9U1.233"
					( objectStatus "vdd(1)" )
				)
				( pin "J9U1.231"
					( objectStatus "vdd(2)" )
				)
				( pin "J9U1.229"
					( objectStatus "vdd(3)" )
				)
				( pin "J9U1.226"
					( objectStatus "vdd(4)" )
				)
				( pin "J9U1.223"
					( objectStatus "vdd(5)" )
				)
				( pin "J9U1.220"
					( objectStatus "vdd(6)" )
				)
				( pin "J9U1.217"
					( objectStatus "vdd(7)" )
				)
				( pin "J9U1.215"
					( objectStatus "vdd(8)" )
				)
				( pin "J9U1.212"
					( objectStatus "vdd(9)" )
				)
				( pin "J9U1.209"
					( objectStatus "vdd(10)" )
				)
				( pin "J9U1.206"
					( objectStatus "vdd(11)" )
				)
				( pin "J9U1.204"
					( objectStatus "vdd(12)" )
				)
				( pin "J9U1.92"
					( objectStatus "vdd(13)" )
				)
				( pin "J9U1.90"
					( objectStatus "vdd(14)" )
				)
				( pin "J9U1.88"
					( objectStatus "vdd(15)" )
				)
				( pin "J9U1.85"
					( objectStatus "vdd(16)" )
				)
				( pin "J9U1.83"
					( objectStatus "vdd(17)" )
				)
				( pin "J9U1.80"
					( objectStatus "vdd(18)" )
				)
				( pin "J9U1.76"
					( objectStatus "vdd(19)" )
				)
				( pin "J9U1.73"
					( objectStatus "vdd(20)" )
				)
				( pin "J9U1.70"
					( objectStatus "vdd(21)" )
				)
				( pin "J9U1.67"
					( objectStatus "vdd(22)" )
				)
				( pin "J9U1.64"
					( objectStatus "vdd(23)" )
				)
				( pin "J9U1.61"
					( objectStatus "vdd(24)" )
				)
				( pin "J9U1.59"
					( objectStatus "vdd(25)" )
				)
				( pin "J9U1.287"
					( objectStatus "vpp(0)" )
				)
				( pin "J9U1.286"
					( objectStatus "vpp(1)" )
				)
				( pin "J9U1.288"
					( objectStatus "vpp(2)" )
				)
				( pin "J9U1.143"
					( objectStatus "vpp(3)" )
				)
				( pin "J9U1.142"
					( objectStatus "vpp(4)" )
				)
				( pin "J9U1.221"
					( objectStatus "vtt(0)" )
				)
				( pin "J9U1.77"
					( objectStatus "vtt(1)" )
				)
			)
			( gate "J9U1"
				( objectStatus "@baseboard_fab2_lib.baseboard_fab2(sch_1):page80_i101" )
				( pin "J9U1.152"
					( objectStatus "dqs0n" )
				)
				( pin "J9U1.153"
					( objectStatus "dqs0p" )
				)
				( pin "J9U1.163"
					( objectStatus "dqs1n" )
				)
				( pin "J9U1.164"
					( objectStatus "dqs1p" )
				)
				( pin "J9U1.174"
					( objectStatus "dqs2n" )
				)
				( pin "J9U1.175"
					( objectStatus "dqs2p" )
				)
				( pin "J9U1.185"
					( objectStatus "dqs3n" )
				)
				( pin "J9U1.186"
					( objectStatus "dqs3p" )
				)
				( pin "J9U1.244"
					( objectStatus "dqs4n" )
				)
				( pin "J9U1.245"
					( objectStatus "dqs4p" )
				)
				( pin "J9U1.255"
					( objectStatus "dqs5n" )
				)
				( pin "J9U1.256"
					( objectStatus "dqs5p" )
				)
				( pin "J9U1.266"
					( objectStatus "dqs6n" )
				)
				( pin "J9U1.267"
					( objectStatus "dqs6p" )
				)
				( pin "J9U1.277"
					( objectStatus "dqs7n" )
				)
				( pin "J9U1.278"
					( objectStatus "dqs7p" )
				)
				( pin "J9U1.196"
					( objectStatus "dqs8n" )
				)
				( pin "J9U1.197"
					( objectStatus "dqs8p" )
				)
				( pin "J9U1.8"
					( objectStatus "dqs9n" )
				)
				( pin "J9U1.7"
					( objectStatus "dqs9p" )
				)
				( pin "J9U1.19"
					( objectStatus "dqs10n" )
				)
				( pin "J9U1.18"
					( objectStatus "dqs10p" )
				)
				( pin "J9U1.30"
					( objectStatus "dqs11n" )
				)
				( pin "J9U1.29"
					( objectStatus "dqs11p" )
				)
				( pin "J9U1.41"
					( objectStatus "dqs12n" )
				)
				( pin "J9U1.40"
					( objectStatus "dqs12p" )
				)
				( pin "J9U1.100"
					( objectStatus "dqs13n" )
				)
				( pin "J9U1.99"
					( objectStatus "dqs13p" )
				)
				( pin "J9U1.111"
					( objectStatus "dqs14n" )
				)
				( pin "J9U1.110"
					( objectStatus "dqs14p" )
				)
				( pin "J9U1.122"
					( objectStatus "dqs15n" )
				)
				( pin "J9U1.121"
					( objectStatus "dqs15p" )
				)
				( pin "J9U1.133"
					( objectStatus "dqs16n" )
				)
				( pin "J9U1.132"
					( objectStatus "dqs16p" )
				)
				( pin "J9U1.52"
					( objectStatus "dqs17n" )
				)
				( pin "J9U1.51"
					( objectStatus "dqs17p" )
				)
			)
			( gate "J9U1"
				( objectStatus "@baseboard_fab2_lib.baseboard_fab2(sch_1):page80_i138" )
				( pin "J9U1.283"
					( objectStatus "vss(0)" )
				)
				( pin "J9U1.281"
					( objectStatus "vss(1)" )
				)
				( pin "J9U1.279"
					( objectStatus "vss(2)" )
				)
				( pin "J9U1.276"
					( objectStatus "vss(3)" )
				)
				( pin "J9U1.274"
					( objectStatus "vss(4)" )
				)
				( pin "J9U1.272"
					( objectStatus "vss(5)" )
				)
				( pin "J9U1.270"
					( objectStatus "vss(6)" )
				)
				( pin "J9U1.268"
					( objectStatus "vss(7)" )
				)
				( pin "J9U1.265"
					( objectStatus "vss(8)" )
				)
				( pin "J9U1.263"
					( objectStatus "vss(9)" )
				)
				( pin "J9U1.261"
					( objectStatus "vss(10)" )
				)
				( pin "J9U1.259"
					( objectStatus "vss(11)" )
				)
				( pin "J9U1.257"
					( objectStatus "vss(12)" )
				)
				( pin "J9U1.254"
					( objectStatus "vss(13)" )
				)
				( pin "J9U1.252"
					( objectStatus "vss(14)" )
				)
				( pin "J9U1.250"
					( objectStatus "vss(15)" )
				)
				( pin "J9U1.248"
					( objectStatus "vss(16)" )
				)
				( pin "J9U1.246"
					( objectStatus "vss(17)" )
				)
				( pin "J9U1.243"
					( objectStatus "vss(18)" )
				)
				( pin "J9U1.241"
					( objectStatus "vss(19)" )
				)
				( pin "J9U1.239"
					( objectStatus "vss(20)" )
				)
				( pin "J9U1.202"
					( objectStatus "vss(21)" )
				)
				( pin "J9U1.200"
					( objectStatus "vss(22)" )
				)
				( pin "J9U1.198"
					( objectStatus "vss(23)" )
				)
				( pin "J9U1.195"
					( objectStatus "vss(24)" )
				)
				( pin "J9U1.193"
					( objectStatus "vss(25)" )
				)
				( pin "J9U1.191"
					( objectStatus "vss(26)" )
				)
				( pin "J9U1.189"
					( objectStatus "vss(27)" )
				)
				( pin "J9U1.187"
					( objectStatus "vss(28)" )
				)
				( pin "J9U1.184"
					( objectStatus "vss(29)" )
				)
				( pin "J9U1.182"
					( objectStatus "vss(30)" )
				)
				( pin "J9U1.180"
					( objectStatus "vss(31)" )
				)
				( pin "J9U1.178"
					( objectStatus "vss(32)" )
				)
				( pin "J9U1.176"
					( objectStatus "vss(33)" )
				)
				( pin "J9U1.173"
					( objectStatus "vss(34)" )
				)
				( pin "J9U1.171"
					( objectStatus "vss(35)" )
				)
				( pin "J9U1.169"
					( objectStatus "vss(36)" )
				)
				( pin "J9U1.167"
					( objectStatus "vss(37)" )
				)
				( pin "J9U1.165"
					( objectStatus "vss(38)" )
				)
				( pin "J9U1.162"
					( objectStatus "vss(39)" )
				)
				( pin "J9U1.160"
					( objectStatus "vss(40)" )
				)
				( pin "J9U1.158"
					( objectStatus "vss(41)" )
				)
				( pin "J9U1.156"
					( objectStatus "vss(42)" )
				)
				( pin "J9U1.154"
					( objectStatus "vss(43)" )
				)
				( pin "J9U1.151"
					( objectStatus "vss(44)" )
				)
				( pin "J9U1.149"
					( objectStatus "vss(45)" )
				)
				( pin "J9U1.147"
					( objectStatus "vss(46)" )
				)
				( pin "J9U1.138"
					( objectStatus "vss(47)" )
				)
				( pin "J9U1.136"
					( objectStatus "vss(48)" )
				)
				( pin "J9U1.134"
					( objectStatus "vss(49)" )
				)
				( pin "J9U1.131"
					( objectStatus "vss(50)" )
				)
				( pin "J9U1.129"
					( objectStatus "vss(51)" )
				)
				( pin "J9U1.127"
					( objectStatus "vss(52)" )
				)
				( pin "J9U1.125"
					( objectStatus "vss(53)" )
				)
				( pin "J9U1.123"
					( objectStatus "vss(54)" )
				)
				( pin "J9U1.120"
					( objectStatus "vss(55)" )
				)
				( pin "J9U1.118"
					( objectStatus "vss(56)" )
				)
				( pin "J9U1.116"
					( objectStatus "vss(57)" )
				)
				( pin "J9U1.114"
					( objectStatus "vss(58)" )
				)
				( pin "J9U1.112"
					( objectStatus "vss(59)" )
				)
				( pin "J9U1.109"
					( objectStatus "vss(60)" )
				)
				( pin "J9U1.107"
					( objectStatus "vss(61)" )
				)
				( pin "J9U1.105"
					( objectStatus "vss(62)" )
				)
				( pin "J9U1.103"
					( objectStatus "vss(63)" )
				)
				( pin "J9U1.101"
					( objectStatus "vss(64)" )
				)
				( pin "J9U1.98"
					( objectStatus "vss(65)" )
				)
				( pin "J9U1.96"
					( objectStatus "vss(66)" )
				)
				( pin "J9U1.94"
					( objectStatus "vss(67)" )
				)
				( pin "J9U1.57"
					( objectStatus "vss(68)" )
				)
				( pin "J9U1.55"
					( objectStatus "vss(69)" )
				)
				( pin "J9U1.53"
					( objectStatus "vss(70)" )
				)
				( pin "J9U1.50"
					( objectStatus "vss(71)" )
				)
				( pin "J9U1.48"
					( objectStatus "vss(72)" )
				)
				( pin "J9U1.46"
					( objectStatus "vss(73)" )
				)
				( pin "J9U1.44"
					( objectStatus "vss(74)" )
				)
				( pin "J9U1.42"
					( objectStatus "vss(75)" )
				)
				( pin "J9U1.39"
					( objectStatus "vss(76)" )
				)
				( pin "J9U1.37"
					( objectStatus "vss(77)" )
				)
				( pin "J9U1.35"
					( objectStatus "vss(78)" )
				)
				( pin "J9U1.33"
					( objectStatus "vss(79)" )
				)
				( pin "J9U1.31"
					( objectStatus "vss(80)" )
				)
				( pin "J9U1.28"
					( objectStatus "vss(81)" )
				)
				( pin "J9U1.26"
					( objectStatus "vss(82)" )
				)
				( pin "J9U1.24"
					( objectStatus "vss(83)" )
				)
				( pin "J9U1.22"
					( objectStatus "vss(84)" )
				)
				( pin "J9U1.20"
					( objectStatus "vss(85)" )
				)
				( pin "J9U1.17"
					( objectStatus "vss(86)" )
				)
				( pin "J9U1.15"
					( objectStatus "vss(87)" )
				)
				( pin "J9U1.13"
					( objectStatus "vss(88)" )
				)
				( pin "J9U1.11"
					( objectStatus "vss(89)" )
				)
				( pin "J9U1.9"
					( objectStatus "vss(90)" )
				)
				( pin "J9U1.6"
					( objectStatus "vss(91)" )
				)
				( pin "J9U1.4"
					( objectStatus "vss(92)" )
				)
				( pin "J9U1.2"
					( objectStatus "vss(93)" )
				)
			)
			( gate "J1G3"
				( objectStatus "@baseboard_fab2_lib.baseboard_fab2(sch_1):page81_i67" )
				( pin "J1G3.152"
					( objectStatus "dqs0n" )
				)
				( pin "J1G3.153"
					( objectStatus "dqs0p" )
				)
				( pin "J1G3.163"
					( objectStatus "dqs1n" )
				)
				( pin "J1G3.164"
					( objectStatus "dqs1p" )
				)
				( pin "J1G3.174"
					( objectStatus "dqs2n" )
				)
				( pin "J1G3.175"
					( objectStatus "dqs2p" )
				)
				( pin "J1G3.185"
					( objectStatus "dqs3n" )
				)
				( pin "J1G3.186"
					( objectStatus "dqs3p" )
				)
				( pin "J1G3.244"
					( objectStatus "dqs4n" )
				)
				( pin "J1G3.245"
					( objectStatus "dqs4p" )
				)
				( pin "J1G3.255"
					( objectStatus "dqs5n" )
				)
				( pin "J1G3.256"
					( objectStatus "dqs5p" )
				)
				( pin "J1G3.266"
					( objectStatus "dqs6n" )
				)
				( pin "J1G3.267"
					( objectStatus "dqs6p" )
				)
				( pin "J1G3.277"
					( objectStatus "dqs7n" )
				)
				( pin "J1G3.278"
					( objectStatus "dqs7p" )
				)
				( pin "J1G3.196"
					( objectStatus "dqs8n" )
				)
				( pin "J1G3.197"
					( objectStatus "dqs8p" )
				)
				( pin "J1G3.8"
					( objectStatus "dqs9n" )
				)
				( pin "J1G3.7"
					( objectStatus "dqs9p" )
				)
				( pin "J1G3.19"
					( objectStatus "dqs10n" )
				)
				( pin "J1G3.18"
					( objectStatus "dqs10p" )
				)
				( pin "J1G3.30"
					( objectStatus "dqs11n" )
				)
				( pin "J1G3.29"
					( objectStatus "dqs11p" )
				)
				( pin "J1G3.41"
					( objectStatus "dqs12n" )
				)
				( pin "J1G3.40"
					( objectStatus "dqs12p" )
				)
				( pin "J1G3.100"
					( objectStatus "dqs13n" )
				)
				( pin "J1G3.99"
					( objectStatus "dqs13p" )
				)
				( pin "J1G3.111"
					( objectStatus "dqs14n" )
				)
				( pin "J1G3.110"
					( objectStatus "dqs14p" )
				)
				( pin "J1G3.122"
					( objectStatus "dqs15n" )
				)
				( pin "J1G3.121"
					( objectStatus "dqs15p" )
				)
				( pin "J1G3.133"
					( objectStatus "dqs16n" )
				)
				( pin "J1G3.132"
					( objectStatus "dqs16p" )
				)
				( pin "J1G3.52"
					( objectStatus "dqs17n" )
				)
				( pin "J1G3.51"
					( objectStatus "dqs17p" )
				)
			)
			( gate "J1G3"
				( objectStatus "@baseboard_fab2_lib.baseboard_fab2(sch_1):page81_i169" )
				( pin "J1G3.145"
					( objectStatus "\12v\(0)" )
				)
				( pin "J1G3.1"
					( objectStatus "\12v\(1)" )
				)
				( pin "J1G3.236"
					( objectStatus "vdd(0)" )
				)
				( pin "J1G3.233"
					( objectStatus "vdd(1)" )
				)
				( pin "J1G3.231"
					( objectStatus "vdd(2)" )
				)
				( pin "J1G3.229"
					( objectStatus "vdd(3)" )
				)
				( pin "J1G3.226"
					( objectStatus "vdd(4)" )
				)
				( pin "J1G3.223"
					( objectStatus "vdd(5)" )
				)
				( pin "J1G3.220"
					( objectStatus "vdd(6)" )
				)
				( pin "J1G3.217"
					( objectStatus "vdd(7)" )
				)
				( pin "J1G3.215"
					( objectStatus "vdd(8)" )
				)
				( pin "J1G3.212"
					( objectStatus "vdd(9)" )
				)
				( pin "J1G3.209"
					( objectStatus "vdd(10)" )
				)
				( pin "J1G3.206"
					( objectStatus "vdd(11)" )
				)
				( pin "J1G3.204"
					( objectStatus "vdd(12)" )
				)
				( pin "J1G3.92"
					( objectStatus "vdd(13)" )
				)
				( pin "J1G3.90"
					( objectStatus "vdd(14)" )
				)
				( pin "J1G3.88"
					( objectStatus "vdd(15)" )
				)
				( pin "J1G3.85"
					( objectStatus "vdd(16)" )
				)
				( pin "J1G3.83"
					( objectStatus "vdd(17)" )
				)
				( pin "J1G3.80"
					( objectStatus "vdd(18)" )
				)
				( pin "J1G3.76"
					( objectStatus "vdd(19)" )
				)
				( pin "J1G3.73"
					( objectStatus "vdd(20)" )
				)
				( pin "J1G3.70"
					( objectStatus "vdd(21)" )
				)
				( pin "J1G3.67"
					( objectStatus "vdd(22)" )
				)
				( pin "J1G3.64"
					( objectStatus "vdd(23)" )
				)
				( pin "J1G3.61"
					( objectStatus "vdd(24)" )
				)
				( pin "J1G3.59"
					( objectStatus "vdd(25)" )
				)
				( pin "J1G3.287"
					( objectStatus "vpp(0)" )
				)
				( pin "J1G3.286"
					( objectStatus "vpp(1)" )
				)
				( pin "J1G3.288"
					( objectStatus "vpp(2)" )
				)
				( pin "J1G3.143"
					( objectStatus "vpp(3)" )
				)
				( pin "J1G3.142"
					( objectStatus "vpp(4)" )
				)
				( pin "J1G3.221"
					( objectStatus "vtt(0)" )
				)
				( pin "J1G3.77"
					( objectStatus "vtt(1)" )
				)
			)
			( gate "C9U10"
				( objectStatus "@baseboard_fab2_lib.baseboard_fab2(sch_1):page81_i178" )
				( pin "C9U10.1"
					( objectStatus "a" )
				)
				( pin "C9U10.2"
					( objectStatus "b" )
				)
			)
			( gate "J1G3"
				( objectStatus "@baseboard_fab2_lib.baseboard_fab2(sch_1):page81_i185" )
				( pin "J1G3.283"
					( objectStatus "vss(0)" )
				)
				( pin "J1G3.281"
					( objectStatus "vss(1)" )
				)
				( pin "J1G3.279"
					( objectStatus "vss(2)" )
				)
				( pin "J1G3.276"
					( objectStatus "vss(3)" )
				)
				( pin "J1G3.274"
					( objectStatus "vss(4)" )
				)
				( pin "J1G3.272"
					( objectStatus "vss(5)" )
				)
				( pin "J1G3.270"
					( objectStatus "vss(6)" )
				)
				( pin "J1G3.268"
					( objectStatus "vss(7)" )
				)
				( pin "J1G3.265"
					( objectStatus "vss(8)" )
				)
				( pin "J1G3.263"
					( objectStatus "vss(9)" )
				)
				( pin "J1G3.261"
					( objectStatus "vss(10)" )
				)
				( pin "J1G3.259"
					( objectStatus "vss(11)" )
				)
				( pin "J1G3.257"
					( objectStatus "vss(12)" )
				)
				( pin "J1G3.254"
					( objectStatus "vss(13)" )
				)
				( pin "J1G3.252"
					( objectStatus "vss(14)" )
				)
				( pin "J1G3.250"
					( objectStatus "vss(15)" )
				)
				( pin "J1G3.248"
					( objectStatus "vss(16)" )
				)
				( pin "J1G3.246"
					( objectStatus "vss(17)" )
				)
				( pin "J1G3.243"
					( objectStatus "vss(18)" )
				)
				( pin "J1G3.241"
					( objectStatus "vss(19)" )
				)
				( pin "J1G3.239"
					( objectStatus "vss(20)" )
				)
				( pin "J1G3.202"
					( objectStatus "vss(21)" )
				)
				( pin "J1G3.200"
					( objectStatus "vss(22)" )
				)
				( pin "J1G3.198"
					( objectStatus "vss(23)" )
				)
				( pin "J1G3.195"
					( objectStatus "vss(24)" )
				)
				( pin "J1G3.193"
					( objectStatus "vss(25)" )
				)
				( pin "J1G3.191"
					( objectStatus "vss(26)" )
				)
				( pin "J1G3.189"
					( objectStatus "vss(27)" )
				)
				( pin "J1G3.187"
					( objectStatus "vss(28)" )
				)
				( pin "J1G3.184"
					( objectStatus "vss(29)" )
				)
				( pin "J1G3.182"
					( objectStatus "vss(30)" )
				)
				( pin "J1G3.180"
					( objectStatus "vss(31)" )
				)
				( pin "J1G3.178"
					( objectStatus "vss(32)" )
				)
				( pin "J1G3.176"
					( objectStatus "vss(33)" )
				)
				( pin "J1G3.173"
					( objectStatus "vss(34)" )
				)
				( pin "J1G3.171"
					( objectStatus "vss(35)" )
				)
				( pin "J1G3.169"
					( objectStatus "vss(36)" )
				)
				( pin "J1G3.167"
					( objectStatus "vss(37)" )
				)
				( pin "J1G3.165"
					( objectStatus "vss(38)" )
				)
				( pin "J1G3.162"
					( objectStatus "vss(39)" )
				)
				( pin "J1G3.160"
					( objectStatus "vss(40)" )
				)
				( pin "J1G3.158"
					( objectStatus "vss(41)" )
				)
				( pin "J1G3.156"
					( objectStatus "vss(42)" )
				)
				( pin "J1G3.154"
					( objectStatus "vss(43)" )
				)
				( pin "J1G3.151"
					( objectStatus "vss(44)" )
				)
				( pin "J1G3.149"
					( objectStatus "vss(45)" )
				)
				( pin "J1G3.147"
					( objectStatus "vss(46)" )
				)
				( pin "J1G3.138"
					( objectStatus "vss(47)" )
				)
				( pin "J1G3.136"
					( objectStatus "vss(48)" )
				)
				( pin "J1G3.134"
					( objectStatus "vss(49)" )
				)
				( pin "J1G3.131"
					( objectStatus "vss(50)" )
				)
				( pin "J1G3.129"
					( objectStatus "vss(51)" )
				)
				( pin "J1G3.127"
					( objectStatus "vss(52)" )
				)
				( pin "J1G3.125"
					( objectStatus "vss(53)" )
				)
				( pin "J1G3.123"
					( objectStatus "vss(54)" )
				)
				( pin "J1G3.120"
					( objectStatus "vss(55)" )
				)
				( pin "J1G3.118"
					( objectStatus "vss(56)" )
				)
				( pin "J1G3.116"
					( objectStatus "vss(57)" )
				)
				( pin "J1G3.114"
					( objectStatus "vss(58)" )
				)
				( pin "J1G3.112"
					( objectStatus "vss(59)" )
				)
				( pin "J1G3.109"
					( objectStatus "vss(60)" )
				)
				( pin "J1G3.107"
					( objectStatus "vss(61)" )
				)
				( pin "J1G3.105"
					( objectStatus "vss(62)" )
				)
				( pin "J1G3.103"
					( objectStatus "vss(63)" )
				)
				( pin "J1G3.101"
					( objectStatus "vss(64)" )
				)
				( pin "J1G3.98"
					( objectStatus "vss(65)" )
				)
				( pin "J1G3.96"
					( objectStatus "vss(66)" )
				)
				( pin "J1G3.94"
					( objectStatus "vss(67)" )
				)
				( pin "J1G3.57"
					( objectStatus "vss(68)" )
				)
				( pin "J1G3.55"
					( objectStatus "vss(69)" )
				)
				( pin "J1G3.53"
					( objectStatus "vss(70)" )
				)
				( pin "J1G3.50"
					( objectStatus "vss(71)" )
				)
				( pin "J1G3.48"
					( objectStatus "vss(72)" )
				)
				( pin "J1G3.46"
					( objectStatus "vss(73)" )
				)
				( pin "J1G3.44"
					( objectStatus "vss(74)" )
				)
				( pin "J1G3.42"
					( objectStatus "vss(75)" )
				)
				( pin "J1G3.39"
					( objectStatus "vss(76)" )
				)
				( pin "J1G3.37"
					( objectStatus "vss(77)" )
				)
				( pin "J1G3.35"
					( objectStatus "vss(78)" )
				)
				( pin "J1G3.33"
					( objectStatus "vss(79)" )
				)
				( pin "J1G3.31"
					( objectStatus "vss(80)" )
				)
				( pin "J1G3.28"
					( objectStatus "vss(81)" )
				)
				( pin "J1G3.26"
					( objectStatus "vss(82)" )
				)
				( pin "J1G3.24"
					( objectStatus "vss(83)" )
				)
				( pin "J1G3.22"
					( objectStatus "vss(84)" )
				)
				( pin "J1G3.20"
					( objectStatus "vss(85)" )
				)
				( pin "J1G3.17"
					( objectStatus "vss(86)" )
				)
				( pin "J1G3.15"
					( objectStatus "vss(87)" )
				)
				( pin "J1G3.13"
					( objectStatus "vss(88)" )
				)
				( pin "J1G3.11"
					( objectStatus "vss(89)" )
				)
				( pin "J1G3.9"
					( objectStatus "vss(90)" )
				)
				( pin "J1G3.6"
					( objectStatus "vss(91)" )
				)
				( pin "J1G3.4"
					( objectStatus "vss(92)" )
				)
				( pin "J1G3.2"
					( objectStatus "vss(93)" )
				)
			)
			( gate "J1G3"
				( objectStatus "@baseboard_fab2_lib.baseboard_fab2(sch_1):page81_i186" )
				( pin "J1G3.79"
					( objectStatus "a0" )
				)
				( pin "J1G3.72"
					( objectStatus "a1" )
				)
				( pin "J1G3.216"
					( objectStatus "a2" )
				)
				( pin "J1G3.71"
					( objectStatus "a3" )
				)
				( pin "J1G3.214"
					( objectStatus "a4" )
				)
				( pin "J1G3.213"
					( objectStatus "a5" )
				)
				( pin "J1G3.69"
					( objectStatus "a6" )
				)
				( pin "J1G3.211"
					( objectStatus "a7" )
				)
				( pin "J1G3.68"
					( objectStatus "a8" )
				)
				( pin "J1G3.66"
					( objectStatus "a9" )
				)
				( pin "J1G3.225"
					( objectStatus "a10" )
				)
				( pin "J1G3.210"
					( objectStatus "a11" )
				)
				( pin "J1G3.65"
					( objectStatus "a12" )
				)
				( pin "J1G3.232"
					( objectStatus "a13" )
				)
				( pin "J1G3.228"
					( objectStatus "a14_we_n" )
				)
				( pin "J1G3.86"
					( objectStatus "a15_cas_n" )
				)
				( pin "J1G3.82"
					( objectStatus "a16_ras_n" )
				)
				( pin "J1G3.234"
					( objectStatus "a17" )
				)
				( pin "J1G3.62"
					( objectStatus "act_n" )
				)
				( pin "J1G3.208"
					( objectStatus "alert_n" )
				)
				( pin "J1G3.81"
					( objectStatus "ba(0)" )
				)
				( pin "J1G3.224"
					( objectStatus "ba(1)" )
				)
				( pin "J1G3.63"
					( objectStatus "bg(0)" )
				)
				( pin "J1G3.207"
					( objectStatus "bg(1)" )
				)
				( pin "J1G3.235"
					( objectStatus "c(2)" )
				)
				( pin "J1G3.49"
					( objectStatus "cb(0)" )
				)
				( pin "J1G3.194"
					( objectStatus "cb(1)" )
				)
				( pin "J1G3.56"
					( objectStatus "cb(2)" )
				)
				( pin "J1G3.201"
					( objectStatus "cb(3)" )
				)
				( pin "J1G3.47"
					( objectStatus "cb(4)" )
				)
				( pin "J1G3.192"
					( objectStatus "cb(5)" )
				)
				( pin "J1G3.54"
					( objectStatus "cb(6)" )
				)
				( pin "J1G3.199"
					( objectStatus "cb(7)" )
				)
				( pin "J1G3.75"
					( objectStatus "ck0n" )
				)
				( pin "J1G3.74"
					( objectStatus "ck0p" )
				)
				( pin "J1G3.219"
					( objectStatus "ck1n" )
				)
				( pin "J1G3.218"
					( objectStatus "ck1p" )
				)
				( pin "J1G3.60"
					( objectStatus "cke(0)" )
				)
				( pin "J1G3.203"
					( objectStatus "cke(1)" )
				)
				( pin "J1G3.5"
					( objectStatus "dq(0)" )
				)
				( pin "J1G3.150"
					( objectStatus "dq(1)" )
				)
				( pin "J1G3.12"
					( objectStatus "dq(2)" )
				)
				( pin "J1G3.157"
					( objectStatus "dq(3)" )
				)
				( pin "J1G3.3"
					( objectStatus "dq(4)" )
				)
				( pin "J1G3.148"
					( objectStatus "dq(5)" )
				)
				( pin "J1G3.10"
					( objectStatus "dq(6)" )
				)
				( pin "J1G3.155"
					( objectStatus "dq(7)" )
				)
				( pin "J1G3.16"
					( objectStatus "dq(8)" )
				)
				( pin "J1G3.161"
					( objectStatus "dq(9)" )
				)
				( pin "J1G3.23"
					( objectStatus "dq(10)" )
				)
				( pin "J1G3.168"
					( objectStatus "dq(11)" )
				)
				( pin "J1G3.14"
					( objectStatus "dq(12)" )
				)
				( pin "J1G3.159"
					( objectStatus "dq(13)" )
				)
				( pin "J1G3.21"
					( objectStatus "dq(14)" )
				)
				( pin "J1G3.166"
					( objectStatus "dq(15)" )
				)
				( pin "J1G3.27"
					( objectStatus "dq(16)" )
				)
				( pin "J1G3.172"
					( objectStatus "dq(17)" )
				)
				( pin "J1G3.34"
					( objectStatus "dq(18)" )
				)
				( pin "J1G3.179"
					( objectStatus "dq(19)" )
				)
				( pin "J1G3.25"
					( objectStatus "dq(20)" )
				)
				( pin "J1G3.170"
					( objectStatus "dq(21)" )
				)
				( pin "J1G3.32"
					( objectStatus "dq(22)" )
				)
				( pin "J1G3.177"
					( objectStatus "dq(23)" )
				)
				( pin "J1G3.38"
					( objectStatus "dq(24)" )
				)
				( pin "J1G3.183"
					( objectStatus "dq(25)" )
				)
				( pin "J1G3.45"
					( objectStatus "dq(26)" )
				)
				( pin "J1G3.190"
					( objectStatus "dq(27)" )
				)
				( pin "J1G3.36"
					( objectStatus "dq(28)" )
				)
				( pin "J1G3.181"
					( objectStatus "dq(29)" )
				)
				( pin "J1G3.43"
					( objectStatus "dq(30)" )
				)
				( pin "J1G3.188"
					( objectStatus "dq(31)" )
				)
				( pin "J1G3.97"
					( objectStatus "dq(32)" )
				)
				( pin "J1G3.242"
					( objectStatus "dq(33)" )
				)
				( pin "J1G3.104"
					( objectStatus "dq(34)" )
				)
				( pin "J1G3.249"
					( objectStatus "dq(35)" )
				)
				( pin "J1G3.95"
					( objectStatus "dq(36)" )
				)
				( pin "J1G3.240"
					( objectStatus "dq(37)" )
				)
				( pin "J1G3.102"
					( objectStatus "dq(38)" )
				)
				( pin "J1G3.247"
					( objectStatus "dq(39)" )
				)
				( pin "J1G3.108"
					( objectStatus "dq(40)" )
				)
				( pin "J1G3.253"
					( objectStatus "dq(41)" )
				)
				( pin "J1G3.115"
					( objectStatus "dq(42)" )
				)
				( pin "J1G3.260"
					( objectStatus "dq(43)" )
				)
				( pin "J1G3.106"
					( objectStatus "dq(44)" )
				)
				( pin "J1G3.251"
					( objectStatus "dq(45)" )
				)
				( pin "J1G3.113"
					( objectStatus "dq(46)" )
				)
				( pin "J1G3.258"
					( objectStatus "dq(47)" )
				)
				( pin "J1G3.119"
					( objectStatus "dq(48)" )
				)
				( pin "J1G3.264"
					( objectStatus "dq(49)" )
				)
				( pin "J1G3.126"
					( objectStatus "dq(50)" )
				)
				( pin "J1G3.271"
					( objectStatus "dq(51)" )
				)
				( pin "J1G3.117"
					( objectStatus "dq(52)" )
				)
				( pin "J1G3.262"
					( objectStatus "dq(53)" )
				)
				( pin "J1G3.124"
					( objectStatus "dq(54)" )
				)
				( pin "J1G3.269"
					( objectStatus "dq(55)" )
				)
				( pin "J1G3.130"
					( objectStatus "dq(56)" )
				)
				( pin "J1G3.275"
					( objectStatus "dq(57)" )
				)
				( pin "J1G3.137"
					( objectStatus "dq(58)" )
				)
				( pin "J1G3.282"
					( objectStatus "dq(59)" )
				)
				( pin "J1G3.128"
					( objectStatus "dq(60)" )
				)
				( pin "J1G3.273"
					( objectStatus "dq(61)" )
				)
				( pin "J1G3.135"
					( objectStatus "dq(62)" )
				)
				( pin "J1G3.280"
					( objectStatus "dq(63)" )
				)
				( pin "J1G3.78"
					( objectStatus "event_n" )
				)
				( pin "J1G3.87"
					( objectStatus "odt(0)" )
				)
				( pin "J1G3.91"
					( objectStatus "odt(1)" )
				)
				( pin "J1G3.222"
					( objectStatus "par" )
				)
				( pin "J1G3.58"
					( objectStatus "reset_n" )
				)
				( pin "J1G3.205"
					( objectStatus "rfu(0)" )
				)
				( pin "J1G3.227"
					( objectStatus "rfu(1)" )
				)
				( pin "J1G3.144"
					( objectStatus "rfu(2)" )
				)
				( pin "J1G3.84"
					( objectStatus "s0_n" )
				)
				( pin "J1G3.89"
					( objectStatus "s1_n" )
				)
				( pin "J1G3.93"
					( objectStatus "s2_n_c(0)" )
				)
				( pin "J1G3.237"
					( objectStatus "s3_n_c(1)" )
				)
				( pin "J1G3.139"
					( objectStatus "sa(0)" )
				)
				( pin "J1G3.140"
					( objectStatus "sa(1)" )
				)
				( pin "J1G3.238"
					( objectStatus "sa(2)" )
				)
				( pin "J1G3.230"
					( objectStatus "save_n_nc" )
				)
				( pin "J1G3.141"
					( objectStatus "scl" )
				)
				( pin "J1G3.285"
					( objectStatus "sda" )
				)
				( pin "J1G3.284"
					( objectStatus "vddspd" )
				)
				( pin "J1G3.146"
					( objectStatus "vrefca" )
				)
			)
			( gate "J9U2"
				( objectStatus "@baseboard_fab2_lib.baseboard_fab2(sch_1):page82_i64" )
				( pin "J9U2.152"
					( objectStatus "dqs0n" )
				)
				( pin "J9U2.153"
					( objectStatus "dqs0p" )
				)
				( pin "J9U2.163"
					( objectStatus "dqs1n" )
				)
				( pin "J9U2.164"
					( objectStatus "dqs1p" )
				)
				( pin "J9U2.174"
					( objectStatus "dqs2n" )
				)
				( pin "J9U2.175"
					( objectStatus "dqs2p" )
				)
				( pin "J9U2.185"
					( objectStatus "dqs3n" )
				)
				( pin "J9U2.186"
					( objectStatus "dqs3p" )
				)
				( pin "J9U2.244"
					( objectStatus "dqs4n" )
				)
				( pin "J9U2.245"
					( objectStatus "dqs4p" )
				)
				( pin "J9U2.255"
					( objectStatus "dqs5n" )
				)
				( pin "J9U2.256"
					( objectStatus "dqs5p" )
				)
				( pin "J9U2.266"
					( objectStatus "dqs6n" )
				)
				( pin "J9U2.267"
					( objectStatus "dqs6p" )
				)
				( pin "J9U2.277"
					( objectStatus "dqs7n" )
				)
				( pin "J9U2.278"
					( objectStatus "dqs7p" )
				)
				( pin "J9U2.196"
					( objectStatus "dqs8n" )
				)
				( pin "J9U2.197"
					( objectStatus "dqs8p" )
				)
				( pin "J9U2.8"
					( objectStatus "dqs9n" )
				)
				( pin "J9U2.7"
					( objectStatus "dqs9p" )
				)
				( pin "J9U2.19"
					( objectStatus "dqs10n" )
				)
				( pin "J9U2.18"
					( objectStatus "dqs10p" )
				)
				( pin "J9U2.30"
					( objectStatus "dqs11n" )
				)
				( pin "J9U2.29"
					( objectStatus "dqs11p" )
				)
				( pin "J9U2.41"
					( objectStatus "dqs12n" )
				)
				( pin "J9U2.40"
					( objectStatus "dqs12p" )
				)
				( pin "J9U2.100"
					( objectStatus "dqs13n" )
				)
				( pin "J9U2.99"
					( objectStatus "dqs13p" )
				)
				( pin "J9U2.111"
					( objectStatus "dqs14n" )
				)
				( pin "J9U2.110"
					( objectStatus "dqs14p" )
				)
				( pin "J9U2.122"
					( objectStatus "dqs15n" )
				)
				( pin "J9U2.121"
					( objectStatus "dqs15p" )
				)
				( pin "J9U2.133"
					( objectStatus "dqs16n" )
				)
				( pin "J9U2.132"
					( objectStatus "dqs16p" )
				)
				( pin "J9U2.52"
					( objectStatus "dqs17n" )
				)
				( pin "J9U2.51"
					( objectStatus "dqs17p" )
				)
			)
			( gate "J9U2"
				( objectStatus "@baseboard_fab2_lib.baseboard_fab2(sch_1):page82_i171" )
				( pin "J9U2.145"
					( objectStatus "\12v\(0)" )
				)
				( pin "J9U2.1"
					( objectStatus "\12v\(1)" )
				)
				( pin "J9U2.236"
					( objectStatus "vdd(0)" )
				)
				( pin "J9U2.233"
					( objectStatus "vdd(1)" )
				)
				( pin "J9U2.231"
					( objectStatus "vdd(2)" )
				)
				( pin "J9U2.229"
					( objectStatus "vdd(3)" )
				)
				( pin "J9U2.226"
					( objectStatus "vdd(4)" )
				)
				( pin "J9U2.223"
					( objectStatus "vdd(5)" )
				)
				( pin "J9U2.220"
					( objectStatus "vdd(6)" )
				)
				( pin "J9U2.217"
					( objectStatus "vdd(7)" )
				)
				( pin "J9U2.215"
					( objectStatus "vdd(8)" )
				)
				( pin "J9U2.212"
					( objectStatus "vdd(9)" )
				)
				( pin "J9U2.209"
					( objectStatus "vdd(10)" )
				)
				( pin "J9U2.206"
					( objectStatus "vdd(11)" )
				)
				( pin "J9U2.204"
					( objectStatus "vdd(12)" )
				)
				( pin "J9U2.92"
					( objectStatus "vdd(13)" )
				)
				( pin "J9U2.90"
					( objectStatus "vdd(14)" )
				)
				( pin "J9U2.88"
					( objectStatus "vdd(15)" )
				)
				( pin "J9U2.85"
					( objectStatus "vdd(16)" )
				)
				( pin "J9U2.83"
					( objectStatus "vdd(17)" )
				)
				( pin "J9U2.80"
					( objectStatus "vdd(18)" )
				)
				( pin "J9U2.76"
					( objectStatus "vdd(19)" )
				)
				( pin "J9U2.73"
					( objectStatus "vdd(20)" )
				)
				( pin "J9U2.70"
					( objectStatus "vdd(21)" )
				)
				( pin "J9U2.67"
					( objectStatus "vdd(22)" )
				)
				( pin "J9U2.64"
					( objectStatus "vdd(23)" )
				)
				( pin "J9U2.61"
					( objectStatus "vdd(24)" )
				)
				( pin "J9U2.59"
					( objectStatus "vdd(25)" )
				)
				( pin "J9U2.287"
					( objectStatus "vpp(0)" )
				)
				( pin "J9U2.286"
					( objectStatus "vpp(1)" )
				)
				( pin "J9U2.288"
					( objectStatus "vpp(2)" )
				)
				( pin "J9U2.143"
					( objectStatus "vpp(3)" )
				)
				( pin "J9U2.142"
					( objectStatus "vpp(4)" )
				)
				( pin "J9U2.221"
					( objectStatus "vtt(0)" )
				)
				( pin "J9U2.77"
					( objectStatus "vtt(1)" )
				)
			)
			( gate "C1G19"
				( objectStatus "@baseboard_fab2_lib.baseboard_fab2(sch_1):page82_i180" )
				( pin "C1G19.1"
					( objectStatus "a" )
				)
				( pin "C1G19.2"
					( objectStatus "b" )
				)
			)
			( gate "J9U2"
				( objectStatus "@baseboard_fab2_lib.baseboard_fab2(sch_1):page82_i187" )
				( pin "J9U2.79"
					( objectStatus "a0" )
				)
				( pin "J9U2.72"
					( objectStatus "a1" )
				)
				( pin "J9U2.216"
					( objectStatus "a2" )
				)
				( pin "J9U2.71"
					( objectStatus "a3" )
				)
				( pin "J9U2.214"
					( objectStatus "a4" )
				)
				( pin "J9U2.213"
					( objectStatus "a5" )
				)
				( pin "J9U2.69"
					( objectStatus "a6" )
				)
				( pin "J9U2.211"
					( objectStatus "a7" )
				)
				( pin "J9U2.68"
					( objectStatus "a8" )
				)
				( pin "J9U2.66"
					( objectStatus "a9" )
				)
				( pin "J9U2.225"
					( objectStatus "a10" )
				)
				( pin "J9U2.210"
					( objectStatus "a11" )
				)
				( pin "J9U2.65"
					( objectStatus "a12" )
				)
				( pin "J9U2.232"
					( objectStatus "a13" )
				)
				( pin "J9U2.228"
					( objectStatus "a14_we_n" )
				)
				( pin "J9U2.86"
					( objectStatus "a15_cas_n" )
				)
				( pin "J9U2.82"
					( objectStatus "a16_ras_n" )
				)
				( pin "J9U2.234"
					( objectStatus "a17" )
				)
				( pin "J9U2.62"
					( objectStatus "act_n" )
				)
				( pin "J9U2.208"
					( objectStatus "alert_n" )
				)
				( pin "J9U2.81"
					( objectStatus "ba(0)" )
				)
				( pin "J9U2.224"
					( objectStatus "ba(1)" )
				)
				( pin "J9U2.63"
					( objectStatus "bg(0)" )
				)
				( pin "J9U2.207"
					( objectStatus "bg(1)" )
				)
				( pin "J9U2.235"
					( objectStatus "c(2)" )
				)
				( pin "J9U2.49"
					( objectStatus "cb(0)" )
				)
				( pin "J9U2.194"
					( objectStatus "cb(1)" )
				)
				( pin "J9U2.56"
					( objectStatus "cb(2)" )
				)
				( pin "J9U2.201"
					( objectStatus "cb(3)" )
				)
				( pin "J9U2.47"
					( objectStatus "cb(4)" )
				)
				( pin "J9U2.192"
					( objectStatus "cb(5)" )
				)
				( pin "J9U2.54"
					( objectStatus "cb(6)" )
				)
				( pin "J9U2.199"
					( objectStatus "cb(7)" )
				)
				( pin "J9U2.75"
					( objectStatus "ck0n" )
				)
				( pin "J9U2.74"
					( objectStatus "ck0p" )
				)
				( pin "J9U2.219"
					( objectStatus "ck1n" )
				)
				( pin "J9U2.218"
					( objectStatus "ck1p" )
				)
				( pin "J9U2.60"
					( objectStatus "cke(0)" )
				)
				( pin "J9U2.203"
					( objectStatus "cke(1)" )
				)
				( pin "J9U2.5"
					( objectStatus "dq(0)" )
				)
				( pin "J9U2.150"
					( objectStatus "dq(1)" )
				)
				( pin "J9U2.12"
					( objectStatus "dq(2)" )
				)
				( pin "J9U2.157"
					( objectStatus "dq(3)" )
				)
				( pin "J9U2.3"
					( objectStatus "dq(4)" )
				)
				( pin "J9U2.148"
					( objectStatus "dq(5)" )
				)
				( pin "J9U2.10"
					( objectStatus "dq(6)" )
				)
				( pin "J9U2.155"
					( objectStatus "dq(7)" )
				)
				( pin "J9U2.16"
					( objectStatus "dq(8)" )
				)
				( pin "J9U2.161"
					( objectStatus "dq(9)" )
				)
				( pin "J9U2.23"
					( objectStatus "dq(10)" )
				)
				( pin "J9U2.168"
					( objectStatus "dq(11)" )
				)
				( pin "J9U2.14"
					( objectStatus "dq(12)" )
				)
				( pin "J9U2.159"
					( objectStatus "dq(13)" )
				)
				( pin "J9U2.21"
					( objectStatus "dq(14)" )
				)
				( pin "J9U2.166"
					( objectStatus "dq(15)" )
				)
				( pin "J9U2.27"
					( objectStatus "dq(16)" )
				)
				( pin "J9U2.172"
					( objectStatus "dq(17)" )
				)
				( pin "J9U2.34"
					( objectStatus "dq(18)" )
				)
				( pin "J9U2.179"
					( objectStatus "dq(19)" )
				)
				( pin "J9U2.25"
					( objectStatus "dq(20)" )
				)
				( pin "J9U2.170"
					( objectStatus "dq(21)" )
				)
				( pin "J9U2.32"
					( objectStatus "dq(22)" )
				)
				( pin "J9U2.177"
					( objectStatus "dq(23)" )
				)
				( pin "J9U2.38"
					( objectStatus "dq(24)" )
				)
				( pin "J9U2.183"
					( objectStatus "dq(25)" )
				)
				( pin "J9U2.45"
					( objectStatus "dq(26)" )
				)
				( pin "J9U2.190"
					( objectStatus "dq(27)" )
				)
				( pin "J9U2.36"
					( objectStatus "dq(28)" )
				)
				( pin "J9U2.181"
					( objectStatus "dq(29)" )
				)
				( pin "J9U2.43"
					( objectStatus "dq(30)" )
				)
				( pin "J9U2.188"
					( objectStatus "dq(31)" )
				)
				( pin "J9U2.97"
					( objectStatus "dq(32)" )
				)
				( pin "J9U2.242"
					( objectStatus "dq(33)" )
				)
				( pin "J9U2.104"
					( objectStatus "dq(34)" )
				)
				( pin "J9U2.249"
					( objectStatus "dq(35)" )
				)
				( pin "J9U2.95"
					( objectStatus "dq(36)" )
				)
				( pin "J9U2.240"
					( objectStatus "dq(37)" )
				)
				( pin "J9U2.102"
					( objectStatus "dq(38)" )
				)
				( pin "J9U2.247"
					( objectStatus "dq(39)" )
				)
				( pin "J9U2.108"
					( objectStatus "dq(40)" )
				)
				( pin "J9U2.253"
					( objectStatus "dq(41)" )
				)
				( pin "J9U2.115"
					( objectStatus "dq(42)" )
				)
				( pin "J9U2.260"
					( objectStatus "dq(43)" )
				)
				( pin "J9U2.106"
					( objectStatus "dq(44)" )
				)
				( pin "J9U2.251"
					( objectStatus "dq(45)" )
				)
				( pin "J9U2.113"
					( objectStatus "dq(46)" )
				)
				( pin "J9U2.258"
					( objectStatus "dq(47)" )
				)
				( pin "J9U2.119"
					( objectStatus "dq(48)" )
				)
				( pin "J9U2.264"
					( objectStatus "dq(49)" )
				)
				( pin "J9U2.126"
					( objectStatus "dq(50)" )
				)
				( pin "J9U2.271"
					( objectStatus "dq(51)" )
				)
				( pin "J9U2.117"
					( objectStatus "dq(52)" )
				)
				( pin "J9U2.262"
					( objectStatus "dq(53)" )
				)
				( pin "J9U2.124"
					( objectStatus "dq(54)" )
				)
				( pin "J9U2.269"
					( objectStatus "dq(55)" )
				)
				( pin "J9U2.130"
					( objectStatus "dq(56)" )
				)
				( pin "J9U2.275"
					( objectStatus "dq(57)" )
				)
				( pin "J9U2.137"
					( objectStatus "dq(58)" )
				)
				( pin "J9U2.282"
					( objectStatus "dq(59)" )
				)
				( pin "J9U2.128"
					( objectStatus "dq(60)" )
				)
				( pin "J9U2.273"
					( objectStatus "dq(61)" )
				)
				( pin "J9U2.135"
					( objectStatus "dq(62)" )
				)
				( pin "J9U2.280"
					( objectStatus "dq(63)" )
				)
				( pin "J9U2.78"
					( objectStatus "event_n" )
				)
				( pin "J9U2.87"
					( objectStatus "odt(0)" )
				)
				( pin "J9U2.91"
					( objectStatus "odt(1)" )
				)
				( pin "J9U2.222"
					( objectStatus "par" )
				)
				( pin "J9U2.58"
					( objectStatus "reset_n" )
				)
				( pin "J9U2.205"
					( objectStatus "rfu(0)" )
				)
				( pin "J9U2.227"
					( objectStatus "rfu(1)" )
				)
				( pin "J9U2.144"
					( objectStatus "rfu(2)" )
				)
				( pin "J9U2.84"
					( objectStatus "s0_n" )
				)
				( pin "J9U2.89"
					( objectStatus "s1_n" )
				)
				( pin "J9U2.93"
					( objectStatus "s2_n_c(0)" )
				)
				( pin "J9U2.237"
					( objectStatus "s3_n_c(1)" )
				)
				( pin "J9U2.139"
					( objectStatus "sa(0)" )
				)
				( pin "J9U2.140"
					( objectStatus "sa(1)" )
				)
				( pin "J9U2.238"
					( objectStatus "sa(2)" )
				)
				( pin "J9U2.230"
					( objectStatus "save_n_nc" )
				)
				( pin "J9U2.141"
					( objectStatus "scl" )
				)
				( pin "J9U2.285"
					( objectStatus "sda" )
				)
				( pin "J9U2.284"
					( objectStatus "vddspd" )
				)
				( pin "J9U2.146"
					( objectStatus "vrefca" )
				)
			)
			( gate "J9U2"
				( objectStatus "@baseboard_fab2_lib.baseboard_fab2(sch_1):page82_i188" )
				( pin "J9U2.283"
					( objectStatus "vss(0)" )
				)
				( pin "J9U2.281"
					( objectStatus "vss(1)" )
				)
				( pin "J9U2.279"
					( objectStatus "vss(2)" )
				)
				( pin "J9U2.276"
					( objectStatus "vss(3)" )
				)
				( pin "J9U2.274"
					( objectStatus "vss(4)" )
				)
				( pin "J9U2.272"
					( objectStatus "vss(5)" )
				)
				( pin "J9U2.270"
					( objectStatus "vss(6)" )
				)
				( pin "J9U2.268"
					( objectStatus "vss(7)" )
				)
				( pin "J9U2.265"
					( objectStatus "vss(8)" )
				)
				( pin "J9U2.263"
					( objectStatus "vss(9)" )
				)
				( pin "J9U2.261"
					( objectStatus "vss(10)" )
				)
				( pin "J9U2.259"
					( objectStatus "vss(11)" )
				)
				( pin "J9U2.257"
					( objectStatus "vss(12)" )
				)
				( pin "J9U2.254"
					( objectStatus "vss(13)" )
				)
				( pin "J9U2.252"
					( objectStatus "vss(14)" )
				)
				( pin "J9U2.250"
					( objectStatus "vss(15)" )
				)
				( pin "J9U2.248"
					( objectStatus "vss(16)" )
				)
				( pin "J9U2.246"
					( objectStatus "vss(17)" )
				)
				( pin "J9U2.243"
					( objectStatus "vss(18)" )
				)
				( pin "J9U2.241"
					( objectStatus "vss(19)" )
				)
				( pin "J9U2.239"
					( objectStatus "vss(20)" )
				)
				( pin "J9U2.202"
					( objectStatus "vss(21)" )
				)
				( pin "J9U2.200"
					( objectStatus "vss(22)" )
				)
				( pin "J9U2.198"
					( objectStatus "vss(23)" )
				)
				( pin "J9U2.195"
					( objectStatus "vss(24)" )
				)
				( pin "J9U2.193"
					( objectStatus "vss(25)" )
				)
				( pin "J9U2.191"
					( objectStatus "vss(26)" )
				)
				( pin "J9U2.189"
					( objectStatus "vss(27)" )
				)
				( pin "J9U2.187"
					( objectStatus "vss(28)" )
				)
				( pin "J9U2.184"
					( objectStatus "vss(29)" )
				)
				( pin "J9U2.182"
					( objectStatus "vss(30)" )
				)
				( pin "J9U2.180"
					( objectStatus "vss(31)" )
				)
				( pin "J9U2.178"
					( objectStatus "vss(32)" )
				)
				( pin "J9U2.176"
					( objectStatus "vss(33)" )
				)
				( pin "J9U2.173"
					( objectStatus "vss(34)" )
				)
				( pin "J9U2.171"
					( objectStatus "vss(35)" )
				)
				( pin "J9U2.169"
					( objectStatus "vss(36)" )
				)
				( pin "J9U2.167"
					( objectStatus "vss(37)" )
				)
				( pin "J9U2.165"
					( objectStatus "vss(38)" )
				)
				( pin "J9U2.162"
					( objectStatus "vss(39)" )
				)
				( pin "J9U2.160"
					( objectStatus "vss(40)" )
				)
				( pin "J9U2.158"
					( objectStatus "vss(41)" )
				)
				( pin "J9U2.156"
					( objectStatus "vss(42)" )
				)
				( pin "J9U2.154"
					( objectStatus "vss(43)" )
				)
				( pin "J9U2.151"
					( objectStatus "vss(44)" )
				)
				( pin "J9U2.149"
					( objectStatus "vss(45)" )
				)
				( pin "J9U2.147"
					( objectStatus "vss(46)" )
				)
				( pin "J9U2.138"
					( objectStatus "vss(47)" )
				)
				( pin "J9U2.136"
					( objectStatus "vss(48)" )
				)
				( pin "J9U2.134"
					( objectStatus "vss(49)" )
				)
				( pin "J9U2.131"
					( objectStatus "vss(50)" )
				)
				( pin "J9U2.129"
					( objectStatus "vss(51)" )
				)
				( pin "J9U2.127"
					( objectStatus "vss(52)" )
				)
				( pin "J9U2.125"
					( objectStatus "vss(53)" )
				)
				( pin "J9U2.123"
					( objectStatus "vss(54)" )
				)
				( pin "J9U2.120"
					( objectStatus "vss(55)" )
				)
				( pin "J9U2.118"
					( objectStatus "vss(56)" )
				)
				( pin "J9U2.116"
					( objectStatus "vss(57)" )
				)
				( pin "J9U2.114"
					( objectStatus "vss(58)" )
				)
				( pin "J9U2.112"
					( objectStatus "vss(59)" )
				)
				( pin "J9U2.109"
					( objectStatus "vss(60)" )
				)
				( pin "J9U2.107"
					( objectStatus "vss(61)" )
				)
				( pin "J9U2.105"
					( objectStatus "vss(62)" )
				)
				( pin "J9U2.103"
					( objectStatus "vss(63)" )
				)
				( pin "J9U2.101"
					( objectStatus "vss(64)" )
				)
				( pin "J9U2.98"
					( objectStatus "vss(65)" )
				)
				( pin "J9U2.96"
					( objectStatus "vss(66)" )
				)
				( pin "J9U2.94"
					( objectStatus "vss(67)" )
				)
				( pin "J9U2.57"
					( objectStatus "vss(68)" )
				)
				( pin "J9U2.55"
					( objectStatus "vss(69)" )
				)
				( pin "J9U2.53"
					( objectStatus "vss(70)" )
				)
				( pin "J9U2.50"
					( objectStatus "vss(71)" )
				)
				( pin "J9U2.48"
					( objectStatus "vss(72)" )
				)
				( pin "J9U2.46"
					( objectStatus "vss(73)" )
				)
				( pin "J9U2.44"
					( objectStatus "vss(74)" )
				)
				( pin "J9U2.42"
					( objectStatus "vss(75)" )
				)
				( pin "J9U2.39"
					( objectStatus "vss(76)" )
				)
				( pin "J9U2.37"
					( objectStatus "vss(77)" )
				)
				( pin "J9U2.35"
					( objectStatus "vss(78)" )
				)
				( pin "J9U2.33"
					( objectStatus "vss(79)" )
				)
				( pin "J9U2.31"
					( objectStatus "vss(80)" )
				)
				( pin "J9U2.28"
					( objectStatus "vss(81)" )
				)
				( pin "J9U2.26"
					( objectStatus "vss(82)" )
				)
				( pin "J9U2.24"
					( objectStatus "vss(83)" )
				)
				( pin "J9U2.22"
					( objectStatus "vss(84)" )
				)
				( pin "J9U2.20"
					( objectStatus "vss(85)" )
				)
				( pin "J9U2.17"
					( objectStatus "vss(86)" )
				)
				( pin "J9U2.15"
					( objectStatus "vss(87)" )
				)
				( pin "J9U2.13"
					( objectStatus "vss(88)" )
				)
				( pin "J9U2.11"
					( objectStatus "vss(89)" )
				)
				( pin "J9U2.9"
					( objectStatus "vss(90)" )
				)
				( pin "J9U2.6"
					( objectStatus "vss(91)" )
				)
				( pin "J9U2.4"
					( objectStatus "vss(92)" )
				)
				( pin "J9U2.2"
					( objectStatus "vss(93)" )
				)
			)
			( gate "J1B1"
				( objectStatus "@baseboard_fab2_lib.baseboard_fab2(sch_1):page83_i43" )
				( pin "J1B1.283"
					( objectStatus "vss(0)" )
				)
				( pin "J1B1.281"
					( objectStatus "vss(1)" )
				)
				( pin "J1B1.279"
					( objectStatus "vss(2)" )
				)
				( pin "J1B1.276"
					( objectStatus "vss(3)" )
				)
				( pin "J1B1.274"
					( objectStatus "vss(4)" )
				)
				( pin "J1B1.272"
					( objectStatus "vss(5)" )
				)
				( pin "J1B1.270"
					( objectStatus "vss(6)" )
				)
				( pin "J1B1.268"
					( objectStatus "vss(7)" )
				)
				( pin "J1B1.265"
					( objectStatus "vss(8)" )
				)
				( pin "J1B1.263"
					( objectStatus "vss(9)" )
				)
				( pin "J1B1.261"
					( objectStatus "vss(10)" )
				)
				( pin "J1B1.259"
					( objectStatus "vss(11)" )
				)
				( pin "J1B1.257"
					( objectStatus "vss(12)" )
				)
				( pin "J1B1.254"
					( objectStatus "vss(13)" )
				)
				( pin "J1B1.252"
					( objectStatus "vss(14)" )
				)
				( pin "J1B1.250"
					( objectStatus "vss(15)" )
				)
				( pin "J1B1.248"
					( objectStatus "vss(16)" )
				)
				( pin "J1B1.246"
					( objectStatus "vss(17)" )
				)
				( pin "J1B1.243"
					( objectStatus "vss(18)" )
				)
				( pin "J1B1.241"
					( objectStatus "vss(19)" )
				)
				( pin "J1B1.239"
					( objectStatus "vss(20)" )
				)
				( pin "J1B1.202"
					( objectStatus "vss(21)" )
				)
				( pin "J1B1.200"
					( objectStatus "vss(22)" )
				)
				( pin "J1B1.198"
					( objectStatus "vss(23)" )
				)
				( pin "J1B1.195"
					( objectStatus "vss(24)" )
				)
				( pin "J1B1.193"
					( objectStatus "vss(25)" )
				)
				( pin "J1B1.191"
					( objectStatus "vss(26)" )
				)
				( pin "J1B1.189"
					( objectStatus "vss(27)" )
				)
				( pin "J1B1.187"
					( objectStatus "vss(28)" )
				)
				( pin "J1B1.184"
					( objectStatus "vss(29)" )
				)
				( pin "J1B1.182"
					( objectStatus "vss(30)" )
				)
				( pin "J1B1.180"
					( objectStatus "vss(31)" )
				)
				( pin "J1B1.178"
					( objectStatus "vss(32)" )
				)
				( pin "J1B1.176"
					( objectStatus "vss(33)" )
				)
				( pin "J1B1.173"
					( objectStatus "vss(34)" )
				)
				( pin "J1B1.171"
					( objectStatus "vss(35)" )
				)
				( pin "J1B1.169"
					( objectStatus "vss(36)" )
				)
				( pin "J1B1.167"
					( objectStatus "vss(37)" )
				)
				( pin "J1B1.165"
					( objectStatus "vss(38)" )
				)
				( pin "J1B1.162"
					( objectStatus "vss(39)" )
				)
				( pin "J1B1.160"
					( objectStatus "vss(40)" )
				)
				( pin "J1B1.158"
					( objectStatus "vss(41)" )
				)
				( pin "J1B1.156"
					( objectStatus "vss(42)" )
				)
				( pin "J1B1.154"
					( objectStatus "vss(43)" )
				)
				( pin "J1B1.151"
					( objectStatus "vss(44)" )
				)
				( pin "J1B1.149"
					( objectStatus "vss(45)" )
				)
				( pin "J1B1.147"
					( objectStatus "vss(46)" )
				)
				( pin "J1B1.138"
					( objectStatus "vss(47)" )
				)
				( pin "J1B1.136"
					( objectStatus "vss(48)" )
				)
				( pin "J1B1.134"
					( objectStatus "vss(49)" )
				)
				( pin "J1B1.131"
					( objectStatus "vss(50)" )
				)
				( pin "J1B1.129"
					( objectStatus "vss(51)" )
				)
				( pin "J1B1.127"
					( objectStatus "vss(52)" )
				)
				( pin "J1B1.125"
					( objectStatus "vss(53)" )
				)
				( pin "J1B1.123"
					( objectStatus "vss(54)" )
				)
				( pin "J1B1.120"
					( objectStatus "vss(55)" )
				)
				( pin "J1B1.118"
					( objectStatus "vss(56)" )
				)
				( pin "J1B1.116"
					( objectStatus "vss(57)" )
				)
				( pin "J1B1.114"
					( objectStatus "vss(58)" )
				)
				( pin "J1B1.112"
					( objectStatus "vss(59)" )
				)
				( pin "J1B1.109"
					( objectStatus "vss(60)" )
				)
				( pin "J1B1.107"
					( objectStatus "vss(61)" )
				)
				( pin "J1B1.105"
					( objectStatus "vss(62)" )
				)
				( pin "J1B1.103"
					( objectStatus "vss(63)" )
				)
				( pin "J1B1.101"
					( objectStatus "vss(64)" )
				)
				( pin "J1B1.98"
					( objectStatus "vss(65)" )
				)
				( pin "J1B1.96"
					( objectStatus "vss(66)" )
				)
				( pin "J1B1.94"
					( objectStatus "vss(67)" )
				)
				( pin "J1B1.57"
					( objectStatus "vss(68)" )
				)
				( pin "J1B1.55"
					( objectStatus "vss(69)" )
				)
				( pin "J1B1.53"
					( objectStatus "vss(70)" )
				)
				( pin "J1B1.50"
					( objectStatus "vss(71)" )
				)
				( pin "J1B1.48"
					( objectStatus "vss(72)" )
				)
				( pin "J1B1.46"
					( objectStatus "vss(73)" )
				)
				( pin "J1B1.44"
					( objectStatus "vss(74)" )
				)
				( pin "J1B1.42"
					( objectStatus "vss(75)" )
				)
				( pin "J1B1.39"
					( objectStatus "vss(76)" )
				)
				( pin "J1B1.37"
					( objectStatus "vss(77)" )
				)
				( pin "J1B1.35"
					( objectStatus "vss(78)" )
				)
				( pin "J1B1.33"
					( objectStatus "vss(79)" )
				)
				( pin "J1B1.31"
					( objectStatus "vss(80)" )
				)
				( pin "J1B1.28"
					( objectStatus "vss(81)" )
				)
				( pin "J1B1.26"
					( objectStatus "vss(82)" )
				)
				( pin "J1B1.24"
					( objectStatus "vss(83)" )
				)
				( pin "J1B1.22"
					( objectStatus "vss(84)" )
				)
				( pin "J1B1.20"
					( objectStatus "vss(85)" )
				)
				( pin "J1B1.17"
					( objectStatus "vss(86)" )
				)
				( pin "J1B1.15"
					( objectStatus "vss(87)" )
				)
				( pin "J1B1.13"
					( objectStatus "vss(88)" )
				)
				( pin "J1B1.11"
					( objectStatus "vss(89)" )
				)
				( pin "J1B1.9"
					( objectStatus "vss(90)" )
				)
				( pin "J1B1.6"
					( objectStatus "vss(91)" )
				)
				( pin "J1B1.4"
					( objectStatus "vss(92)" )
				)
				( pin "J1B1.2"
					( objectStatus "vss(93)" )
				)
			)
			( gate "J1B1"
				( objectStatus "@baseboard_fab2_lib.baseboard_fab2(sch_1):page83_i66" )
				( pin "J1B1.152"
					( objectStatus "dqs0n" )
				)
				( pin "J1B1.153"
					( objectStatus "dqs0p" )
				)
				( pin "J1B1.163"
					( objectStatus "dqs1n" )
				)
				( pin "J1B1.164"
					( objectStatus "dqs1p" )
				)
				( pin "J1B1.174"
					( objectStatus "dqs2n" )
				)
				( pin "J1B1.175"
					( objectStatus "dqs2p" )
				)
				( pin "J1B1.185"
					( objectStatus "dqs3n" )
				)
				( pin "J1B1.186"
					( objectStatus "dqs3p" )
				)
				( pin "J1B1.244"
					( objectStatus "dqs4n" )
				)
				( pin "J1B1.245"
					( objectStatus "dqs4p" )
				)
				( pin "J1B1.255"
					( objectStatus "dqs5n" )
				)
				( pin "J1B1.256"
					( objectStatus "dqs5p" )
				)
				( pin "J1B1.266"
					( objectStatus "dqs6n" )
				)
				( pin "J1B1.267"
					( objectStatus "dqs6p" )
				)
				( pin "J1B1.277"
					( objectStatus "dqs7n" )
				)
				( pin "J1B1.278"
					( objectStatus "dqs7p" )
				)
				( pin "J1B1.196"
					( objectStatus "dqs8n" )
				)
				( pin "J1B1.197"
					( objectStatus "dqs8p" )
				)
				( pin "J1B1.8"
					( objectStatus "dqs9n" )
				)
				( pin "J1B1.7"
					( objectStatus "dqs9p" )
				)
				( pin "J1B1.19"
					( objectStatus "dqs10n" )
				)
				( pin "J1B1.18"
					( objectStatus "dqs10p" )
				)
				( pin "J1B1.30"
					( objectStatus "dqs11n" )
				)
				( pin "J1B1.29"
					( objectStatus "dqs11p" )
				)
				( pin "J1B1.41"
					( objectStatus "dqs12n" )
				)
				( pin "J1B1.40"
					( objectStatus "dqs12p" )
				)
				( pin "J1B1.100"
					( objectStatus "dqs13n" )
				)
				( pin "J1B1.99"
					( objectStatus "dqs13p" )
				)
				( pin "J1B1.111"
					( objectStatus "dqs14n" )
				)
				( pin "J1B1.110"
					( objectStatus "dqs14p" )
				)
				( pin "J1B1.122"
					( objectStatus "dqs15n" )
				)
				( pin "J1B1.121"
					( objectStatus "dqs15p" )
				)
				( pin "J1B1.133"
					( objectStatus "dqs16n" )
				)
				( pin "J1B1.132"
					( objectStatus "dqs16p" )
				)
				( pin "J1B1.52"
					( objectStatus "dqs17n" )
				)
				( pin "J1B1.51"
					( objectStatus "dqs17p" )
				)
			)
			( gate "J1B1"
				( objectStatus "@baseboard_fab2_lib.baseboard_fab2(sch_1):page83_i111" )
				( pin "J1B1.79"
					( objectStatus "a0" )
				)
				( pin "J1B1.72"
					( objectStatus "a1" )
				)
				( pin "J1B1.216"
					( objectStatus "a2" )
				)
				( pin "J1B1.71"
					( objectStatus "a3" )
				)
				( pin "J1B1.214"
					( objectStatus "a4" )
				)
				( pin "J1B1.213"
					( objectStatus "a5" )
				)
				( pin "J1B1.69"
					( objectStatus "a6" )
				)
				( pin "J1B1.211"
					( objectStatus "a7" )
				)
				( pin "J1B1.68"
					( objectStatus "a8" )
				)
				( pin "J1B1.66"
					( objectStatus "a9" )
				)
				( pin "J1B1.225"
					( objectStatus "a10" )
				)
				( pin "J1B1.210"
					( objectStatus "a11" )
				)
				( pin "J1B1.65"
					( objectStatus "a12" )
				)
				( pin "J1B1.232"
					( objectStatus "a13" )
				)
				( pin "J1B1.228"
					( objectStatus "a14_we_n" )
				)
				( pin "J1B1.86"
					( objectStatus "a15_cas_n" )
				)
				( pin "J1B1.82"
					( objectStatus "a16_ras_n" )
				)
				( pin "J1B1.234"
					( objectStatus "a17" )
				)
				( pin "J1B1.62"
					( objectStatus "act_n" )
				)
				( pin "J1B1.208"
					( objectStatus "alert_n" )
				)
				( pin "J1B1.81"
					( objectStatus "ba(0)" )
				)
				( pin "J1B1.224"
					( objectStatus "ba(1)" )
				)
				( pin "J1B1.63"
					( objectStatus "bg(0)" )
				)
				( pin "J1B1.207"
					( objectStatus "bg(1)" )
				)
				( pin "J1B1.235"
					( objectStatus "c(2)" )
				)
				( pin "J1B1.49"
					( objectStatus "cb(0)" )
				)
				( pin "J1B1.194"
					( objectStatus "cb(1)" )
				)
				( pin "J1B1.56"
					( objectStatus "cb(2)" )
				)
				( pin "J1B1.201"
					( objectStatus "cb(3)" )
				)
				( pin "J1B1.47"
					( objectStatus "cb(4)" )
				)
				( pin "J1B1.192"
					( objectStatus "cb(5)" )
				)
				( pin "J1B1.54"
					( objectStatus "cb(6)" )
				)
				( pin "J1B1.199"
					( objectStatus "cb(7)" )
				)
				( pin "J1B1.75"
					( objectStatus "ck0n" )
				)
				( pin "J1B1.74"
					( objectStatus "ck0p" )
				)
				( pin "J1B1.219"
					( objectStatus "ck1n" )
				)
				( pin "J1B1.218"
					( objectStatus "ck1p" )
				)
				( pin "J1B1.60"
					( objectStatus "cke(0)" )
				)
				( pin "J1B1.203"
					( objectStatus "cke(1)" )
				)
				( pin "J1B1.5"
					( objectStatus "dq(0)" )
				)
				( pin "J1B1.150"
					( objectStatus "dq(1)" )
				)
				( pin "J1B1.12"
					( objectStatus "dq(2)" )
				)
				( pin "J1B1.157"
					( objectStatus "dq(3)" )
				)
				( pin "J1B1.3"
					( objectStatus "dq(4)" )
				)
				( pin "J1B1.148"
					( objectStatus "dq(5)" )
				)
				( pin "J1B1.10"
					( objectStatus "dq(6)" )
				)
				( pin "J1B1.155"
					( objectStatus "dq(7)" )
				)
				( pin "J1B1.16"
					( objectStatus "dq(8)" )
				)
				( pin "J1B1.161"
					( objectStatus "dq(9)" )
				)
				( pin "J1B1.23"
					( objectStatus "dq(10)" )
				)
				( pin "J1B1.168"
					( objectStatus "dq(11)" )
				)
				( pin "J1B1.14"
					( objectStatus "dq(12)" )
				)
				( pin "J1B1.159"
					( objectStatus "dq(13)" )
				)
				( pin "J1B1.21"
					( objectStatus "dq(14)" )
				)
				( pin "J1B1.166"
					( objectStatus "dq(15)" )
				)
				( pin "J1B1.27"
					( objectStatus "dq(16)" )
				)
				( pin "J1B1.172"
					( objectStatus "dq(17)" )
				)
				( pin "J1B1.34"
					( objectStatus "dq(18)" )
				)
				( pin "J1B1.179"
					( objectStatus "dq(19)" )
				)
				( pin "J1B1.25"
					( objectStatus "dq(20)" )
				)
				( pin "J1B1.170"
					( objectStatus "dq(21)" )
				)
				( pin "J1B1.32"
					( objectStatus "dq(22)" )
				)
				( pin "J1B1.177"
					( objectStatus "dq(23)" )
				)
				( pin "J1B1.38"
					( objectStatus "dq(24)" )
				)
				( pin "J1B1.183"
					( objectStatus "dq(25)" )
				)
				( pin "J1B1.45"
					( objectStatus "dq(26)" )
				)
				( pin "J1B1.190"
					( objectStatus "dq(27)" )
				)
				( pin "J1B1.36"
					( objectStatus "dq(28)" )
				)
				( pin "J1B1.181"
					( objectStatus "dq(29)" )
				)
				( pin "J1B1.43"
					( objectStatus "dq(30)" )
				)
				( pin "J1B1.188"
					( objectStatus "dq(31)" )
				)
				( pin "J1B1.97"
					( objectStatus "dq(32)" )
				)
				( pin "J1B1.242"
					( objectStatus "dq(33)" )
				)
				( pin "J1B1.104"
					( objectStatus "dq(34)" )
				)
				( pin "J1B1.249"
					( objectStatus "dq(35)" )
				)
				( pin "J1B1.95"
					( objectStatus "dq(36)" )
				)
				( pin "J1B1.240"
					( objectStatus "dq(37)" )
				)
				( pin "J1B1.102"
					( objectStatus "dq(38)" )
				)
				( pin "J1B1.247"
					( objectStatus "dq(39)" )
				)
				( pin "J1B1.108"
					( objectStatus "dq(40)" )
				)
				( pin "J1B1.253"
					( objectStatus "dq(41)" )
				)
				( pin "J1B1.115"
					( objectStatus "dq(42)" )
				)
				( pin "J1B1.260"
					( objectStatus "dq(43)" )
				)
				( pin "J1B1.106"
					( objectStatus "dq(44)" )
				)
				( pin "J1B1.251"
					( objectStatus "dq(45)" )
				)
				( pin "J1B1.113"
					( objectStatus "dq(46)" )
				)
				( pin "J1B1.258"
					( objectStatus "dq(47)" )
				)
				( pin "J1B1.119"
					( objectStatus "dq(48)" )
				)
				( pin "J1B1.264"
					( objectStatus "dq(49)" )
				)
				( pin "J1B1.126"
					( objectStatus "dq(50)" )
				)
				( pin "J1B1.271"
					( objectStatus "dq(51)" )
				)
				( pin "J1B1.117"
					( objectStatus "dq(52)" )
				)
				( pin "J1B1.262"
					( objectStatus "dq(53)" )
				)
				( pin "J1B1.124"
					( objectStatus "dq(54)" )
				)
				( pin "J1B1.269"
					( objectStatus "dq(55)" )
				)
				( pin "J1B1.130"
					( objectStatus "dq(56)" )
				)
				( pin "J1B1.275"
					( objectStatus "dq(57)" )
				)
				( pin "J1B1.137"
					( objectStatus "dq(58)" )
				)
				( pin "J1B1.282"
					( objectStatus "dq(59)" )
				)
				( pin "J1B1.128"
					( objectStatus "dq(60)" )
				)
				( pin "J1B1.273"
					( objectStatus "dq(61)" )
				)
				( pin "J1B1.135"
					( objectStatus "dq(62)" )
				)
				( pin "J1B1.280"
					( objectStatus "dq(63)" )
				)
				( pin "J1B1.78"
					( objectStatus "event_n" )
				)
				( pin "J1B1.87"
					( objectStatus "odt(0)" )
				)
				( pin "J1B1.91"
					( objectStatus "odt(1)" )
				)
				( pin "J1B1.222"
					( objectStatus "par" )
				)
				( pin "J1B1.58"
					( objectStatus "reset_n" )
				)
				( pin "J1B1.205"
					( objectStatus "rfu(0)" )
				)
				( pin "J1B1.227"
					( objectStatus "rfu(1)" )
				)
				( pin "J1B1.144"
					( objectStatus "rfu(2)" )
				)
				( pin "J1B1.84"
					( objectStatus "s0_n" )
				)
				( pin "J1B1.89"
					( objectStatus "s1_n" )
				)
				( pin "J1B1.93"
					( objectStatus "s2_n_c(0)" )
				)
				( pin "J1B1.237"
					( objectStatus "s3_n_c(1)" )
				)
				( pin "J1B1.139"
					( objectStatus "sa(0)" )
				)
				( pin "J1B1.140"
					( objectStatus "sa(1)" )
				)
				( pin "J1B1.238"
					( objectStatus "sa(2)" )
				)
				( pin "J1B1.230"
					( objectStatus "save_n_nc" )
				)
				( pin "J1B1.141"
					( objectStatus "scl" )
				)
				( pin "J1B1.285"
					( objectStatus "sda" )
				)
				( pin "J1B1.284"
					( objectStatus "vddspd" )
				)
				( pin "J1B1.146"
					( objectStatus "vrefca" )
				)
			)
			( gate "J1B1"
				( objectStatus "@baseboard_fab2_lib.baseboard_fab2(sch_1):page83_i167" )
				( pin "J1B1.145"
					( objectStatus "\12v\(0)" )
				)
				( pin "J1B1.1"
					( objectStatus "\12v\(1)" )
				)
				( pin "J1B1.236"
					( objectStatus "vdd(0)" )
				)
				( pin "J1B1.233"
					( objectStatus "vdd(1)" )
				)
				( pin "J1B1.231"
					( objectStatus "vdd(2)" )
				)
				( pin "J1B1.229"
					( objectStatus "vdd(3)" )
				)
				( pin "J1B1.226"
					( objectStatus "vdd(4)" )
				)
				( pin "J1B1.223"
					( objectStatus "vdd(5)" )
				)
				( pin "J1B1.220"
					( objectStatus "vdd(6)" )
				)
				( pin "J1B1.217"
					( objectStatus "vdd(7)" )
				)
				( pin "J1B1.215"
					( objectStatus "vdd(8)" )
				)
				( pin "J1B1.212"
					( objectStatus "vdd(9)" )
				)
				( pin "J1B1.209"
					( objectStatus "vdd(10)" )
				)
				( pin "J1B1.206"
					( objectStatus "vdd(11)" )
				)
				( pin "J1B1.204"
					( objectStatus "vdd(12)" )
				)
				( pin "J1B1.92"
					( objectStatus "vdd(13)" )
				)
				( pin "J1B1.90"
					( objectStatus "vdd(14)" )
				)
				( pin "J1B1.88"
					( objectStatus "vdd(15)" )
				)
				( pin "J1B1.85"
					( objectStatus "vdd(16)" )
				)
				( pin "J1B1.83"
					( objectStatus "vdd(17)" )
				)
				( pin "J1B1.80"
					( objectStatus "vdd(18)" )
				)
				( pin "J1B1.76"
					( objectStatus "vdd(19)" )
				)
				( pin "J1B1.73"
					( objectStatus "vdd(20)" )
				)
				( pin "J1B1.70"
					( objectStatus "vdd(21)" )
				)
				( pin "J1B1.67"
					( objectStatus "vdd(22)" )
				)
				( pin "J1B1.64"
					( objectStatus "vdd(23)" )
				)
				( pin "J1B1.61"
					( objectStatus "vdd(24)" )
				)
				( pin "J1B1.59"
					( objectStatus "vdd(25)" )
				)
				( pin "J1B1.287"
					( objectStatus "vpp(0)" )
				)
				( pin "J1B1.286"
					( objectStatus "vpp(1)" )
				)
				( pin "J1B1.288"
					( objectStatus "vpp(2)" )
				)
				( pin "J1B1.143"
					( objectStatus "vpp(3)" )
				)
				( pin "J1B1.142"
					( objectStatus "vpp(4)" )
				)
				( pin "J1B1.221"
					( objectStatus "vtt(0)" )
				)
				( pin "J1B1.77"
					( objectStatus "vtt(1)" )
				)
			)
			( gate "C1B9"
				( objectStatus "@baseboard_fab2_lib.baseboard_fab2(sch_1):page83_i176" )
				( pin "C1B9.1"
					( objectStatus "a" )
				)
				( pin "C1B9.2"
					( objectStatus "b" )
				)
			)
			( gate "C9M1"
				( objectStatus "@baseboard_fab2_lib.baseboard_fab2(sch_1):page84_i4" )
				( pin "C9M1.1"
					( objectStatus "a" )
				)
				( pin "C9M1.2"
					( objectStatus "b" )
				)
			)
			( gate "J9M1"
				( objectStatus "@baseboard_fab2_lib.baseboard_fab2(sch_1):page84_i14" )
				( pin "J9M1.79"
					( objectStatus "a0" )
				)
				( pin "J9M1.72"
					( objectStatus "a1" )
				)
				( pin "J9M1.216"
					( objectStatus "a2" )
				)
				( pin "J9M1.71"
					( objectStatus "a3" )
				)
				( pin "J9M1.214"
					( objectStatus "a4" )
				)
				( pin "J9M1.213"
					( objectStatus "a5" )
				)
				( pin "J9M1.69"
					( objectStatus "a6" )
				)
				( pin "J9M1.211"
					( objectStatus "a7" )
				)
				( pin "J9M1.68"
					( objectStatus "a8" )
				)
				( pin "J9M1.66"
					( objectStatus "a9" )
				)
				( pin "J9M1.225"
					( objectStatus "a10" )
				)
				( pin "J9M1.210"
					( objectStatus "a11" )
				)
				( pin "J9M1.65"
					( objectStatus "a12" )
				)
				( pin "J9M1.232"
					( objectStatus "a13" )
				)
				( pin "J9M1.228"
					( objectStatus "a14_we_n" )
				)
				( pin "J9M1.86"
					( objectStatus "a15_cas_n" )
				)
				( pin "J9M1.82"
					( objectStatus "a16_ras_n" )
				)
				( pin "J9M1.234"
					( objectStatus "a17" )
				)
				( pin "J9M1.62"
					( objectStatus "act_n" )
				)
				( pin "J9M1.208"
					( objectStatus "alert_n" )
				)
				( pin "J9M1.81"
					( objectStatus "ba(0)" )
				)
				( pin "J9M1.224"
					( objectStatus "ba(1)" )
				)
				( pin "J9M1.63"
					( objectStatus "bg(0)" )
				)
				( pin "J9M1.207"
					( objectStatus "bg(1)" )
				)
				( pin "J9M1.235"
					( objectStatus "c(2)" )
				)
				( pin "J9M1.49"
					( objectStatus "cb(0)" )
				)
				( pin "J9M1.194"
					( objectStatus "cb(1)" )
				)
				( pin "J9M1.56"
					( objectStatus "cb(2)" )
				)
				( pin "J9M1.201"
					( objectStatus "cb(3)" )
				)
				( pin "J9M1.47"
					( objectStatus "cb(4)" )
				)
				( pin "J9M1.192"
					( objectStatus "cb(5)" )
				)
				( pin "J9M1.54"
					( objectStatus "cb(6)" )
				)
				( pin "J9M1.199"
					( objectStatus "cb(7)" )
				)
				( pin "J9M1.75"
					( objectStatus "ck0n" )
				)
				( pin "J9M1.74"
					( objectStatus "ck0p" )
				)
				( pin "J9M1.219"
					( objectStatus "ck1n" )
				)
				( pin "J9M1.218"
					( objectStatus "ck1p" )
				)
				( pin "J9M1.60"
					( objectStatus "cke(0)" )
				)
				( pin "J9M1.203"
					( objectStatus "cke(1)" )
				)
				( pin "J9M1.5"
					( objectStatus "dq(0)" )
				)
				( pin "J9M1.150"
					( objectStatus "dq(1)" )
				)
				( pin "J9M1.12"
					( objectStatus "dq(2)" )
				)
				( pin "J9M1.157"
					( objectStatus "dq(3)" )
				)
				( pin "J9M1.3"
					( objectStatus "dq(4)" )
				)
				( pin "J9M1.148"
					( objectStatus "dq(5)" )
				)
				( pin "J9M1.10"
					( objectStatus "dq(6)" )
				)
				( pin "J9M1.155"
					( objectStatus "dq(7)" )
				)
				( pin "J9M1.16"
					( objectStatus "dq(8)" )
				)
				( pin "J9M1.161"
					( objectStatus "dq(9)" )
				)
				( pin "J9M1.23"
					( objectStatus "dq(10)" )
				)
				( pin "J9M1.168"
					( objectStatus "dq(11)" )
				)
				( pin "J9M1.14"
					( objectStatus "dq(12)" )
				)
				( pin "J9M1.159"
					( objectStatus "dq(13)" )
				)
				( pin "J9M1.21"
					( objectStatus "dq(14)" )
				)
				( pin "J9M1.166"
					( objectStatus "dq(15)" )
				)
				( pin "J9M1.27"
					( objectStatus "dq(16)" )
				)
				( pin "J9M1.172"
					( objectStatus "dq(17)" )
				)
				( pin "J9M1.34"
					( objectStatus "dq(18)" )
				)
				( pin "J9M1.179"
					( objectStatus "dq(19)" )
				)
				( pin "J9M1.25"
					( objectStatus "dq(20)" )
				)
				( pin "J9M1.170"
					( objectStatus "dq(21)" )
				)
				( pin "J9M1.32"
					( objectStatus "dq(22)" )
				)
				( pin "J9M1.177"
					( objectStatus "dq(23)" )
				)
				( pin "J9M1.38"
					( objectStatus "dq(24)" )
				)
				( pin "J9M1.183"
					( objectStatus "dq(25)" )
				)
				( pin "J9M1.45"
					( objectStatus "dq(26)" )
				)
				( pin "J9M1.190"
					( objectStatus "dq(27)" )
				)
				( pin "J9M1.36"
					( objectStatus "dq(28)" )
				)
				( pin "J9M1.181"
					( objectStatus "dq(29)" )
				)
				( pin "J9M1.43"
					( objectStatus "dq(30)" )
				)
				( pin "J9M1.188"
					( objectStatus "dq(31)" )
				)
				( pin "J9M1.97"
					( objectStatus "dq(32)" )
				)
				( pin "J9M1.242"
					( objectStatus "dq(33)" )
				)
				( pin "J9M1.104"
					( objectStatus "dq(34)" )
				)
				( pin "J9M1.249"
					( objectStatus "dq(35)" )
				)
				( pin "J9M1.95"
					( objectStatus "dq(36)" )
				)
				( pin "J9M1.240"
					( objectStatus "dq(37)" )
				)
				( pin "J9M1.102"
					( objectStatus "dq(38)" )
				)
				( pin "J9M1.247"
					( objectStatus "dq(39)" )
				)
				( pin "J9M1.108"
					( objectStatus "dq(40)" )
				)
				( pin "J9M1.253"
					( objectStatus "dq(41)" )
				)
				( pin "J9M1.115"
					( objectStatus "dq(42)" )
				)
				( pin "J9M1.260"
					( objectStatus "dq(43)" )
				)
				( pin "J9M1.106"
					( objectStatus "dq(44)" )
				)
				( pin "J9M1.251"
					( objectStatus "dq(45)" )
				)
				( pin "J9M1.113"
					( objectStatus "dq(46)" )
				)
				( pin "J9M1.258"
					( objectStatus "dq(47)" )
				)
				( pin "J9M1.119"
					( objectStatus "dq(48)" )
				)
				( pin "J9M1.264"
					( objectStatus "dq(49)" )
				)
				( pin "J9M1.126"
					( objectStatus "dq(50)" )
				)
				( pin "J9M1.271"
					( objectStatus "dq(51)" )
				)
				( pin "J9M1.117"
					( objectStatus "dq(52)" )
				)
				( pin "J9M1.262"
					( objectStatus "dq(53)" )
				)
				( pin "J9M1.124"
					( objectStatus "dq(54)" )
				)
				( pin "J9M1.269"
					( objectStatus "dq(55)" )
				)
				( pin "J9M1.130"
					( objectStatus "dq(56)" )
				)
				( pin "J9M1.275"
					( objectStatus "dq(57)" )
				)
				( pin "J9M1.137"
					( objectStatus "dq(58)" )
				)
				( pin "J9M1.282"
					( objectStatus "dq(59)" )
				)
				( pin "J9M1.128"
					( objectStatus "dq(60)" )
				)
				( pin "J9M1.273"
					( objectStatus "dq(61)" )
				)
				( pin "J9M1.135"
					( objectStatus "dq(62)" )
				)
				( pin "J9M1.280"
					( objectStatus "dq(63)" )
				)
				( pin "J9M1.78"
					( objectStatus "event_n" )
				)
				( pin "J9M1.87"
					( objectStatus "odt(0)" )
				)
				( pin "J9M1.91"
					( objectStatus "odt(1)" )
				)
				( pin "J9M1.222"
					( objectStatus "par" )
				)
				( pin "J9M1.58"
					( objectStatus "reset_n" )
				)
				( pin "J9M1.205"
					( objectStatus "rfu(0)" )
				)
				( pin "J9M1.227"
					( objectStatus "rfu(1)" )
				)
				( pin "J9M1.144"
					( objectStatus "rfu(2)" )
				)
				( pin "J9M1.84"
					( objectStatus "s0_n" )
				)
				( pin "J9M1.89"
					( objectStatus "s1_n" )
				)
				( pin "J9M1.93"
					( objectStatus "s2_n_c(0)" )
				)
				( pin "J9M1.237"
					( objectStatus "s3_n_c(1)" )
				)
				( pin "J9M1.139"
					( objectStatus "sa(0)" )
				)
				( pin "J9M1.140"
					( objectStatus "sa(1)" )
				)
				( pin "J9M1.238"
					( objectStatus "sa(2)" )
				)
				( pin "J9M1.230"
					( objectStatus "save_n_nc" )
				)
				( pin "J9M1.141"
					( objectStatus "scl" )
				)
				( pin "J9M1.285"
					( objectStatus "sda" )
				)
				( pin "J9M1.284"
					( objectStatus "vddspd" )
				)
				( pin "J9M1.146"
					( objectStatus "vrefca" )
				)
			)
			( gate "J9M1"
				( objectStatus "@baseboard_fab2_lib.baseboard_fab2(sch_1):page84_i57" )
				( pin "J9M1.145"
					( objectStatus "\12v\(0)" )
				)
				( pin "J9M1.1"
					( objectStatus "\12v\(1)" )
				)
				( pin "J9M1.236"
					( objectStatus "vdd(0)" )
				)
				( pin "J9M1.233"
					( objectStatus "vdd(1)" )
				)
				( pin "J9M1.231"
					( objectStatus "vdd(2)" )
				)
				( pin "J9M1.229"
					( objectStatus "vdd(3)" )
				)
				( pin "J9M1.226"
					( objectStatus "vdd(4)" )
				)
				( pin "J9M1.223"
					( objectStatus "vdd(5)" )
				)
				( pin "J9M1.220"
					( objectStatus "vdd(6)" )
				)
				( pin "J9M1.217"
					( objectStatus "vdd(7)" )
				)
				( pin "J9M1.215"
					( objectStatus "vdd(8)" )
				)
				( pin "J9M1.212"
					( objectStatus "vdd(9)" )
				)
				( pin "J9M1.209"
					( objectStatus "vdd(10)" )
				)
				( pin "J9M1.206"
					( objectStatus "vdd(11)" )
				)
				( pin "J9M1.204"
					( objectStatus "vdd(12)" )
				)
				( pin "J9M1.92"
					( objectStatus "vdd(13)" )
				)
				( pin "J9M1.90"
					( objectStatus "vdd(14)" )
				)
				( pin "J9M1.88"
					( objectStatus "vdd(15)" )
				)
				( pin "J9M1.85"
					( objectStatus "vdd(16)" )
				)
				( pin "J9M1.83"
					( objectStatus "vdd(17)" )
				)
				( pin "J9M1.80"
					( objectStatus "vdd(18)" )
				)
				( pin "J9M1.76"
					( objectStatus "vdd(19)" )
				)
				( pin "J9M1.73"
					( objectStatus "vdd(20)" )
				)
				( pin "J9M1.70"
					( objectStatus "vdd(21)" )
				)
				( pin "J9M1.67"
					( objectStatus "vdd(22)" )
				)
				( pin "J9M1.64"
					( objectStatus "vdd(23)" )
				)
				( pin "J9M1.61"
					( objectStatus "vdd(24)" )
				)
				( pin "J9M1.59"
					( objectStatus "vdd(25)" )
				)
				( pin "J9M1.287"
					( objectStatus "vpp(0)" )
				)
				( pin "J9M1.286"
					( objectStatus "vpp(1)" )
				)
				( pin "J9M1.288"
					( objectStatus "vpp(2)" )
				)
				( pin "J9M1.143"
					( objectStatus "vpp(3)" )
				)
				( pin "J9M1.142"
					( objectStatus "vpp(4)" )
				)
				( pin "J9M1.221"
					( objectStatus "vtt(0)" )
				)
				( pin "J9M1.77"
					( objectStatus "vtt(1)" )
				)
			)
			( gate "J9M1"
				( objectStatus "@baseboard_fab2_lib.baseboard_fab2(sch_1):page84_i102" )
				( pin "J9M1.152"
					( objectStatus "dqs0n" )
				)
				( pin "J9M1.153"
					( objectStatus "dqs0p" )
				)
				( pin "J9M1.163"
					( objectStatus "dqs1n" )
				)
				( pin "J9M1.164"
					( objectStatus "dqs1p" )
				)
				( pin "J9M1.174"
					( objectStatus "dqs2n" )
				)
				( pin "J9M1.175"
					( objectStatus "dqs2p" )
				)
				( pin "J9M1.185"
					( objectStatus "dqs3n" )
				)
				( pin "J9M1.186"
					( objectStatus "dqs3p" )
				)
				( pin "J9M1.244"
					( objectStatus "dqs4n" )
				)
				( pin "J9M1.245"
					( objectStatus "dqs4p" )
				)
				( pin "J9M1.255"
					( objectStatus "dqs5n" )
				)
				( pin "J9M1.256"
					( objectStatus "dqs5p" )
				)
				( pin "J9M1.266"
					( objectStatus "dqs6n" )
				)
				( pin "J9M1.267"
					( objectStatus "dqs6p" )
				)
				( pin "J9M1.277"
					( objectStatus "dqs7n" )
				)
				( pin "J9M1.278"
					( objectStatus "dqs7p" )
				)
				( pin "J9M1.196"
					( objectStatus "dqs8n" )
				)
				( pin "J9M1.197"
					( objectStatus "dqs8p" )
				)
				( pin "J9M1.8"
					( objectStatus "dqs9n" )
				)
				( pin "J9M1.7"
					( objectStatus "dqs9p" )
				)
				( pin "J9M1.19"
					( objectStatus "dqs10n" )
				)
				( pin "J9M1.18"
					( objectStatus "dqs10p" )
				)
				( pin "J9M1.30"
					( objectStatus "dqs11n" )
				)
				( pin "J9M1.29"
					( objectStatus "dqs11p" )
				)
				( pin "J9M1.41"
					( objectStatus "dqs12n" )
				)
				( pin "J9M1.40"
					( objectStatus "dqs12p" )
				)
				( pin "J9M1.100"
					( objectStatus "dqs13n" )
				)
				( pin "J9M1.99"
					( objectStatus "dqs13p" )
				)
				( pin "J9M1.111"
					( objectStatus "dqs14n" )
				)
				( pin "J9M1.110"
					( objectStatus "dqs14p" )
				)
				( pin "J9M1.122"
					( objectStatus "dqs15n" )
				)
				( pin "J9M1.121"
					( objectStatus "dqs15p" )
				)
				( pin "J9M1.133"
					( objectStatus "dqs16n" )
				)
				( pin "J9M1.132"
					( objectStatus "dqs16p" )
				)
				( pin "J9M1.52"
					( objectStatus "dqs17n" )
				)
				( pin "J9M1.51"
					( objectStatus "dqs17p" )
				)
			)
			( gate "J9M1"
				( objectStatus "@baseboard_fab2_lib.baseboard_fab2(sch_1):page84_i138" )
				( pin "J9M1.283"
					( objectStatus "vss(0)" )
				)
				( pin "J9M1.281"
					( objectStatus "vss(1)" )
				)
				( pin "J9M1.279"
					( objectStatus "vss(2)" )
				)
				( pin "J9M1.276"
					( objectStatus "vss(3)" )
				)
				( pin "J9M1.274"
					( objectStatus "vss(4)" )
				)
				( pin "J9M1.272"
					( objectStatus "vss(5)" )
				)
				( pin "J9M1.270"
					( objectStatus "vss(6)" )
				)
				( pin "J9M1.268"
					( objectStatus "vss(7)" )
				)
				( pin "J9M1.265"
					( objectStatus "vss(8)" )
				)
				( pin "J9M1.263"
					( objectStatus "vss(9)" )
				)
				( pin "J9M1.261"
					( objectStatus "vss(10)" )
				)
				( pin "J9M1.259"
					( objectStatus "vss(11)" )
				)
				( pin "J9M1.257"
					( objectStatus "vss(12)" )
				)
				( pin "J9M1.254"
					( objectStatus "vss(13)" )
				)
				( pin "J9M1.252"
					( objectStatus "vss(14)" )
				)
				( pin "J9M1.250"
					( objectStatus "vss(15)" )
				)
				( pin "J9M1.248"
					( objectStatus "vss(16)" )
				)
				( pin "J9M1.246"
					( objectStatus "vss(17)" )
				)
				( pin "J9M1.243"
					( objectStatus "vss(18)" )
				)
				( pin "J9M1.241"
					( objectStatus "vss(19)" )
				)
				( pin "J9M1.239"
					( objectStatus "vss(20)" )
				)
				( pin "J9M1.202"
					( objectStatus "vss(21)" )
				)
				( pin "J9M1.200"
					( objectStatus "vss(22)" )
				)
				( pin "J9M1.198"
					( objectStatus "vss(23)" )
				)
				( pin "J9M1.195"
					( objectStatus "vss(24)" )
				)
				( pin "J9M1.193"
					( objectStatus "vss(25)" )
				)
				( pin "J9M1.191"
					( objectStatus "vss(26)" )
				)
				( pin "J9M1.189"
					( objectStatus "vss(27)" )
				)
				( pin "J9M1.187"
					( objectStatus "vss(28)" )
				)
				( pin "J9M1.184"
					( objectStatus "vss(29)" )
				)
				( pin "J9M1.182"
					( objectStatus "vss(30)" )
				)
				( pin "J9M1.180"
					( objectStatus "vss(31)" )
				)
				( pin "J9M1.178"
					( objectStatus "vss(32)" )
				)
				( pin "J9M1.176"
					( objectStatus "vss(33)" )
				)
				( pin "J9M1.173"
					( objectStatus "vss(34)" )
				)
				( pin "J9M1.171"
					( objectStatus "vss(35)" )
				)
				( pin "J9M1.169"
					( objectStatus "vss(36)" )
				)
				( pin "J9M1.167"
					( objectStatus "vss(37)" )
				)
				( pin "J9M1.165"
					( objectStatus "vss(38)" )
				)
				( pin "J9M1.162"
					( objectStatus "vss(39)" )
				)
				( pin "J9M1.160"
					( objectStatus "vss(40)" )
				)
				( pin "J9M1.158"
					( objectStatus "vss(41)" )
				)
				( pin "J9M1.156"
					( objectStatus "vss(42)" )
				)
				( pin "J9M1.154"
					( objectStatus "vss(43)" )
				)
				( pin "J9M1.151"
					( objectStatus "vss(44)" )
				)
				( pin "J9M1.149"
					( objectStatus "vss(45)" )
				)
				( pin "J9M1.147"
					( objectStatus "vss(46)" )
				)
				( pin "J9M1.138"
					( objectStatus "vss(47)" )
				)
				( pin "J9M1.136"
					( objectStatus "vss(48)" )
				)
				( pin "J9M1.134"
					( objectStatus "vss(49)" )
				)
				( pin "J9M1.131"
					( objectStatus "vss(50)" )
				)
				( pin "J9M1.129"
					( objectStatus "vss(51)" )
				)
				( pin "J9M1.127"
					( objectStatus "vss(52)" )
				)
				( pin "J9M1.125"
					( objectStatus "vss(53)" )
				)
				( pin "J9M1.123"
					( objectStatus "vss(54)" )
				)
				( pin "J9M1.120"
					( objectStatus "vss(55)" )
				)
				( pin "J9M1.118"
					( objectStatus "vss(56)" )
				)
				( pin "J9M1.116"
					( objectStatus "vss(57)" )
				)
				( pin "J9M1.114"
					( objectStatus "vss(58)" )
				)
				( pin "J9M1.112"
					( objectStatus "vss(59)" )
				)
				( pin "J9M1.109"
					( objectStatus "vss(60)" )
				)
				( pin "J9M1.107"
					( objectStatus "vss(61)" )
				)
				( pin "J9M1.105"
					( objectStatus "vss(62)" )
				)
				( pin "J9M1.103"
					( objectStatus "vss(63)" )
				)
				( pin "J9M1.101"
					( objectStatus "vss(64)" )
				)
				( pin "J9M1.98"
					( objectStatus "vss(65)" )
				)
				( pin "J9M1.96"
					( objectStatus "vss(66)" )
				)
				( pin "J9M1.94"
					( objectStatus "vss(67)" )
				)
				( pin "J9M1.57"
					( objectStatus "vss(68)" )
				)
				( pin "J9M1.55"
					( objectStatus "vss(69)" )
				)
				( pin "J9M1.53"
					( objectStatus "vss(70)" )
				)
				( pin "J9M1.50"
					( objectStatus "vss(71)" )
				)
				( pin "J9M1.48"
					( objectStatus "vss(72)" )
				)
				( pin "J9M1.46"
					( objectStatus "vss(73)" )
				)
				( pin "J9M1.44"
					( objectStatus "vss(74)" )
				)
				( pin "J9M1.42"
					( objectStatus "vss(75)" )
				)
				( pin "J9M1.39"
					( objectStatus "vss(76)" )
				)
				( pin "J9M1.37"
					( objectStatus "vss(77)" )
				)
				( pin "J9M1.35"
					( objectStatus "vss(78)" )
				)
				( pin "J9M1.33"
					( objectStatus "vss(79)" )
				)
				( pin "J9M1.31"
					( objectStatus "vss(80)" )
				)
				( pin "J9M1.28"
					( objectStatus "vss(81)" )
				)
				( pin "J9M1.26"
					( objectStatus "vss(82)" )
				)
				( pin "J9M1.24"
					( objectStatus "vss(83)" )
				)
				( pin "J9M1.22"
					( objectStatus "vss(84)" )
				)
				( pin "J9M1.20"
					( objectStatus "vss(85)" )
				)
				( pin "J9M1.17"
					( objectStatus "vss(86)" )
				)
				( pin "J9M1.15"
					( objectStatus "vss(87)" )
				)
				( pin "J9M1.13"
					( objectStatus "vss(88)" )
				)
				( pin "J9M1.11"
					( objectStatus "vss(89)" )
				)
				( pin "J9M1.9"
					( objectStatus "vss(90)" )
				)
				( pin "J9M1.6"
					( objectStatus "vss(91)" )
				)
				( pin "J9M1.4"
					( objectStatus "vss(92)" )
				)
				( pin "J9M1.2"
					( objectStatus "vss(93)" )
				)
			)
			( gate "J1A2"
				( objectStatus "@baseboard_fab2_lib.baseboard_fab2(sch_1):page85_i43" )
				( pin "J1A2.283"
					( objectStatus "vss(0)" )
				)
				( pin "J1A2.281"
					( objectStatus "vss(1)" )
				)
				( pin "J1A2.279"
					( objectStatus "vss(2)" )
				)
				( pin "J1A2.276"
					( objectStatus "vss(3)" )
				)
				( pin "J1A2.274"
					( objectStatus "vss(4)" )
				)
				( pin "J1A2.272"
					( objectStatus "vss(5)" )
				)
				( pin "J1A2.270"
					( objectStatus "vss(6)" )
				)
				( pin "J1A2.268"
					( objectStatus "vss(7)" )
				)
				( pin "J1A2.265"
					( objectStatus "vss(8)" )
				)
				( pin "J1A2.263"
					( objectStatus "vss(9)" )
				)
				( pin "J1A2.261"
					( objectStatus "vss(10)" )
				)
				( pin "J1A2.259"
					( objectStatus "vss(11)" )
				)
				( pin "J1A2.257"
					( objectStatus "vss(12)" )
				)
				( pin "J1A2.254"
					( objectStatus "vss(13)" )
				)
				( pin "J1A2.252"
					( objectStatus "vss(14)" )
				)
				( pin "J1A2.250"
					( objectStatus "vss(15)" )
				)
				( pin "J1A2.248"
					( objectStatus "vss(16)" )
				)
				( pin "J1A2.246"
					( objectStatus "vss(17)" )
				)
				( pin "J1A2.243"
					( objectStatus "vss(18)" )
				)
				( pin "J1A2.241"
					( objectStatus "vss(19)" )
				)
				( pin "J1A2.239"
					( objectStatus "vss(20)" )
				)
				( pin "J1A2.202"
					( objectStatus "vss(21)" )
				)
				( pin "J1A2.200"
					( objectStatus "vss(22)" )
				)
				( pin "J1A2.198"
					( objectStatus "vss(23)" )
				)
				( pin "J1A2.195"
					( objectStatus "vss(24)" )
				)
				( pin "J1A2.193"
					( objectStatus "vss(25)" )
				)
				( pin "J1A2.191"
					( objectStatus "vss(26)" )
				)
				( pin "J1A2.189"
					( objectStatus "vss(27)" )
				)
				( pin "J1A2.187"
					( objectStatus "vss(28)" )
				)
				( pin "J1A2.184"
					( objectStatus "vss(29)" )
				)
				( pin "J1A2.182"
					( objectStatus "vss(30)" )
				)
				( pin "J1A2.180"
					( objectStatus "vss(31)" )
				)
				( pin "J1A2.178"
					( objectStatus "vss(32)" )
				)
				( pin "J1A2.176"
					( objectStatus "vss(33)" )
				)
				( pin "J1A2.173"
					( objectStatus "vss(34)" )
				)
				( pin "J1A2.171"
					( objectStatus "vss(35)" )
				)
				( pin "J1A2.169"
					( objectStatus "vss(36)" )
				)
				( pin "J1A2.167"
					( objectStatus "vss(37)" )
				)
				( pin "J1A2.165"
					( objectStatus "vss(38)" )
				)
				( pin "J1A2.162"
					( objectStatus "vss(39)" )
				)
				( pin "J1A2.160"
					( objectStatus "vss(40)" )
				)
				( pin "J1A2.158"
					( objectStatus "vss(41)" )
				)
				( pin "J1A2.156"
					( objectStatus "vss(42)" )
				)
				( pin "J1A2.154"
					( objectStatus "vss(43)" )
				)
				( pin "J1A2.151"
					( objectStatus "vss(44)" )
				)
				( pin "J1A2.149"
					( objectStatus "vss(45)" )
				)
				( pin "J1A2.147"
					( objectStatus "vss(46)" )
				)
				( pin "J1A2.138"
					( objectStatus "vss(47)" )
				)
				( pin "J1A2.136"
					( objectStatus "vss(48)" )
				)
				( pin "J1A2.134"
					( objectStatus "vss(49)" )
				)
				( pin "J1A2.131"
					( objectStatus "vss(50)" )
				)
				( pin "J1A2.129"
					( objectStatus "vss(51)" )
				)
				( pin "J1A2.127"
					( objectStatus "vss(52)" )
				)
				( pin "J1A2.125"
					( objectStatus "vss(53)" )
				)
				( pin "J1A2.123"
					( objectStatus "vss(54)" )
				)
				( pin "J1A2.120"
					( objectStatus "vss(55)" )
				)
				( pin "J1A2.118"
					( objectStatus "vss(56)" )
				)
				( pin "J1A2.116"
					( objectStatus "vss(57)" )
				)
				( pin "J1A2.114"
					( objectStatus "vss(58)" )
				)
				( pin "J1A2.112"
					( objectStatus "vss(59)" )
				)
				( pin "J1A2.109"
					( objectStatus "vss(60)" )
				)
				( pin "J1A2.107"
					( objectStatus "vss(61)" )
				)
				( pin "J1A2.105"
					( objectStatus "vss(62)" )
				)
				( pin "J1A2.103"
					( objectStatus "vss(63)" )
				)
				( pin "J1A2.101"
					( objectStatus "vss(64)" )
				)
				( pin "J1A2.98"
					( objectStatus "vss(65)" )
				)
				( pin "J1A2.96"
					( objectStatus "vss(66)" )
				)
				( pin "J1A2.94"
					( objectStatus "vss(67)" )
				)
				( pin "J1A2.57"
					( objectStatus "vss(68)" )
				)
				( pin "J1A2.55"
					( objectStatus "vss(69)" )
				)
				( pin "J1A2.53"
					( objectStatus "vss(70)" )
				)
				( pin "J1A2.50"
					( objectStatus "vss(71)" )
				)
				( pin "J1A2.48"
					( objectStatus "vss(72)" )
				)
				( pin "J1A2.46"
					( objectStatus "vss(73)" )
				)
				( pin "J1A2.44"
					( objectStatus "vss(74)" )
				)
				( pin "J1A2.42"
					( objectStatus "vss(75)" )
				)
				( pin "J1A2.39"
					( objectStatus "vss(76)" )
				)
				( pin "J1A2.37"
					( objectStatus "vss(77)" )
				)
				( pin "J1A2.35"
					( objectStatus "vss(78)" )
				)
				( pin "J1A2.33"
					( objectStatus "vss(79)" )
				)
				( pin "J1A2.31"
					( objectStatus "vss(80)" )
				)
				( pin "J1A2.28"
					( objectStatus "vss(81)" )
				)
				( pin "J1A2.26"
					( objectStatus "vss(82)" )
				)
				( pin "J1A2.24"
					( objectStatus "vss(83)" )
				)
				( pin "J1A2.22"
					( objectStatus "vss(84)" )
				)
				( pin "J1A2.20"
					( objectStatus "vss(85)" )
				)
				( pin "J1A2.17"
					( objectStatus "vss(86)" )
				)
				( pin "J1A2.15"
					( objectStatus "vss(87)" )
				)
				( pin "J1A2.13"
					( objectStatus "vss(88)" )
				)
				( pin "J1A2.11"
					( objectStatus "vss(89)" )
				)
				( pin "J1A2.9"
					( objectStatus "vss(90)" )
				)
				( pin "J1A2.6"
					( objectStatus "vss(91)" )
				)
				( pin "J1A2.4"
					( objectStatus "vss(92)" )
				)
				( pin "J1A2.2"
					( objectStatus "vss(93)" )
				)
			)
			( gate "J1A2"
				( objectStatus "@baseboard_fab2_lib.baseboard_fab2(sch_1):page85_i66" )
				( pin "J1A2.152"
					( objectStatus "dqs0n" )
				)
				( pin "J1A2.153"
					( objectStatus "dqs0p" )
				)
				( pin "J1A2.163"
					( objectStatus "dqs1n" )
				)
				( pin "J1A2.164"
					( objectStatus "dqs1p" )
				)
				( pin "J1A2.174"
					( objectStatus "dqs2n" )
				)
				( pin "J1A2.175"
					( objectStatus "dqs2p" )
				)
				( pin "J1A2.185"
					( objectStatus "dqs3n" )
				)
				( pin "J1A2.186"
					( objectStatus "dqs3p" )
				)
				( pin "J1A2.244"
					( objectStatus "dqs4n" )
				)
				( pin "J1A2.245"
					( objectStatus "dqs4p" )
				)
				( pin "J1A2.255"
					( objectStatus "dqs5n" )
				)
				( pin "J1A2.256"
					( objectStatus "dqs5p" )
				)
				( pin "J1A2.266"
					( objectStatus "dqs6n" )
				)
				( pin "J1A2.267"
					( objectStatus "dqs6p" )
				)
				( pin "J1A2.277"
					( objectStatus "dqs7n" )
				)
				( pin "J1A2.278"
					( objectStatus "dqs7p" )
				)
				( pin "J1A2.196"
					( objectStatus "dqs8n" )
				)
				( pin "J1A2.197"
					( objectStatus "dqs8p" )
				)
				( pin "J1A2.8"
					( objectStatus "dqs9n" )
				)
				( pin "J1A2.7"
					( objectStatus "dqs9p" )
				)
				( pin "J1A2.19"
					( objectStatus "dqs10n" )
				)
				( pin "J1A2.18"
					( objectStatus "dqs10p" )
				)
				( pin "J1A2.30"
					( objectStatus "dqs11n" )
				)
				( pin "J1A2.29"
					( objectStatus "dqs11p" )
				)
				( pin "J1A2.41"
					( objectStatus "dqs12n" )
				)
				( pin "J1A2.40"
					( objectStatus "dqs12p" )
				)
				( pin "J1A2.100"
					( objectStatus "dqs13n" )
				)
				( pin "J1A2.99"
					( objectStatus "dqs13p" )
				)
				( pin "J1A2.111"
					( objectStatus "dqs14n" )
				)
				( pin "J1A2.110"
					( objectStatus "dqs14p" )
				)
				( pin "J1A2.122"
					( objectStatus "dqs15n" )
				)
				( pin "J1A2.121"
					( objectStatus "dqs15p" )
				)
				( pin "J1A2.133"
					( objectStatus "dqs16n" )
				)
				( pin "J1A2.132"
					( objectStatus "dqs16p" )
				)
				( pin "J1A2.52"
					( objectStatus "dqs17n" )
				)
				( pin "J1A2.51"
					( objectStatus "dqs17p" )
				)
			)
			( gate "J1A2"
				( objectStatus "@baseboard_fab2_lib.baseboard_fab2(sch_1):page85_i111" )
				( pin "J1A2.79"
					( objectStatus "a0" )
				)
				( pin "J1A2.72"
					( objectStatus "a1" )
				)
				( pin "J1A2.216"
					( objectStatus "a2" )
				)
				( pin "J1A2.71"
					( objectStatus "a3" )
				)
				( pin "J1A2.214"
					( objectStatus "a4" )
				)
				( pin "J1A2.213"
					( objectStatus "a5" )
				)
				( pin "J1A2.69"
					( objectStatus "a6" )
				)
				( pin "J1A2.211"
					( objectStatus "a7" )
				)
				( pin "J1A2.68"
					( objectStatus "a8" )
				)
				( pin "J1A2.66"
					( objectStatus "a9" )
				)
				( pin "J1A2.225"
					( objectStatus "a10" )
				)
				( pin "J1A2.210"
					( objectStatus "a11" )
				)
				( pin "J1A2.65"
					( objectStatus "a12" )
				)
				( pin "J1A2.232"
					( objectStatus "a13" )
				)
				( pin "J1A2.228"
					( objectStatus "a14_we_n" )
				)
				( pin "J1A2.86"
					( objectStatus "a15_cas_n" )
				)
				( pin "J1A2.82"
					( objectStatus "a16_ras_n" )
				)
				( pin "J1A2.234"
					( objectStatus "a17" )
				)
				( pin "J1A2.62"
					( objectStatus "act_n" )
				)
				( pin "J1A2.208"
					( objectStatus "alert_n" )
				)
				( pin "J1A2.81"
					( objectStatus "ba(0)" )
				)
				( pin "J1A2.224"
					( objectStatus "ba(1)" )
				)
				( pin "J1A2.63"
					( objectStatus "bg(0)" )
				)
				( pin "J1A2.207"
					( objectStatus "bg(1)" )
				)
				( pin "J1A2.235"
					( objectStatus "c(2)" )
				)
				( pin "J1A2.49"
					( objectStatus "cb(0)" )
				)
				( pin "J1A2.194"
					( objectStatus "cb(1)" )
				)
				( pin "J1A2.56"
					( objectStatus "cb(2)" )
				)
				( pin "J1A2.201"
					( objectStatus "cb(3)" )
				)
				( pin "J1A2.47"
					( objectStatus "cb(4)" )
				)
				( pin "J1A2.192"
					( objectStatus "cb(5)" )
				)
				( pin "J1A2.54"
					( objectStatus "cb(6)" )
				)
				( pin "J1A2.199"
					( objectStatus "cb(7)" )
				)
				( pin "J1A2.75"
					( objectStatus "ck0n" )
				)
				( pin "J1A2.74"
					( objectStatus "ck0p" )
				)
				( pin "J1A2.219"
					( objectStatus "ck1n" )
				)
				( pin "J1A2.218"
					( objectStatus "ck1p" )
				)
				( pin "J1A2.60"
					( objectStatus "cke(0)" )
				)
				( pin "J1A2.203"
					( objectStatus "cke(1)" )
				)
				( pin "J1A2.5"
					( objectStatus "dq(0)" )
				)
				( pin "J1A2.150"
					( objectStatus "dq(1)" )
				)
				( pin "J1A2.12"
					( objectStatus "dq(2)" )
				)
				( pin "J1A2.157"
					( objectStatus "dq(3)" )
				)
				( pin "J1A2.3"
					( objectStatus "dq(4)" )
				)
				( pin "J1A2.148"
					( objectStatus "dq(5)" )
				)
				( pin "J1A2.10"
					( objectStatus "dq(6)" )
				)
				( pin "J1A2.155"
					( objectStatus "dq(7)" )
				)
				( pin "J1A2.16"
					( objectStatus "dq(8)" )
				)
				( pin "J1A2.161"
					( objectStatus "dq(9)" )
				)
				( pin "J1A2.23"
					( objectStatus "dq(10)" )
				)
				( pin "J1A2.168"
					( objectStatus "dq(11)" )
				)
				( pin "J1A2.14"
					( objectStatus "dq(12)" )
				)
				( pin "J1A2.159"
					( objectStatus "dq(13)" )
				)
				( pin "J1A2.21"
					( objectStatus "dq(14)" )
				)
				( pin "J1A2.166"
					( objectStatus "dq(15)" )
				)
				( pin "J1A2.27"
					( objectStatus "dq(16)" )
				)
				( pin "J1A2.172"
					( objectStatus "dq(17)" )
				)
				( pin "J1A2.34"
					( objectStatus "dq(18)" )
				)
				( pin "J1A2.179"
					( objectStatus "dq(19)" )
				)
				( pin "J1A2.25"
					( objectStatus "dq(20)" )
				)
				( pin "J1A2.170"
					( objectStatus "dq(21)" )
				)
				( pin "J1A2.32"
					( objectStatus "dq(22)" )
				)
				( pin "J1A2.177"
					( objectStatus "dq(23)" )
				)
				( pin "J1A2.38"
					( objectStatus "dq(24)" )
				)
				( pin "J1A2.183"
					( objectStatus "dq(25)" )
				)
				( pin "J1A2.45"
					( objectStatus "dq(26)" )
				)
				( pin "J1A2.190"
					( objectStatus "dq(27)" )
				)
				( pin "J1A2.36"
					( objectStatus "dq(28)" )
				)
				( pin "J1A2.181"
					( objectStatus "dq(29)" )
				)
				( pin "J1A2.43"
					( objectStatus "dq(30)" )
				)
				( pin "J1A2.188"
					( objectStatus "dq(31)" )
				)
				( pin "J1A2.97"
					( objectStatus "dq(32)" )
				)
				( pin "J1A2.242"
					( objectStatus "dq(33)" )
				)
				( pin "J1A2.104"
					( objectStatus "dq(34)" )
				)
				( pin "J1A2.249"
					( objectStatus "dq(35)" )
				)
				( pin "J1A2.95"
					( objectStatus "dq(36)" )
				)
				( pin "J1A2.240"
					( objectStatus "dq(37)" )
				)
				( pin "J1A2.102"
					( objectStatus "dq(38)" )
				)
				( pin "J1A2.247"
					( objectStatus "dq(39)" )
				)
				( pin "J1A2.108"
					( objectStatus "dq(40)" )
				)
				( pin "J1A2.253"
					( objectStatus "dq(41)" )
				)
				( pin "J1A2.115"
					( objectStatus "dq(42)" )
				)
				( pin "J1A2.260"
					( objectStatus "dq(43)" )
				)
				( pin "J1A2.106"
					( objectStatus "dq(44)" )
				)
				( pin "J1A2.251"
					( objectStatus "dq(45)" )
				)
				( pin "J1A2.113"
					( objectStatus "dq(46)" )
				)
				( pin "J1A2.258"
					( objectStatus "dq(47)" )
				)
				( pin "J1A2.119"
					( objectStatus "dq(48)" )
				)
				( pin "J1A2.264"
					( objectStatus "dq(49)" )
				)
				( pin "J1A2.126"
					( objectStatus "dq(50)" )
				)
				( pin "J1A2.271"
					( objectStatus "dq(51)" )
				)
				( pin "J1A2.117"
					( objectStatus "dq(52)" )
				)
				( pin "J1A2.262"
					( objectStatus "dq(53)" )
				)
				( pin "J1A2.124"
					( objectStatus "dq(54)" )
				)
				( pin "J1A2.269"
					( objectStatus "dq(55)" )
				)
				( pin "J1A2.130"
					( objectStatus "dq(56)" )
				)
				( pin "J1A2.275"
					( objectStatus "dq(57)" )
				)
				( pin "J1A2.137"
					( objectStatus "dq(58)" )
				)
				( pin "J1A2.282"
					( objectStatus "dq(59)" )
				)
				( pin "J1A2.128"
					( objectStatus "dq(60)" )
				)
				( pin "J1A2.273"
					( objectStatus "dq(61)" )
				)
				( pin "J1A2.135"
					( objectStatus "dq(62)" )
				)
				( pin "J1A2.280"
					( objectStatus "dq(63)" )
				)
				( pin "J1A2.78"
					( objectStatus "event_n" )
				)
				( pin "J1A2.87"
					( objectStatus "odt(0)" )
				)
				( pin "J1A2.91"
					( objectStatus "odt(1)" )
				)
				( pin "J1A2.222"
					( objectStatus "par" )
				)
				( pin "J1A2.58"
					( objectStatus "reset_n" )
				)
				( pin "J1A2.205"
					( objectStatus "rfu(0)" )
				)
				( pin "J1A2.227"
					( objectStatus "rfu(1)" )
				)
				( pin "J1A2.144"
					( objectStatus "rfu(2)" )
				)
				( pin "J1A2.84"
					( objectStatus "s0_n" )
				)
				( pin "J1A2.89"
					( objectStatus "s1_n" )
				)
				( pin "J1A2.93"
					( objectStatus "s2_n_c(0)" )
				)
				( pin "J1A2.237"
					( objectStatus "s3_n_c(1)" )
				)
				( pin "J1A2.139"
					( objectStatus "sa(0)" )
				)
				( pin "J1A2.140"
					( objectStatus "sa(1)" )
				)
				( pin "J1A2.238"
					( objectStatus "sa(2)" )
				)
				( pin "J1A2.230"
					( objectStatus "save_n_nc" )
				)
				( pin "J1A2.141"
					( objectStatus "scl" )
				)
				( pin "J1A2.285"
					( objectStatus "sda" )
				)
				( pin "J1A2.284"
					( objectStatus "vddspd" )
				)
				( pin "J1A2.146"
					( objectStatus "vrefca" )
				)
			)
			( gate "J1A2"
				( objectStatus "@baseboard_fab2_lib.baseboard_fab2(sch_1):page85_i172" )
				( pin "J1A2.145"
					( objectStatus "\12v\(0)" )
				)
				( pin "J1A2.1"
					( objectStatus "\12v\(1)" )
				)
				( pin "J1A2.236"
					( objectStatus "vdd(0)" )
				)
				( pin "J1A2.233"
					( objectStatus "vdd(1)" )
				)
				( pin "J1A2.231"
					( objectStatus "vdd(2)" )
				)
				( pin "J1A2.229"
					( objectStatus "vdd(3)" )
				)
				( pin "J1A2.226"
					( objectStatus "vdd(4)" )
				)
				( pin "J1A2.223"
					( objectStatus "vdd(5)" )
				)
				( pin "J1A2.220"
					( objectStatus "vdd(6)" )
				)
				( pin "J1A2.217"
					( objectStatus "vdd(7)" )
				)
				( pin "J1A2.215"
					( objectStatus "vdd(8)" )
				)
				( pin "J1A2.212"
					( objectStatus "vdd(9)" )
				)
				( pin "J1A2.209"
					( objectStatus "vdd(10)" )
				)
				( pin "J1A2.206"
					( objectStatus "vdd(11)" )
				)
				( pin "J1A2.204"
					( objectStatus "vdd(12)" )
				)
				( pin "J1A2.92"
					( objectStatus "vdd(13)" )
				)
				( pin "J1A2.90"
					( objectStatus "vdd(14)" )
				)
				( pin "J1A2.88"
					( objectStatus "vdd(15)" )
				)
				( pin "J1A2.85"
					( objectStatus "vdd(16)" )
				)
				( pin "J1A2.83"
					( objectStatus "vdd(17)" )
				)
				( pin "J1A2.80"
					( objectStatus "vdd(18)" )
				)
				( pin "J1A2.76"
					( objectStatus "vdd(19)" )
				)
				( pin "J1A2.73"
					( objectStatus "vdd(20)" )
				)
				( pin "J1A2.70"
					( objectStatus "vdd(21)" )
				)
				( pin "J1A2.67"
					( objectStatus "vdd(22)" )
				)
				( pin "J1A2.64"
					( objectStatus "vdd(23)" )
				)
				( pin "J1A2.61"
					( objectStatus "vdd(24)" )
				)
				( pin "J1A2.59"
					( objectStatus "vdd(25)" )
				)
				( pin "J1A2.287"
					( objectStatus "vpp(0)" )
				)
				( pin "J1A2.286"
					( objectStatus "vpp(1)" )
				)
				( pin "J1A2.288"
					( objectStatus "vpp(2)" )
				)
				( pin "J1A2.143"
					( objectStatus "vpp(3)" )
				)
				( pin "J1A2.142"
					( objectStatus "vpp(4)" )
				)
				( pin "J1A2.221"
					( objectStatus "vtt(0)" )
				)
				( pin "J1A2.77"
					( objectStatus "vtt(1)" )
				)
			)
			( gate "C9L7"
				( objectStatus "@baseboard_fab2_lib.baseboard_fab2(sch_1):page85_i181" )
				( pin "C9L7.1"
					( objectStatus "a" )
				)
				( pin "C9L7.2"
					( objectStatus "b" )
				)
			)
			( gate "J9L2"
				( objectStatus "@baseboard_fab2_lib.baseboard_fab2(sch_1):page86_i12" )
				( pin "J9L2.79"
					( objectStatus "a0" )
				)
				( pin "J9L2.72"
					( objectStatus "a1" )
				)
				( pin "J9L2.216"
					( objectStatus "a2" )
				)
				( pin "J9L2.71"
					( objectStatus "a3" )
				)
				( pin "J9L2.214"
					( objectStatus "a4" )
				)
				( pin "J9L2.213"
					( objectStatus "a5" )
				)
				( pin "J9L2.69"
					( objectStatus "a6" )
				)
				( pin "J9L2.211"
					( objectStatus "a7" )
				)
				( pin "J9L2.68"
					( objectStatus "a8" )
				)
				( pin "J9L2.66"
					( objectStatus "a9" )
				)
				( pin "J9L2.225"
					( objectStatus "a10" )
				)
				( pin "J9L2.210"
					( objectStatus "a11" )
				)
				( pin "J9L2.65"
					( objectStatus "a12" )
				)
				( pin "J9L2.232"
					( objectStatus "a13" )
				)
				( pin "J9L2.228"
					( objectStatus "a14_we_n" )
				)
				( pin "J9L2.86"
					( objectStatus "a15_cas_n" )
				)
				( pin "J9L2.82"
					( objectStatus "a16_ras_n" )
				)
				( pin "J9L2.234"
					( objectStatus "a17" )
				)
				( pin "J9L2.62"
					( objectStatus "act_n" )
				)
				( pin "J9L2.208"
					( objectStatus "alert_n" )
				)
				( pin "J9L2.81"
					( objectStatus "ba(0)" )
				)
				( pin "J9L2.224"
					( objectStatus "ba(1)" )
				)
				( pin "J9L2.63"
					( objectStatus "bg(0)" )
				)
				( pin "J9L2.207"
					( objectStatus "bg(1)" )
				)
				( pin "J9L2.235"
					( objectStatus "c(2)" )
				)
				( pin "J9L2.49"
					( objectStatus "cb(0)" )
				)
				( pin "J9L2.194"
					( objectStatus "cb(1)" )
				)
				( pin "J9L2.56"
					( objectStatus "cb(2)" )
				)
				( pin "J9L2.201"
					( objectStatus "cb(3)" )
				)
				( pin "J9L2.47"
					( objectStatus "cb(4)" )
				)
				( pin "J9L2.192"
					( objectStatus "cb(5)" )
				)
				( pin "J9L2.54"
					( objectStatus "cb(6)" )
				)
				( pin "J9L2.199"
					( objectStatus "cb(7)" )
				)
				( pin "J9L2.75"
					( objectStatus "ck0n" )
				)
				( pin "J9L2.74"
					( objectStatus "ck0p" )
				)
				( pin "J9L2.219"
					( objectStatus "ck1n" )
				)
				( pin "J9L2.218"
					( objectStatus "ck1p" )
				)
				( pin "J9L2.60"
					( objectStatus "cke(0)" )
				)
				( pin "J9L2.203"
					( objectStatus "cke(1)" )
				)
				( pin "J9L2.5"
					( objectStatus "dq(0)" )
				)
				( pin "J9L2.150"
					( objectStatus "dq(1)" )
				)
				( pin "J9L2.12"
					( objectStatus "dq(2)" )
				)
				( pin "J9L2.157"
					( objectStatus "dq(3)" )
				)
				( pin "J9L2.3"
					( objectStatus "dq(4)" )
				)
				( pin "J9L2.148"
					( objectStatus "dq(5)" )
				)
				( pin "J9L2.10"
					( objectStatus "dq(6)" )
				)
				( pin "J9L2.155"
					( objectStatus "dq(7)" )
				)
				( pin "J9L2.16"
					( objectStatus "dq(8)" )
				)
				( pin "J9L2.161"
					( objectStatus "dq(9)" )
				)
				( pin "J9L2.23"
					( objectStatus "dq(10)" )
				)
				( pin "J9L2.168"
					( objectStatus "dq(11)" )
				)
				( pin "J9L2.14"
					( objectStatus "dq(12)" )
				)
				( pin "J9L2.159"
					( objectStatus "dq(13)" )
				)
				( pin "J9L2.21"
					( objectStatus "dq(14)" )
				)
				( pin "J9L2.166"
					( objectStatus "dq(15)" )
				)
				( pin "J9L2.27"
					( objectStatus "dq(16)" )
				)
				( pin "J9L2.172"
					( objectStatus "dq(17)" )
				)
				( pin "J9L2.34"
					( objectStatus "dq(18)" )
				)
				( pin "J9L2.179"
					( objectStatus "dq(19)" )
				)
				( pin "J9L2.25"
					( objectStatus "dq(20)" )
				)
				( pin "J9L2.170"
					( objectStatus "dq(21)" )
				)
				( pin "J9L2.32"
					( objectStatus "dq(22)" )
				)
				( pin "J9L2.177"
					( objectStatus "dq(23)" )
				)
				( pin "J9L2.38"
					( objectStatus "dq(24)" )
				)
				( pin "J9L2.183"
					( objectStatus "dq(25)" )
				)
				( pin "J9L2.45"
					( objectStatus "dq(26)" )
				)
				( pin "J9L2.190"
					( objectStatus "dq(27)" )
				)
				( pin "J9L2.36"
					( objectStatus "dq(28)" )
				)
				( pin "J9L2.181"
					( objectStatus "dq(29)" )
				)
				( pin "J9L2.43"
					( objectStatus "dq(30)" )
				)
				( pin "J9L2.188"
					( objectStatus "dq(31)" )
				)
				( pin "J9L2.97"
					( objectStatus "dq(32)" )
				)
				( pin "J9L2.242"
					( objectStatus "dq(33)" )
				)
				( pin "J9L2.104"
					( objectStatus "dq(34)" )
				)
				( pin "J9L2.249"
					( objectStatus "dq(35)" )
				)
				( pin "J9L2.95"
					( objectStatus "dq(36)" )
				)
				( pin "J9L2.240"
					( objectStatus "dq(37)" )
				)
				( pin "J9L2.102"
					( objectStatus "dq(38)" )
				)
				( pin "J9L2.247"
					( objectStatus "dq(39)" )
				)
				( pin "J9L2.108"
					( objectStatus "dq(40)" )
				)
				( pin "J9L2.253"
					( objectStatus "dq(41)" )
				)
				( pin "J9L2.115"
					( objectStatus "dq(42)" )
				)
				( pin "J9L2.260"
					( objectStatus "dq(43)" )
				)
				( pin "J9L2.106"
					( objectStatus "dq(44)" )
				)
				( pin "J9L2.251"
					( objectStatus "dq(45)" )
				)
				( pin "J9L2.113"
					( objectStatus "dq(46)" )
				)
				( pin "J9L2.258"
					( objectStatus "dq(47)" )
				)
				( pin "J9L2.119"
					( objectStatus "dq(48)" )
				)
				( pin "J9L2.264"
					( objectStatus "dq(49)" )
				)
				( pin "J9L2.126"
					( objectStatus "dq(50)" )
				)
				( pin "J9L2.271"
					( objectStatus "dq(51)" )
				)
				( pin "J9L2.117"
					( objectStatus "dq(52)" )
				)
				( pin "J9L2.262"
					( objectStatus "dq(53)" )
				)
				( pin "J9L2.124"
					( objectStatus "dq(54)" )
				)
				( pin "J9L2.269"
					( objectStatus "dq(55)" )
				)
				( pin "J9L2.130"
					( objectStatus "dq(56)" )
				)
				( pin "J9L2.275"
					( objectStatus "dq(57)" )
				)
				( pin "J9L2.137"
					( objectStatus "dq(58)" )
				)
				( pin "J9L2.282"
					( objectStatus "dq(59)" )
				)
				( pin "J9L2.128"
					( objectStatus "dq(60)" )
				)
				( pin "J9L2.273"
					( objectStatus "dq(61)" )
				)
				( pin "J9L2.135"
					( objectStatus "dq(62)" )
				)
				( pin "J9L2.280"
					( objectStatus "dq(63)" )
				)
				( pin "J9L2.78"
					( objectStatus "event_n" )
				)
				( pin "J9L2.87"
					( objectStatus "odt(0)" )
				)
				( pin "J9L2.91"
					( objectStatus "odt(1)" )
				)
				( pin "J9L2.222"
					( objectStatus "par" )
				)
				( pin "J9L2.58"
					( objectStatus "reset_n" )
				)
				( pin "J9L2.205"
					( objectStatus "rfu(0)" )
				)
				( pin "J9L2.227"
					( objectStatus "rfu(1)" )
				)
				( pin "J9L2.144"
					( objectStatus "rfu(2)" )
				)
				( pin "J9L2.84"
					( objectStatus "s0_n" )
				)
				( pin "J9L2.89"
					( objectStatus "s1_n" )
				)
				( pin "J9L2.93"
					( objectStatus "s2_n_c(0)" )
				)
				( pin "J9L2.237"
					( objectStatus "s3_n_c(1)" )
				)
				( pin "J9L2.139"
					( objectStatus "sa(0)" )
				)
				( pin "J9L2.140"
					( objectStatus "sa(1)" )
				)
				( pin "J9L2.238"
					( objectStatus "sa(2)" )
				)
				( pin "J9L2.230"
					( objectStatus "save_n_nc" )
				)
				( pin "J9L2.141"
					( objectStatus "scl" )
				)
				( pin "J9L2.285"
					( objectStatus "sda" )
				)
				( pin "J9L2.284"
					( objectStatus "vddspd" )
				)
				( pin "J9L2.146"
					( objectStatus "vrefca" )
				)
			)
			( gate "J9L2"
				( objectStatus "@baseboard_fab2_lib.baseboard_fab2(sch_1):page86_i55" )
				( pin "J9L2.145"
					( objectStatus "\12v\(0)" )
				)
				( pin "J9L2.1"
					( objectStatus "\12v\(1)" )
				)
				( pin "J9L2.236"
					( objectStatus "vdd(0)" )
				)
				( pin "J9L2.233"
					( objectStatus "vdd(1)" )
				)
				( pin "J9L2.231"
					( objectStatus "vdd(2)" )
				)
				( pin "J9L2.229"
					( objectStatus "vdd(3)" )
				)
				( pin "J9L2.226"
					( objectStatus "vdd(4)" )
				)
				( pin "J9L2.223"
					( objectStatus "vdd(5)" )
				)
				( pin "J9L2.220"
					( objectStatus "vdd(6)" )
				)
				( pin "J9L2.217"
					( objectStatus "vdd(7)" )
				)
				( pin "J9L2.215"
					( objectStatus "vdd(8)" )
				)
				( pin "J9L2.212"
					( objectStatus "vdd(9)" )
				)
				( pin "J9L2.209"
					( objectStatus "vdd(10)" )
				)
				( pin "J9L2.206"
					( objectStatus "vdd(11)" )
				)
				( pin "J9L2.204"
					( objectStatus "vdd(12)" )
				)
				( pin "J9L2.92"
					( objectStatus "vdd(13)" )
				)
				( pin "J9L2.90"
					( objectStatus "vdd(14)" )
				)
				( pin "J9L2.88"
					( objectStatus "vdd(15)" )
				)
				( pin "J9L2.85"
					( objectStatus "vdd(16)" )
				)
				( pin "J9L2.83"
					( objectStatus "vdd(17)" )
				)
				( pin "J9L2.80"
					( objectStatus "vdd(18)" )
				)
				( pin "J9L2.76"
					( objectStatus "vdd(19)" )
				)
				( pin "J9L2.73"
					( objectStatus "vdd(20)" )
				)
				( pin "J9L2.70"
					( objectStatus "vdd(21)" )
				)
				( pin "J9L2.67"
					( objectStatus "vdd(22)" )
				)
				( pin "J9L2.64"
					( objectStatus "vdd(23)" )
				)
				( pin "J9L2.61"
					( objectStatus "vdd(24)" )
				)
				( pin "J9L2.59"
					( objectStatus "vdd(25)" )
				)
				( pin "J9L2.287"
					( objectStatus "vpp(0)" )
				)
				( pin "J9L2.286"
					( objectStatus "vpp(1)" )
				)
				( pin "J9L2.288"
					( objectStatus "vpp(2)" )
				)
				( pin "J9L2.143"
					( objectStatus "vpp(3)" )
				)
				( pin "J9L2.142"
					( objectStatus "vpp(4)" )
				)
				( pin "J9L2.221"
					( objectStatus "vtt(0)" )
				)
				( pin "J9L2.77"
					( objectStatus "vtt(1)" )
				)
			)
			( gate "J9L2"
				( objectStatus "@baseboard_fab2_lib.baseboard_fab2(sch_1):page86_i100" )
				( pin "J9L2.152"
					( objectStatus "dqs0n" )
				)
				( pin "J9L2.153"
					( objectStatus "dqs0p" )
				)
				( pin "J9L2.163"
					( objectStatus "dqs1n" )
				)
				( pin "J9L2.164"
					( objectStatus "dqs1p" )
				)
				( pin "J9L2.174"
					( objectStatus "dqs2n" )
				)
				( pin "J9L2.175"
					( objectStatus "dqs2p" )
				)
				( pin "J9L2.185"
					( objectStatus "dqs3n" )
				)
				( pin "J9L2.186"
					( objectStatus "dqs3p" )
				)
				( pin "J9L2.244"
					( objectStatus "dqs4n" )
				)
				( pin "J9L2.245"
					( objectStatus "dqs4p" )
				)
				( pin "J9L2.255"
					( objectStatus "dqs5n" )
				)
				( pin "J9L2.256"
					( objectStatus "dqs5p" )
				)
				( pin "J9L2.266"
					( objectStatus "dqs6n" )
				)
				( pin "J9L2.267"
					( objectStatus "dqs6p" )
				)
				( pin "J9L2.277"
					( objectStatus "dqs7n" )
				)
				( pin "J9L2.278"
					( objectStatus "dqs7p" )
				)
				( pin "J9L2.196"
					( objectStatus "dqs8n" )
				)
				( pin "J9L2.197"
					( objectStatus "dqs8p" )
				)
				( pin "J9L2.8"
					( objectStatus "dqs9n" )
				)
				( pin "J9L2.7"
					( objectStatus "dqs9p" )
				)
				( pin "J9L2.19"
					( objectStatus "dqs10n" )
				)
				( pin "J9L2.18"
					( objectStatus "dqs10p" )
				)
				( pin "J9L2.30"
					( objectStatus "dqs11n" )
				)
				( pin "J9L2.29"
					( objectStatus "dqs11p" )
				)
				( pin "J9L2.41"
					( objectStatus "dqs12n" )
				)
				( pin "J9L2.40"
					( objectStatus "dqs12p" )
				)
				( pin "J9L2.100"
					( objectStatus "dqs13n" )
				)
				( pin "J9L2.99"
					( objectStatus "dqs13p" )
				)
				( pin "J9L2.111"
					( objectStatus "dqs14n" )
				)
				( pin "J9L2.110"
					( objectStatus "dqs14p" )
				)
				( pin "J9L2.122"
					( objectStatus "dqs15n" )
				)
				( pin "J9L2.121"
					( objectStatus "dqs15p" )
				)
				( pin "J9L2.133"
					( objectStatus "dqs16n" )
				)
				( pin "J9L2.132"
					( objectStatus "dqs16p" )
				)
				( pin "J9L2.52"
					( objectStatus "dqs17n" )
				)
				( pin "J9L2.51"
					( objectStatus "dqs17p" )
				)
			)
			( gate "J9L2"
				( objectStatus "@baseboard_fab2_lib.baseboard_fab2(sch_1):page86_i138" )
				( pin "J9L2.283"
					( objectStatus "vss(0)" )
				)
				( pin "J9L2.281"
					( objectStatus "vss(1)" )
				)
				( pin "J9L2.279"
					( objectStatus "vss(2)" )
				)
				( pin "J9L2.276"
					( objectStatus "vss(3)" )
				)
				( pin "J9L2.274"
					( objectStatus "vss(4)" )
				)
				( pin "J9L2.272"
					( objectStatus "vss(5)" )
				)
				( pin "J9L2.270"
					( objectStatus "vss(6)" )
				)
				( pin "J9L2.268"
					( objectStatus "vss(7)" )
				)
				( pin "J9L2.265"
					( objectStatus "vss(8)" )
				)
				( pin "J9L2.263"
					( objectStatus "vss(9)" )
				)
				( pin "J9L2.261"
					( objectStatus "vss(10)" )
				)
				( pin "J9L2.259"
					( objectStatus "vss(11)" )
				)
				( pin "J9L2.257"
					( objectStatus "vss(12)" )
				)
				( pin "J9L2.254"
					( objectStatus "vss(13)" )
				)
				( pin "J9L2.252"
					( objectStatus "vss(14)" )
				)
				( pin "J9L2.250"
					( objectStatus "vss(15)" )
				)
				( pin "J9L2.248"
					( objectStatus "vss(16)" )
				)
				( pin "J9L2.246"
					( objectStatus "vss(17)" )
				)
				( pin "J9L2.243"
					( objectStatus "vss(18)" )
				)
				( pin "J9L2.241"
					( objectStatus "vss(19)" )
				)
				( pin "J9L2.239"
					( objectStatus "vss(20)" )
				)
				( pin "J9L2.202"
					( objectStatus "vss(21)" )
				)
				( pin "J9L2.200"
					( objectStatus "vss(22)" )
				)
				( pin "J9L2.198"
					( objectStatus "vss(23)" )
				)
				( pin "J9L2.195"
					( objectStatus "vss(24)" )
				)
				( pin "J9L2.193"
					( objectStatus "vss(25)" )
				)
				( pin "J9L2.191"
					( objectStatus "vss(26)" )
				)
				( pin "J9L2.189"
					( objectStatus "vss(27)" )
				)
				( pin "J9L2.187"
					( objectStatus "vss(28)" )
				)
				( pin "J9L2.184"
					( objectStatus "vss(29)" )
				)
				( pin "J9L2.182"
					( objectStatus "vss(30)" )
				)
				( pin "J9L2.180"
					( objectStatus "vss(31)" )
				)
				( pin "J9L2.178"
					( objectStatus "vss(32)" )
				)
				( pin "J9L2.176"
					( objectStatus "vss(33)" )
				)
				( pin "J9L2.173"
					( objectStatus "vss(34)" )
				)
				( pin "J9L2.171"
					( objectStatus "vss(35)" )
				)
				( pin "J9L2.169"
					( objectStatus "vss(36)" )
				)
				( pin "J9L2.167"
					( objectStatus "vss(37)" )
				)
				( pin "J9L2.165"
					( objectStatus "vss(38)" )
				)
				( pin "J9L2.162"
					( objectStatus "vss(39)" )
				)
				( pin "J9L2.160"
					( objectStatus "vss(40)" )
				)
				( pin "J9L2.158"
					( objectStatus "vss(41)" )
				)
				( pin "J9L2.156"
					( objectStatus "vss(42)" )
				)
				( pin "J9L2.154"
					( objectStatus "vss(43)" )
				)
				( pin "J9L2.151"
					( objectStatus "vss(44)" )
				)
				( pin "J9L2.149"
					( objectStatus "vss(45)" )
				)
				( pin "J9L2.147"
					( objectStatus "vss(46)" )
				)
				( pin "J9L2.138"
					( objectStatus "vss(47)" )
				)
				( pin "J9L2.136"
					( objectStatus "vss(48)" )
				)
				( pin "J9L2.134"
					( objectStatus "vss(49)" )
				)
				( pin "J9L2.131"
					( objectStatus "vss(50)" )
				)
				( pin "J9L2.129"
					( objectStatus "vss(51)" )
				)
				( pin "J9L2.127"
					( objectStatus "vss(52)" )
				)
				( pin "J9L2.125"
					( objectStatus "vss(53)" )
				)
				( pin "J9L2.123"
					( objectStatus "vss(54)" )
				)
				( pin "J9L2.120"
					( objectStatus "vss(55)" )
				)
				( pin "J9L2.118"
					( objectStatus "vss(56)" )
				)
				( pin "J9L2.116"
					( objectStatus "vss(57)" )
				)
				( pin "J9L2.114"
					( objectStatus "vss(58)" )
				)
				( pin "J9L2.112"
					( objectStatus "vss(59)" )
				)
				( pin "J9L2.109"
					( objectStatus "vss(60)" )
				)
				( pin "J9L2.107"
					( objectStatus "vss(61)" )
				)
				( pin "J9L2.105"
					( objectStatus "vss(62)" )
				)
				( pin "J9L2.103"
					( objectStatus "vss(63)" )
				)
				( pin "J9L2.101"
					( objectStatus "vss(64)" )
				)
				( pin "J9L2.98"
					( objectStatus "vss(65)" )
				)
				( pin "J9L2.96"
					( objectStatus "vss(66)" )
				)
				( pin "J9L2.94"
					( objectStatus "vss(67)" )
				)
				( pin "J9L2.57"
					( objectStatus "vss(68)" )
				)
				( pin "J9L2.55"
					( objectStatus "vss(69)" )
				)
				( pin "J9L2.53"
					( objectStatus "vss(70)" )
				)
				( pin "J9L2.50"
					( objectStatus "vss(71)" )
				)
				( pin "J9L2.48"
					( objectStatus "vss(72)" )
				)
				( pin "J9L2.46"
					( objectStatus "vss(73)" )
				)
				( pin "J9L2.44"
					( objectStatus "vss(74)" )
				)
				( pin "J9L2.42"
					( objectStatus "vss(75)" )
				)
				( pin "J9L2.39"
					( objectStatus "vss(76)" )
				)
				( pin "J9L2.37"
					( objectStatus "vss(77)" )
				)
				( pin "J9L2.35"
					( objectStatus "vss(78)" )
				)
				( pin "J9L2.33"
					( objectStatus "vss(79)" )
				)
				( pin "J9L2.31"
					( objectStatus "vss(80)" )
				)
				( pin "J9L2.28"
					( objectStatus "vss(81)" )
				)
				( pin "J9L2.26"
					( objectStatus "vss(82)" )
				)
				( pin "J9L2.24"
					( objectStatus "vss(83)" )
				)
				( pin "J9L2.22"
					( objectStatus "vss(84)" )
				)
				( pin "J9L2.20"
					( objectStatus "vss(85)" )
				)
				( pin "J9L2.17"
					( objectStatus "vss(86)" )
				)
				( pin "J9L2.15"
					( objectStatus "vss(87)" )
				)
				( pin "J9L2.13"
					( objectStatus "vss(88)" )
				)
				( pin "J9L2.11"
					( objectStatus "vss(89)" )
				)
				( pin "J9L2.9"
					( objectStatus "vss(90)" )
				)
				( pin "J9L2.6"
					( objectStatus "vss(91)" )
				)
				( pin "J9L2.4"
					( objectStatus "vss(92)" )
				)
				( pin "J9L2.2"
					( objectStatus "vss(93)" )
				)
			)
			( gate "C1A17"
				( objectStatus "@baseboard_fab2_lib.baseboard_fab2(sch_1):page86_i182" )
				( pin "C1A17.1"
					( objectStatus "a" )
				)
				( pin "C1A17.2"
					( objectStatus "b" )
				)
			)
			( gate "J1A1"
				( objectStatus "@baseboard_fab2_lib.baseboard_fab2(sch_1):page87_i169" )
				( pin "J1A1.145"
					( objectStatus "\12v\(0)" )
				)
				( pin "J1A1.1"
					( objectStatus "\12v\(1)" )
				)
				( pin "J1A1.236"
					( objectStatus "vdd(0)" )
				)
				( pin "J1A1.233"
					( objectStatus "vdd(1)" )
				)
				( pin "J1A1.231"
					( objectStatus "vdd(2)" )
				)
				( pin "J1A1.229"
					( objectStatus "vdd(3)" )
				)
				( pin "J1A1.226"
					( objectStatus "vdd(4)" )
				)
				( pin "J1A1.223"
					( objectStatus "vdd(5)" )
				)
				( pin "J1A1.220"
					( objectStatus "vdd(6)" )
				)
				( pin "J1A1.217"
					( objectStatus "vdd(7)" )
				)
				( pin "J1A1.215"
					( objectStatus "vdd(8)" )
				)
				( pin "J1A1.212"
					( objectStatus "vdd(9)" )
				)
				( pin "J1A1.209"
					( objectStatus "vdd(10)" )
				)
				( pin "J1A1.206"
					( objectStatus "vdd(11)" )
				)
				( pin "J1A1.204"
					( objectStatus "vdd(12)" )
				)
				( pin "J1A1.92"
					( objectStatus "vdd(13)" )
				)
				( pin "J1A1.90"
					( objectStatus "vdd(14)" )
				)
				( pin "J1A1.88"
					( objectStatus "vdd(15)" )
				)
				( pin "J1A1.85"
					( objectStatus "vdd(16)" )
				)
				( pin "J1A1.83"
					( objectStatus "vdd(17)" )
				)
				( pin "J1A1.80"
					( objectStatus "vdd(18)" )
				)
				( pin "J1A1.76"
					( objectStatus "vdd(19)" )
				)
				( pin "J1A1.73"
					( objectStatus "vdd(20)" )
				)
				( pin "J1A1.70"
					( objectStatus "vdd(21)" )
				)
				( pin "J1A1.67"
					( objectStatus "vdd(22)" )
				)
				( pin "J1A1.64"
					( objectStatus "vdd(23)" )
				)
				( pin "J1A1.61"
					( objectStatus "vdd(24)" )
				)
				( pin "J1A1.59"
					( objectStatus "vdd(25)" )
				)
				( pin "J1A1.287"
					( objectStatus "vpp(0)" )
				)
				( pin "J1A1.286"
					( objectStatus "vpp(1)" )
				)
				( pin "J1A1.288"
					( objectStatus "vpp(2)" )
				)
				( pin "J1A1.143"
					( objectStatus "vpp(3)" )
				)
				( pin "J1A1.142"
					( objectStatus "vpp(4)" )
				)
				( pin "J1A1.221"
					( objectStatus "vtt(0)" )
				)
				( pin "J1A1.77"
					( objectStatus "vtt(1)" )
				)
			)
			( gate "C1A5"
				( objectStatus "@baseboard_fab2_lib.baseboard_fab2(sch_1):page87_i178" )
				( pin "C1A5.1"
					( objectStatus "a" )
				)
				( pin "C1A5.2"
					( objectStatus "b" )
				)
			)
			( gate "J1A1"
				( objectStatus "@baseboard_fab2_lib.baseboard_fab2(sch_1):page87_i185" )
				( pin "J1A1.283"
					( objectStatus "vss(0)" )
				)
				( pin "J1A1.281"
					( objectStatus "vss(1)" )
				)
				( pin "J1A1.279"
					( objectStatus "vss(2)" )
				)
				( pin "J1A1.276"
					( objectStatus "vss(3)" )
				)
				( pin "J1A1.274"
					( objectStatus "vss(4)" )
				)
				( pin "J1A1.272"
					( objectStatus "vss(5)" )
				)
				( pin "J1A1.270"
					( objectStatus "vss(6)" )
				)
				( pin "J1A1.268"
					( objectStatus "vss(7)" )
				)
				( pin "J1A1.265"
					( objectStatus "vss(8)" )
				)
				( pin "J1A1.263"
					( objectStatus "vss(9)" )
				)
				( pin "J1A1.261"
					( objectStatus "vss(10)" )
				)
				( pin "J1A1.259"
					( objectStatus "vss(11)" )
				)
				( pin "J1A1.257"
					( objectStatus "vss(12)" )
				)
				( pin "J1A1.254"
					( objectStatus "vss(13)" )
				)
				( pin "J1A1.252"
					( objectStatus "vss(14)" )
				)
				( pin "J1A1.250"
					( objectStatus "vss(15)" )
				)
				( pin "J1A1.248"
					( objectStatus "vss(16)" )
				)
				( pin "J1A1.246"
					( objectStatus "vss(17)" )
				)
				( pin "J1A1.243"
					( objectStatus "vss(18)" )
				)
				( pin "J1A1.241"
					( objectStatus "vss(19)" )
				)
				( pin "J1A1.239"
					( objectStatus "vss(20)" )
				)
				( pin "J1A1.202"
					( objectStatus "vss(21)" )
				)
				( pin "J1A1.200"
					( objectStatus "vss(22)" )
				)
				( pin "J1A1.198"
					( objectStatus "vss(23)" )
				)
				( pin "J1A1.195"
					( objectStatus "vss(24)" )
				)
				( pin "J1A1.193"
					( objectStatus "vss(25)" )
				)
				( pin "J1A1.191"
					( objectStatus "vss(26)" )
				)
				( pin "J1A1.189"
					( objectStatus "vss(27)" )
				)
				( pin "J1A1.187"
					( objectStatus "vss(28)" )
				)
				( pin "J1A1.184"
					( objectStatus "vss(29)" )
				)
				( pin "J1A1.182"
					( objectStatus "vss(30)" )
				)
				( pin "J1A1.180"
					( objectStatus "vss(31)" )
				)
				( pin "J1A1.178"
					( objectStatus "vss(32)" )
				)
				( pin "J1A1.176"
					( objectStatus "vss(33)" )
				)
				( pin "J1A1.173"
					( objectStatus "vss(34)" )
				)
				( pin "J1A1.171"
					( objectStatus "vss(35)" )
				)
				( pin "J1A1.169"
					( objectStatus "vss(36)" )
				)
				( pin "J1A1.167"
					( objectStatus "vss(37)" )
				)
				( pin "J1A1.165"
					( objectStatus "vss(38)" )
				)
				( pin "J1A1.162"
					( objectStatus "vss(39)" )
				)
				( pin "J1A1.160"
					( objectStatus "vss(40)" )
				)
				( pin "J1A1.158"
					( objectStatus "vss(41)" )
				)
				( pin "J1A1.156"
					( objectStatus "vss(42)" )
				)
				( pin "J1A1.154"
					( objectStatus "vss(43)" )
				)
				( pin "J1A1.151"
					( objectStatus "vss(44)" )
				)
				( pin "J1A1.149"
					( objectStatus "vss(45)" )
				)
				( pin "J1A1.147"
					( objectStatus "vss(46)" )
				)
				( pin "J1A1.138"
					( objectStatus "vss(47)" )
				)
				( pin "J1A1.136"
					( objectStatus "vss(48)" )
				)
				( pin "J1A1.134"
					( objectStatus "vss(49)" )
				)
				( pin "J1A1.131"
					( objectStatus "vss(50)" )
				)
				( pin "J1A1.129"
					( objectStatus "vss(51)" )
				)
				( pin "J1A1.127"
					( objectStatus "vss(52)" )
				)
				( pin "J1A1.125"
					( objectStatus "vss(53)" )
				)
				( pin "J1A1.123"
					( objectStatus "vss(54)" )
				)
				( pin "J1A1.120"
					( objectStatus "vss(55)" )
				)
				( pin "J1A1.118"
					( objectStatus "vss(56)" )
				)
				( pin "J1A1.116"
					( objectStatus "vss(57)" )
				)
				( pin "J1A1.114"
					( objectStatus "vss(58)" )
				)
				( pin "J1A1.112"
					( objectStatus "vss(59)" )
				)
				( pin "J1A1.109"
					( objectStatus "vss(60)" )
				)
				( pin "J1A1.107"
					( objectStatus "vss(61)" )
				)
				( pin "J1A1.105"
					( objectStatus "vss(62)" )
				)
				( pin "J1A1.103"
					( objectStatus "vss(63)" )
				)
				( pin "J1A1.101"
					( objectStatus "vss(64)" )
				)
				( pin "J1A1.98"
					( objectStatus "vss(65)" )
				)
				( pin "J1A1.96"
					( objectStatus "vss(66)" )
				)
				( pin "J1A1.94"
					( objectStatus "vss(67)" )
				)
				( pin "J1A1.57"
					( objectStatus "vss(68)" )
				)
				( pin "J1A1.55"
					( objectStatus "vss(69)" )
				)
				( pin "J1A1.53"
					( objectStatus "vss(70)" )
				)
				( pin "J1A1.50"
					( objectStatus "vss(71)" )
				)
				( pin "J1A1.48"
					( objectStatus "vss(72)" )
				)
				( pin "J1A1.46"
					( objectStatus "vss(73)" )
				)
				( pin "J1A1.44"
					( objectStatus "vss(74)" )
				)
				( pin "J1A1.42"
					( objectStatus "vss(75)" )
				)
				( pin "J1A1.39"
					( objectStatus "vss(76)" )
				)
				( pin "J1A1.37"
					( objectStatus "vss(77)" )
				)
				( pin "J1A1.35"
					( objectStatus "vss(78)" )
				)
				( pin "J1A1.33"
					( objectStatus "vss(79)" )
				)
				( pin "J1A1.31"
					( objectStatus "vss(80)" )
				)
				( pin "J1A1.28"
					( objectStatus "vss(81)" )
				)
				( pin "J1A1.26"
					( objectStatus "vss(82)" )
				)
				( pin "J1A1.24"
					( objectStatus "vss(83)" )
				)
				( pin "J1A1.22"
					( objectStatus "vss(84)" )
				)
				( pin "J1A1.20"
					( objectStatus "vss(85)" )
				)
				( pin "J1A1.17"
					( objectStatus "vss(86)" )
				)
				( pin "J1A1.15"
					( objectStatus "vss(87)" )
				)
				( pin "J1A1.13"
					( objectStatus "vss(88)" )
				)
				( pin "J1A1.11"
					( objectStatus "vss(89)" )
				)
				( pin "J1A1.9"
					( objectStatus "vss(90)" )
				)
				( pin "J1A1.6"
					( objectStatus "vss(91)" )
				)
				( pin "J1A1.4"
					( objectStatus "vss(92)" )
				)
				( pin "J1A1.2"
					( objectStatus "vss(93)" )
				)
			)
			( gate "J1A1"
				( objectStatus "@baseboard_fab2_lib.baseboard_fab2(sch_1):page87_i186" )
				( pin "J1A1.79"
					( objectStatus "a0" )
				)
				( pin "J1A1.72"
					( objectStatus "a1" )
				)
				( pin "J1A1.216"
					( objectStatus "a2" )
				)
				( pin "J1A1.71"
					( objectStatus "a3" )
				)
				( pin "J1A1.214"
					( objectStatus "a4" )
				)
				( pin "J1A1.213"
					( objectStatus "a5" )
				)
				( pin "J1A1.69"
					( objectStatus "a6" )
				)
				( pin "J1A1.211"
					( objectStatus "a7" )
				)
				( pin "J1A1.68"
					( objectStatus "a8" )
				)
				( pin "J1A1.66"
					( objectStatus "a9" )
				)
				( pin "J1A1.225"
					( objectStatus "a10" )
				)
				( pin "J1A1.210"
					( objectStatus "a11" )
				)
				( pin "J1A1.65"
					( objectStatus "a12" )
				)
				( pin "J1A1.232"
					( objectStatus "a13" )
				)
				( pin "J1A1.228"
					( objectStatus "a14_we_n" )
				)
				( pin "J1A1.86"
					( objectStatus "a15_cas_n" )
				)
				( pin "J1A1.82"
					( objectStatus "a16_ras_n" )
				)
				( pin "J1A1.234"
					( objectStatus "a17" )
				)
				( pin "J1A1.62"
					( objectStatus "act_n" )
				)
				( pin "J1A1.208"
					( objectStatus "alert_n" )
				)
				( pin "J1A1.81"
					( objectStatus "ba(0)" )
				)
				( pin "J1A1.224"
					( objectStatus "ba(1)" )
				)
				( pin "J1A1.63"
					( objectStatus "bg(0)" )
				)
				( pin "J1A1.207"
					( objectStatus "bg(1)" )
				)
				( pin "J1A1.235"
					( objectStatus "c(2)" )
				)
				( pin "J1A1.49"
					( objectStatus "cb(0)" )
				)
				( pin "J1A1.194"
					( objectStatus "cb(1)" )
				)
				( pin "J1A1.56"
					( objectStatus "cb(2)" )
				)
				( pin "J1A1.201"
					( objectStatus "cb(3)" )
				)
				( pin "J1A1.47"
					( objectStatus "cb(4)" )
				)
				( pin "J1A1.192"
					( objectStatus "cb(5)" )
				)
				( pin "J1A1.54"
					( objectStatus "cb(6)" )
				)
				( pin "J1A1.199"
					( objectStatus "cb(7)" )
				)
				( pin "J1A1.75"
					( objectStatus "ck0n" )
				)
				( pin "J1A1.74"
					( objectStatus "ck0p" )
				)
				( pin "J1A1.219"
					( objectStatus "ck1n" )
				)
				( pin "J1A1.218"
					( objectStatus "ck1p" )
				)
				( pin "J1A1.60"
					( objectStatus "cke(0)" )
				)
				( pin "J1A1.203"
					( objectStatus "cke(1)" )
				)
				( pin "J1A1.5"
					( objectStatus "dq(0)" )
				)
				( pin "J1A1.150"
					( objectStatus "dq(1)" )
				)
				( pin "J1A1.12"
					( objectStatus "dq(2)" )
				)
				( pin "J1A1.157"
					( objectStatus "dq(3)" )
				)
				( pin "J1A1.3"
					( objectStatus "dq(4)" )
				)
				( pin "J1A1.148"
					( objectStatus "dq(5)" )
				)
				( pin "J1A1.10"
					( objectStatus "dq(6)" )
				)
				( pin "J1A1.155"
					( objectStatus "dq(7)" )
				)
				( pin "J1A1.16"
					( objectStatus "dq(8)" )
				)
				( pin "J1A1.161"
					( objectStatus "dq(9)" )
				)
				( pin "J1A1.23"
					( objectStatus "dq(10)" )
				)
				( pin "J1A1.168"
					( objectStatus "dq(11)" )
				)
				( pin "J1A1.14"
					( objectStatus "dq(12)" )
				)
				( pin "J1A1.159"
					( objectStatus "dq(13)" )
				)
				( pin "J1A1.21"
					( objectStatus "dq(14)" )
				)
				( pin "J1A1.166"
					( objectStatus "dq(15)" )
				)
				( pin "J1A1.27"
					( objectStatus "dq(16)" )
				)
				( pin "J1A1.172"
					( objectStatus "dq(17)" )
				)
				( pin "J1A1.34"
					( objectStatus "dq(18)" )
				)
				( pin "J1A1.179"
					( objectStatus "dq(19)" )
				)
				( pin "J1A1.25"
					( objectStatus "dq(20)" )
				)
				( pin "J1A1.170"
					( objectStatus "dq(21)" )
				)
				( pin "J1A1.32"
					( objectStatus "dq(22)" )
				)
				( pin "J1A1.177"
					( objectStatus "dq(23)" )
				)
				( pin "J1A1.38"
					( objectStatus "dq(24)" )
				)
				( pin "J1A1.183"
					( objectStatus "dq(25)" )
				)
				( pin "J1A1.45"
					( objectStatus "dq(26)" )
				)
				( pin "J1A1.190"
					( objectStatus "dq(27)" )
				)
				( pin "J1A1.36"
					( objectStatus "dq(28)" )
				)
				( pin "J1A1.181"
					( objectStatus "dq(29)" )
				)
				( pin "J1A1.43"
					( objectStatus "dq(30)" )
				)
				( pin "J1A1.188"
					( objectStatus "dq(31)" )
				)
				( pin "J1A1.97"
					( objectStatus "dq(32)" )
				)
				( pin "J1A1.242"
					( objectStatus "dq(33)" )
				)
				( pin "J1A1.104"
					( objectStatus "dq(34)" )
				)
				( pin "J1A1.249"
					( objectStatus "dq(35)" )
				)
				( pin "J1A1.95"
					( objectStatus "dq(36)" )
				)
				( pin "J1A1.240"
					( objectStatus "dq(37)" )
				)
				( pin "J1A1.102"
					( objectStatus "dq(38)" )
				)
				( pin "J1A1.247"
					( objectStatus "dq(39)" )
				)
				( pin "J1A1.108"
					( objectStatus "dq(40)" )
				)
				( pin "J1A1.253"
					( objectStatus "dq(41)" )
				)
				( pin "J1A1.115"
					( objectStatus "dq(42)" )
				)
				( pin "J1A1.260"
					( objectStatus "dq(43)" )
				)
				( pin "J1A1.106"
					( objectStatus "dq(44)" )
				)
				( pin "J1A1.251"
					( objectStatus "dq(45)" )
				)
				( pin "J1A1.113"
					( objectStatus "dq(46)" )
				)
				( pin "J1A1.258"
					( objectStatus "dq(47)" )
				)
				( pin "J1A1.119"
					( objectStatus "dq(48)" )
				)
				( pin "J1A1.264"
					( objectStatus "dq(49)" )
				)
				( pin "J1A1.126"
					( objectStatus "dq(50)" )
				)
				( pin "J1A1.271"
					( objectStatus "dq(51)" )
				)
				( pin "J1A1.117"
					( objectStatus "dq(52)" )
				)
				( pin "J1A1.262"
					( objectStatus "dq(53)" )
				)
				( pin "J1A1.124"
					( objectStatus "dq(54)" )
				)
				( pin "J1A1.269"
					( objectStatus "dq(55)" )
				)
				( pin "J1A1.130"
					( objectStatus "dq(56)" )
				)
				( pin "J1A1.275"
					( objectStatus "dq(57)" )
				)
				( pin "J1A1.137"
					( objectStatus "dq(58)" )
				)
				( pin "J1A1.282"
					( objectStatus "dq(59)" )
				)
				( pin "J1A1.128"
					( objectStatus "dq(60)" )
				)
				( pin "J1A1.273"
					( objectStatus "dq(61)" )
				)
				( pin "J1A1.135"
					( objectStatus "dq(62)" )
				)
				( pin "J1A1.280"
					( objectStatus "dq(63)" )
				)
				( pin "J1A1.78"
					( objectStatus "event_n" )
				)
				( pin "J1A1.87"
					( objectStatus "odt(0)" )
				)
				( pin "J1A1.91"
					( objectStatus "odt(1)" )
				)
				( pin "J1A1.222"
					( objectStatus "par" )
				)
				( pin "J1A1.58"
					( objectStatus "reset_n" )
				)
				( pin "J1A1.205"
					( objectStatus "rfu(0)" )
				)
				( pin "J1A1.227"
					( objectStatus "rfu(1)" )
				)
				( pin "J1A1.144"
					( objectStatus "rfu(2)" )
				)
				( pin "J1A1.84"
					( objectStatus "s0_n" )
				)
				( pin "J1A1.89"
					( objectStatus "s1_n" )
				)
				( pin "J1A1.93"
					( objectStatus "s2_n_c(0)" )
				)
				( pin "J1A1.237"
					( objectStatus "s3_n_c(1)" )
				)
				( pin "J1A1.139"
					( objectStatus "sa(0)" )
				)
				( pin "J1A1.140"
					( objectStatus "sa(1)" )
				)
				( pin "J1A1.238"
					( objectStatus "sa(2)" )
				)
				( pin "J1A1.230"
					( objectStatus "save_n_nc" )
				)
				( pin "J1A1.141"
					( objectStatus "scl" )
				)
				( pin "J1A1.285"
					( objectStatus "sda" )
				)
				( pin "J1A1.284"
					( objectStatus "vddspd" )
				)
				( pin "J1A1.146"
					( objectStatus "vrefca" )
				)
			)
			( gate "J1A1"
				( objectStatus "@baseboard_fab2_lib.baseboard_fab2(sch_1):page87_i187" )
				( pin "J1A1.152"
					( objectStatus "dqs0n" )
				)
				( pin "J1A1.153"
					( objectStatus "dqs0p" )
				)
				( pin "J1A1.163"
					( objectStatus "dqs1n" )
				)
				( pin "J1A1.164"
					( objectStatus "dqs1p" )
				)
				( pin "J1A1.174"
					( objectStatus "dqs2n" )
				)
				( pin "J1A1.175"
					( objectStatus "dqs2p" )
				)
				( pin "J1A1.185"
					( objectStatus "dqs3n" )
				)
				( pin "J1A1.186"
					( objectStatus "dqs3p" )
				)
				( pin "J1A1.244"
					( objectStatus "dqs4n" )
				)
				( pin "J1A1.245"
					( objectStatus "dqs4p" )
				)
				( pin "J1A1.255"
					( objectStatus "dqs5n" )
				)
				( pin "J1A1.256"
					( objectStatus "dqs5p" )
				)
				( pin "J1A1.266"
					( objectStatus "dqs6n" )
				)
				( pin "J1A1.267"
					( objectStatus "dqs6p" )
				)
				( pin "J1A1.277"
					( objectStatus "dqs7n" )
				)
				( pin "J1A1.278"
					( objectStatus "dqs7p" )
				)
				( pin "J1A1.196"
					( objectStatus "dqs8n" )
				)
				( pin "J1A1.197"
					( objectStatus "dqs8p" )
				)
				( pin "J1A1.8"
					( objectStatus "dqs9n" )
				)
				( pin "J1A1.7"
					( objectStatus "dqs9p" )
				)
				( pin "J1A1.19"
					( objectStatus "dqs10n" )
				)
				( pin "J1A1.18"
					( objectStatus "dqs10p" )
				)
				( pin "J1A1.30"
					( objectStatus "dqs11n" )
				)
				( pin "J1A1.29"
					( objectStatus "dqs11p" )
				)
				( pin "J1A1.41"
					( objectStatus "dqs12n" )
				)
				( pin "J1A1.40"
					( objectStatus "dqs12p" )
				)
				( pin "J1A1.100"
					( objectStatus "dqs13n" )
				)
				( pin "J1A1.99"
					( objectStatus "dqs13p" )
				)
				( pin "J1A1.111"
					( objectStatus "dqs14n" )
				)
				( pin "J1A1.110"
					( objectStatus "dqs14p" )
				)
				( pin "J1A1.122"
					( objectStatus "dqs15n" )
				)
				( pin "J1A1.121"
					( objectStatus "dqs15p" )
				)
				( pin "J1A1.133"
					( objectStatus "dqs16n" )
				)
				( pin "J1A1.132"
					( objectStatus "dqs16p" )
				)
				( pin "J1A1.52"
					( objectStatus "dqs17n" )
				)
				( pin "J1A1.51"
					( objectStatus "dqs17p" )
				)
			)
			( gate "J9L1"
				( objectStatus "@baseboard_fab2_lib.baseboard_fab2(sch_1):page88_i25" )
				( pin "J9L1.283"
					( objectStatus "vss(0)" )
				)
				( pin "J9L1.281"
					( objectStatus "vss(1)" )
				)
				( pin "J9L1.279"
					( objectStatus "vss(2)" )
				)
				( pin "J9L1.276"
					( objectStatus "vss(3)" )
				)
				( pin "J9L1.274"
					( objectStatus "vss(4)" )
				)
				( pin "J9L1.272"
					( objectStatus "vss(5)" )
				)
				( pin "J9L1.270"
					( objectStatus "vss(6)" )
				)
				( pin "J9L1.268"
					( objectStatus "vss(7)" )
				)
				( pin "J9L1.265"
					( objectStatus "vss(8)" )
				)
				( pin "J9L1.263"
					( objectStatus "vss(9)" )
				)
				( pin "J9L1.261"
					( objectStatus "vss(10)" )
				)
				( pin "J9L1.259"
					( objectStatus "vss(11)" )
				)
				( pin "J9L1.257"
					( objectStatus "vss(12)" )
				)
				( pin "J9L1.254"
					( objectStatus "vss(13)" )
				)
				( pin "J9L1.252"
					( objectStatus "vss(14)" )
				)
				( pin "J9L1.250"
					( objectStatus "vss(15)" )
				)
				( pin "J9L1.248"
					( objectStatus "vss(16)" )
				)
				( pin "J9L1.246"
					( objectStatus "vss(17)" )
				)
				( pin "J9L1.243"
					( objectStatus "vss(18)" )
				)
				( pin "J9L1.241"
					( objectStatus "vss(19)" )
				)
				( pin "J9L1.239"
					( objectStatus "vss(20)" )
				)
				( pin "J9L1.202"
					( objectStatus "vss(21)" )
				)
				( pin "J9L1.200"
					( objectStatus "vss(22)" )
				)
				( pin "J9L1.198"
					( objectStatus "vss(23)" )
				)
				( pin "J9L1.195"
					( objectStatus "vss(24)" )
				)
				( pin "J9L1.193"
					( objectStatus "vss(25)" )
				)
				( pin "J9L1.191"
					( objectStatus "vss(26)" )
				)
				( pin "J9L1.189"
					( objectStatus "vss(27)" )
				)
				( pin "J9L1.187"
					( objectStatus "vss(28)" )
				)
				( pin "J9L1.184"
					( objectStatus "vss(29)" )
				)
				( pin "J9L1.182"
					( objectStatus "vss(30)" )
				)
				( pin "J9L1.180"
					( objectStatus "vss(31)" )
				)
				( pin "J9L1.178"
					( objectStatus "vss(32)" )
				)
				( pin "J9L1.176"
					( objectStatus "vss(33)" )
				)
				( pin "J9L1.173"
					( objectStatus "vss(34)" )
				)
				( pin "J9L1.171"
					( objectStatus "vss(35)" )
				)
				( pin "J9L1.169"
					( objectStatus "vss(36)" )
				)
				( pin "J9L1.167"
					( objectStatus "vss(37)" )
				)
				( pin "J9L1.165"
					( objectStatus "vss(38)" )
				)
				( pin "J9L1.162"
					( objectStatus "vss(39)" )
				)
				( pin "J9L1.160"
					( objectStatus "vss(40)" )
				)
				( pin "J9L1.158"
					( objectStatus "vss(41)" )
				)
				( pin "J9L1.156"
					( objectStatus "vss(42)" )
				)
				( pin "J9L1.154"
					( objectStatus "vss(43)" )
				)
				( pin "J9L1.151"
					( objectStatus "vss(44)" )
				)
				( pin "J9L1.149"
					( objectStatus "vss(45)" )
				)
				( pin "J9L1.147"
					( objectStatus "vss(46)" )
				)
				( pin "J9L1.138"
					( objectStatus "vss(47)" )
				)
				( pin "J9L1.136"
					( objectStatus "vss(48)" )
				)
				( pin "J9L1.134"
					( objectStatus "vss(49)" )
				)
				( pin "J9L1.131"
					( objectStatus "vss(50)" )
				)
				( pin "J9L1.129"
					( objectStatus "vss(51)" )
				)
				( pin "J9L1.127"
					( objectStatus "vss(52)" )
				)
				( pin "J9L1.125"
					( objectStatus "vss(53)" )
				)
				( pin "J9L1.123"
					( objectStatus "vss(54)" )
				)
				( pin "J9L1.120"
					( objectStatus "vss(55)" )
				)
				( pin "J9L1.118"
					( objectStatus "vss(56)" )
				)
				( pin "J9L1.116"
					( objectStatus "vss(57)" )
				)
				( pin "J9L1.114"
					( objectStatus "vss(58)" )
				)
				( pin "J9L1.112"
					( objectStatus "vss(59)" )
				)
				( pin "J9L1.109"
					( objectStatus "vss(60)" )
				)
				( pin "J9L1.107"
					( objectStatus "vss(61)" )
				)
				( pin "J9L1.105"
					( objectStatus "vss(62)" )
				)
				( pin "J9L1.103"
					( objectStatus "vss(63)" )
				)
				( pin "J9L1.101"
					( objectStatus "vss(64)" )
				)
				( pin "J9L1.98"
					( objectStatus "vss(65)" )
				)
				( pin "J9L1.96"
					( objectStatus "vss(66)" )
				)
				( pin "J9L1.94"
					( objectStatus "vss(67)" )
				)
				( pin "J9L1.57"
					( objectStatus "vss(68)" )
				)
				( pin "J9L1.55"
					( objectStatus "vss(69)" )
				)
				( pin "J9L1.53"
					( objectStatus "vss(70)" )
				)
				( pin "J9L1.50"
					( objectStatus "vss(71)" )
				)
				( pin "J9L1.48"
					( objectStatus "vss(72)" )
				)
				( pin "J9L1.46"
					( objectStatus "vss(73)" )
				)
				( pin "J9L1.44"
					( objectStatus "vss(74)" )
				)
				( pin "J9L1.42"
					( objectStatus "vss(75)" )
				)
				( pin "J9L1.39"
					( objectStatus "vss(76)" )
				)
				( pin "J9L1.37"
					( objectStatus "vss(77)" )
				)
				( pin "J9L1.35"
					( objectStatus "vss(78)" )
				)
				( pin "J9L1.33"
					( objectStatus "vss(79)" )
				)
				( pin "J9L1.31"
					( objectStatus "vss(80)" )
				)
				( pin "J9L1.28"
					( objectStatus "vss(81)" )
				)
				( pin "J9L1.26"
					( objectStatus "vss(82)" )
				)
				( pin "J9L1.24"
					( objectStatus "vss(83)" )
				)
				( pin "J9L1.22"
					( objectStatus "vss(84)" )
				)
				( pin "J9L1.20"
					( objectStatus "vss(85)" )
				)
				( pin "J9L1.17"
					( objectStatus "vss(86)" )
				)
				( pin "J9L1.15"
					( objectStatus "vss(87)" )
				)
				( pin "J9L1.13"
					( objectStatus "vss(88)" )
				)
				( pin "J9L1.11"
					( objectStatus "vss(89)" )
				)
				( pin "J9L1.9"
					( objectStatus "vss(90)" )
				)
				( pin "J9L1.6"
					( objectStatus "vss(91)" )
				)
				( pin "J9L1.4"
					( objectStatus "vss(92)" )
				)
				( pin "J9L1.2"
					( objectStatus "vss(93)" )
				)
			)
			( gate "J9L1"
				( objectStatus "@baseboard_fab2_lib.baseboard_fab2(sch_1):page88_i87" )
				( pin "J9L1.152"
					( objectStatus "dqs0n" )
				)
				( pin "J9L1.153"
					( objectStatus "dqs0p" )
				)
				( pin "J9L1.163"
					( objectStatus "dqs1n" )
				)
				( pin "J9L1.164"
					( objectStatus "dqs1p" )
				)
				( pin "J9L1.174"
					( objectStatus "dqs2n" )
				)
				( pin "J9L1.175"
					( objectStatus "dqs2p" )
				)
				( pin "J9L1.185"
					( objectStatus "dqs3n" )
				)
				( pin "J9L1.186"
					( objectStatus "dqs3p" )
				)
				( pin "J9L1.244"
					( objectStatus "dqs4n" )
				)
				( pin "J9L1.245"
					( objectStatus "dqs4p" )
				)
				( pin "J9L1.255"
					( objectStatus "dqs5n" )
				)
				( pin "J9L1.256"
					( objectStatus "dqs5p" )
				)
				( pin "J9L1.266"
					( objectStatus "dqs6n" )
				)
				( pin "J9L1.267"
					( objectStatus "dqs6p" )
				)
				( pin "J9L1.277"
					( objectStatus "dqs7n" )
				)
				( pin "J9L1.278"
					( objectStatus "dqs7p" )
				)
				( pin "J9L1.196"
					( objectStatus "dqs8n" )
				)
				( pin "J9L1.197"
					( objectStatus "dqs8p" )
				)
				( pin "J9L1.8"
					( objectStatus "dqs9n" )
				)
				( pin "J9L1.7"
					( objectStatus "dqs9p" )
				)
				( pin "J9L1.19"
					( objectStatus "dqs10n" )
				)
				( pin "J9L1.18"
					( objectStatus "dqs10p" )
				)
				( pin "J9L1.30"
					( objectStatus "dqs11n" )
				)
				( pin "J9L1.29"
					( objectStatus "dqs11p" )
				)
				( pin "J9L1.41"
					( objectStatus "dqs12n" )
				)
				( pin "J9L1.40"
					( objectStatus "dqs12p" )
				)
				( pin "J9L1.100"
					( objectStatus "dqs13n" )
				)
				( pin "J9L1.99"
					( objectStatus "dqs13p" )
				)
				( pin "J9L1.111"
					( objectStatus "dqs14n" )
				)
				( pin "J9L1.110"
					( objectStatus "dqs14p" )
				)
				( pin "J9L1.122"
					( objectStatus "dqs15n" )
				)
				( pin "J9L1.121"
					( objectStatus "dqs15p" )
				)
				( pin "J9L1.133"
					( objectStatus "dqs16n" )
				)
				( pin "J9L1.132"
					( objectStatus "dqs16p" )
				)
				( pin "J9L1.52"
					( objectStatus "dqs17n" )
				)
				( pin "J9L1.51"
					( objectStatus "dqs17p" )
				)
			)
			( gate "J9L1"
				( objectStatus "@baseboard_fab2_lib.baseboard_fab2(sch_1):page88_i111" )
				( pin "J9L1.79"
					( objectStatus "a0" )
				)
				( pin "J9L1.72"
					( objectStatus "a1" )
				)
				( pin "J9L1.216"
					( objectStatus "a2" )
				)
				( pin "J9L1.71"
					( objectStatus "a3" )
				)
				( pin "J9L1.214"
					( objectStatus "a4" )
				)
				( pin "J9L1.213"
					( objectStatus "a5" )
				)
				( pin "J9L1.69"
					( objectStatus "a6" )
				)
				( pin "J9L1.211"
					( objectStatus "a7" )
				)
				( pin "J9L1.68"
					( objectStatus "a8" )
				)
				( pin "J9L1.66"
					( objectStatus "a9" )
				)
				( pin "J9L1.225"
					( objectStatus "a10" )
				)
				( pin "J9L1.210"
					( objectStatus "a11" )
				)
				( pin "J9L1.65"
					( objectStatus "a12" )
				)
				( pin "J9L1.232"
					( objectStatus "a13" )
				)
				( pin "J9L1.228"
					( objectStatus "a14_we_n" )
				)
				( pin "J9L1.86"
					( objectStatus "a15_cas_n" )
				)
				( pin "J9L1.82"
					( objectStatus "a16_ras_n" )
				)
				( pin "J9L1.234"
					( objectStatus "a17" )
				)
				( pin "J9L1.62"
					( objectStatus "act_n" )
				)
				( pin "J9L1.208"
					( objectStatus "alert_n" )
				)
				( pin "J9L1.81"
					( objectStatus "ba(0)" )
				)
				( pin "J9L1.224"
					( objectStatus "ba(1)" )
				)
				( pin "J9L1.63"
					( objectStatus "bg(0)" )
				)
				( pin "J9L1.207"
					( objectStatus "bg(1)" )
				)
				( pin "J9L1.235"
					( objectStatus "c(2)" )
				)
				( pin "J9L1.49"
					( objectStatus "cb(0)" )
				)
				( pin "J9L1.194"
					( objectStatus "cb(1)" )
				)
				( pin "J9L1.56"
					( objectStatus "cb(2)" )
				)
				( pin "J9L1.201"
					( objectStatus "cb(3)" )
				)
				( pin "J9L1.47"
					( objectStatus "cb(4)" )
				)
				( pin "J9L1.192"
					( objectStatus "cb(5)" )
				)
				( pin "J9L1.54"
					( objectStatus "cb(6)" )
				)
				( pin "J9L1.199"
					( objectStatus "cb(7)" )
				)
				( pin "J9L1.75"
					( objectStatus "ck0n" )
				)
				( pin "J9L1.74"
					( objectStatus "ck0p" )
				)
				( pin "J9L1.219"
					( objectStatus "ck1n" )
				)
				( pin "J9L1.218"
					( objectStatus "ck1p" )
				)
				( pin "J9L1.60"
					( objectStatus "cke(0)" )
				)
				( pin "J9L1.203"
					( objectStatus "cke(1)" )
				)
				( pin "J9L1.5"
					( objectStatus "dq(0)" )
				)
				( pin "J9L1.150"
					( objectStatus "dq(1)" )
				)
				( pin "J9L1.12"
					( objectStatus "dq(2)" )
				)
				( pin "J9L1.157"
					( objectStatus "dq(3)" )
				)
				( pin "J9L1.3"
					( objectStatus "dq(4)" )
				)
				( pin "J9L1.148"
					( objectStatus "dq(5)" )
				)
				( pin "J9L1.10"
					( objectStatus "dq(6)" )
				)
				( pin "J9L1.155"
					( objectStatus "dq(7)" )
				)
				( pin "J9L1.16"
					( objectStatus "dq(8)" )
				)
				( pin "J9L1.161"
					( objectStatus "dq(9)" )
				)
				( pin "J9L1.23"
					( objectStatus "dq(10)" )
				)
				( pin "J9L1.168"
					( objectStatus "dq(11)" )
				)
				( pin "J9L1.14"
					( objectStatus "dq(12)" )
				)
				( pin "J9L1.159"
					( objectStatus "dq(13)" )
				)
				( pin "J9L1.21"
					( objectStatus "dq(14)" )
				)
				( pin "J9L1.166"
					( objectStatus "dq(15)" )
				)
				( pin "J9L1.27"
					( objectStatus "dq(16)" )
				)
				( pin "J9L1.172"
					( objectStatus "dq(17)" )
				)
				( pin "J9L1.34"
					( objectStatus "dq(18)" )
				)
				( pin "J9L1.179"
					( objectStatus "dq(19)" )
				)
				( pin "J9L1.25"
					( objectStatus "dq(20)" )
				)
				( pin "J9L1.170"
					( objectStatus "dq(21)" )
				)
				( pin "J9L1.32"
					( objectStatus "dq(22)" )
				)
				( pin "J9L1.177"
					( objectStatus "dq(23)" )
				)
				( pin "J9L1.38"
					( objectStatus "dq(24)" )
				)
				( pin "J9L1.183"
					( objectStatus "dq(25)" )
				)
				( pin "J9L1.45"
					( objectStatus "dq(26)" )
				)
				( pin "J9L1.190"
					( objectStatus "dq(27)" )
				)
				( pin "J9L1.36"
					( objectStatus "dq(28)" )
				)
				( pin "J9L1.181"
					( objectStatus "dq(29)" )
				)
				( pin "J9L1.43"
					( objectStatus "dq(30)" )
				)
				( pin "J9L1.188"
					( objectStatus "dq(31)" )
				)
				( pin "J9L1.97"
					( objectStatus "dq(32)" )
				)
				( pin "J9L1.242"
					( objectStatus "dq(33)" )
				)
				( pin "J9L1.104"
					( objectStatus "dq(34)" )
				)
				( pin "J9L1.249"
					( objectStatus "dq(35)" )
				)
				( pin "J9L1.95"
					( objectStatus "dq(36)" )
				)
				( pin "J9L1.240"
					( objectStatus "dq(37)" )
				)
				( pin "J9L1.102"
					( objectStatus "dq(38)" )
				)
				( pin "J9L1.247"
					( objectStatus "dq(39)" )
				)
				( pin "J9L1.108"
					( objectStatus "dq(40)" )
				)
				( pin "J9L1.253"
					( objectStatus "dq(41)" )
				)
				( pin "J9L1.115"
					( objectStatus "dq(42)" )
				)
				( pin "J9L1.260"
					( objectStatus "dq(43)" )
				)
				( pin "J9L1.106"
					( objectStatus "dq(44)" )
				)
				( pin "J9L1.251"
					( objectStatus "dq(45)" )
				)
				( pin "J9L1.113"
					( objectStatus "dq(46)" )
				)
				( pin "J9L1.258"
					( objectStatus "dq(47)" )
				)
				( pin "J9L1.119"
					( objectStatus "dq(48)" )
				)
				( pin "J9L1.264"
					( objectStatus "dq(49)" )
				)
				( pin "J9L1.126"
					( objectStatus "dq(50)" )
				)
				( pin "J9L1.271"
					( objectStatus "dq(51)" )
				)
				( pin "J9L1.117"
					( objectStatus "dq(52)" )
				)
				( pin "J9L1.262"
					( objectStatus "dq(53)" )
				)
				( pin "J9L1.124"
					( objectStatus "dq(54)" )
				)
				( pin "J9L1.269"
					( objectStatus "dq(55)" )
				)
				( pin "J9L1.130"
					( objectStatus "dq(56)" )
				)
				( pin "J9L1.275"
					( objectStatus "dq(57)" )
				)
				( pin "J9L1.137"
					( objectStatus "dq(58)" )
				)
				( pin "J9L1.282"
					( objectStatus "dq(59)" )
				)
				( pin "J9L1.128"
					( objectStatus "dq(60)" )
				)
				( pin "J9L1.273"
					( objectStatus "dq(61)" )
				)
				( pin "J9L1.135"
					( objectStatus "dq(62)" )
				)
				( pin "J9L1.280"
					( objectStatus "dq(63)" )
				)
				( pin "J9L1.78"
					( objectStatus "event_n" )
				)
				( pin "J9L1.87"
					( objectStatus "odt(0)" )
				)
				( pin "J9L1.91"
					( objectStatus "odt(1)" )
				)
				( pin "J9L1.222"
					( objectStatus "par" )
				)
				( pin "J9L1.58"
					( objectStatus "reset_n" )
				)
				( pin "J9L1.205"
					( objectStatus "rfu(0)" )
				)
				( pin "J9L1.227"
					( objectStatus "rfu(1)" )
				)
				( pin "J9L1.144"
					( objectStatus "rfu(2)" )
				)
				( pin "J9L1.84"
					( objectStatus "s0_n" )
				)
				( pin "J9L1.89"
					( objectStatus "s1_n" )
				)
				( pin "J9L1.93"
					( objectStatus "s2_n_c(0)" )
				)
				( pin "J9L1.237"
					( objectStatus "s3_n_c(1)" )
				)
				( pin "J9L1.139"
					( objectStatus "sa(0)" )
				)
				( pin "J9L1.140"
					( objectStatus "sa(1)" )
				)
				( pin "J9L1.238"
					( objectStatus "sa(2)" )
				)
				( pin "J9L1.230"
					( objectStatus "save_n_nc" )
				)
				( pin "J9L1.141"
					( objectStatus "scl" )
				)
				( pin "J9L1.285"
					( objectStatus "sda" )
				)
				( pin "J9L1.284"
					( objectStatus "vddspd" )
				)
				( pin "J9L1.146"
					( objectStatus "vrefca" )
				)
			)
			( gate "J9L1"
				( objectStatus "@baseboard_fab2_lib.baseboard_fab2(sch_1):page88_i168" )
				( pin "J9L1.145"
					( objectStatus "\12v\(0)" )
				)
				( pin "J9L1.1"
					( objectStatus "\12v\(1)" )
				)
				( pin "J9L1.236"
					( objectStatus "vdd(0)" )
				)
				( pin "J9L1.233"
					( objectStatus "vdd(1)" )
				)
				( pin "J9L1.231"
					( objectStatus "vdd(2)" )
				)
				( pin "J9L1.229"
					( objectStatus "vdd(3)" )
				)
				( pin "J9L1.226"
					( objectStatus "vdd(4)" )
				)
				( pin "J9L1.223"
					( objectStatus "vdd(5)" )
				)
				( pin "J9L1.220"
					( objectStatus "vdd(6)" )
				)
				( pin "J9L1.217"
					( objectStatus "vdd(7)" )
				)
				( pin "J9L1.215"
					( objectStatus "vdd(8)" )
				)
				( pin "J9L1.212"
					( objectStatus "vdd(9)" )
				)
				( pin "J9L1.209"
					( objectStatus "vdd(10)" )
				)
				( pin "J9L1.206"
					( objectStatus "vdd(11)" )
				)
				( pin "J9L1.204"
					( objectStatus "vdd(12)" )
				)
				( pin "J9L1.92"
					( objectStatus "vdd(13)" )
				)
				( pin "J9L1.90"
					( objectStatus "vdd(14)" )
				)
				( pin "J9L1.88"
					( objectStatus "vdd(15)" )
				)
				( pin "J9L1.85"
					( objectStatus "vdd(16)" )
				)
				( pin "J9L1.83"
					( objectStatus "vdd(17)" )
				)
				( pin "J9L1.80"
					( objectStatus "vdd(18)" )
				)
				( pin "J9L1.76"
					( objectStatus "vdd(19)" )
				)
				( pin "J9L1.73"
					( objectStatus "vdd(20)" )
				)
				( pin "J9L1.70"
					( objectStatus "vdd(21)" )
				)
				( pin "J9L1.67"
					( objectStatus "vdd(22)" )
				)
				( pin "J9L1.64"
					( objectStatus "vdd(23)" )
				)
				( pin "J9L1.61"
					( objectStatus "vdd(24)" )
				)
				( pin "J9L1.59"
					( objectStatus "vdd(25)" )
				)
				( pin "J9L1.287"
					( objectStatus "vpp(0)" )
				)
				( pin "J9L1.286"
					( objectStatus "vpp(1)" )
				)
				( pin "J9L1.288"
					( objectStatus "vpp(2)" )
				)
				( pin "J9L1.143"
					( objectStatus "vpp(3)" )
				)
				( pin "J9L1.142"
					( objectStatus "vpp(4)" )
				)
				( pin "J9L1.221"
					( objectStatus "vtt(0)" )
				)
				( pin "J9L1.77"
					( objectStatus "vtt(1)" )
				)
			)
			( gate "C9L1"
				( objectStatus "@baseboard_fab2_lib.baseboard_fab2(sch_1):page88_i177" )
				( pin "C9L1.1"
					( objectStatus "a" )
				)
				( pin "C9L1.2"
					( objectStatus "b" )
				)
			)
			( gate "R4T2"
				( objectStatus "@baseboard_fab2_lib.baseboard_fab2(sch_1):page89_i1" )
				( pin "R4T2.1"
					( objectStatus "a" )
				)
				( pin "R4T2.2"
					( objectStatus "b" )
				)
			)
			( gate "R4T1"
				( objectStatus "@baseboard_fab2_lib.baseboard_fab2(sch_1):page89_i2" )
				( pin "R4T1.1"
					( objectStatus "a" )
				)
				( pin "R4T1.2"
					( objectStatus "b" )
				)
			)
			( gate "R6F4"
				( objectStatus "@baseboard_fab2_lib.baseboard_fab2(sch_1):page89_i3" )
				( pin "R6F4.1"
					( objectStatus "a" )
				)
				( pin "R6F4.2"
					( objectStatus "b" )
				)
			)
			( gate "R6F1"
				( objectStatus "@baseboard_fab2_lib.baseboard_fab2(sch_1):page89_i4" )
				( pin "R6F1.1"
					( objectStatus "a" )
				)
				( pin "R6F1.2"
					( objectStatus "b" )
				)
			)
			( gate "R6F5"
				( objectStatus "@baseboard_fab2_lib.baseboard_fab2(sch_1):page89_i5" )
				( pin "R6F5.1"
					( objectStatus "a" )
				)
				( pin "R6F5.2"
					( objectStatus "b" )
				)
			)
			( gate "R6F2"
				( objectStatus "@baseboard_fab2_lib.baseboard_fab2(sch_1):page89_i6" )
				( pin "R6F2.1"
					( objectStatus "a" )
				)
				( pin "R6F2.2"
					( objectStatus "b" )
				)
			)
			( gate "R6F3"
				( objectStatus "@baseboard_fab2_lib.baseboard_fab2(sch_1):page89_i7" )
				( pin "R6F3.1"
					( objectStatus "a" )
				)
				( pin "R6F3.2"
					( objectStatus "b" )
				)
			)
			( gate "Q6F1"
				( objectStatus "@baseboard_fab2_lib.baseboard_fab2(sch_1):page89_i18" )
				( pin "Q6F1.3"
					( objectStatus "drn" )
				)
				( pin "Q6F1.1"
					( objectStatus "gate" )
				)
				( pin "Q6F1.2"
					( objectStatus "src" )
				)
			)
			( gate "R2P12"
				( objectStatus "@baseboard_fab2_lib.baseboard_fab2(sch_1):page89_i23" )
				( pin "R2P12.1"
					( objectStatus "a" )
				)
				( pin "R2P12.2"
					( objectStatus "b" )
				)
			)
			( gate "R8D29"
				( objectStatus "@baseboard_fab2_lib.baseboard_fab2(sch_1):page89_i26" )
				( pin "R8D29.1"
					( objectStatus "a" )
				)
				( pin "R8D29.2"
					( objectStatus "b" )
				)
			)
			( gate "R8D31"
				( objectStatus "@baseboard_fab2_lib.baseboard_fab2(sch_1):page89_i27" )
				( pin "R8D31.1"
					( objectStatus "a" )
				)
				( pin "R8D31.2"
					( objectStatus "b" )
				)
			)
			( gate "R8D30"
				( objectStatus "@baseboard_fab2_lib.baseboard_fab2(sch_1):page89_i34" )
				( pin "R8D30.1"
					( objectStatus "a" )
				)
				( pin "R8D30.2"
					( objectStatus "b" )
				)
			)
			( gate "Q8D1"
				( objectStatus "@baseboard_fab2_lib.baseboard_fab2(sch_1):page89_i35" )
				( pin "Q8D1.5"
					( objectStatus "b(0)" )
				)
				( pin "Q8D1.3"
					( objectStatus "c(0)" )
				)
				( pin "Q8D1.4"
					( objectStatus "e(0)" )
				)
			)
			( gate "Q8D1"
				( objectStatus "@baseboard_fab2_lib.baseboard_fab2(sch_1):page89_i36" )
				( pin "Q8D1.2"
					( objectStatus "b(0)" )
				)
				( pin "Q8D1.6"
					( objectStatus "c(0)" )
				)
				( pin "Q8D1.1"
					( objectStatus "e(0)" )
				)
			)
			( gate "R6D6"
				( objectStatus "@baseboard_fab2_lib.baseboard_fab2(sch_1):page90_i3" )
				( pin "R6D6.1"
					( objectStatus "a" )
				)
				( pin "R6D6.2"
					( objectStatus "b" )
				)
			)
			( gate "R4P1"
				( objectStatus "@baseboard_fab2_lib.baseboard_fab2(sch_1):page90_i4" )
				( pin "R4P1.1"
					( objectStatus "a" )
				)
				( pin "R4P1.2"
					( objectStatus "b" )
				)
			)
			( gate "R3D12"
				( objectStatus "@baseboard_fab2_lib.baseboard_fab2(sch_1):page90_i11" )
				( pin "R3D12.1"
					( objectStatus "a" )
				)
				( pin "R3D12.2"
					( objectStatus "b" )
				)
			)
			( gate "R3D13"
				( objectStatus "@baseboard_fab2_lib.baseboard_fab2(sch_1):page90_i12" )
				( pin "R3D13.1"
					( objectStatus "a" )
				)
				( pin "R3D13.2"
					( objectStatus "b" )
				)
			)
			( gate "R3D22"
				( objectStatus "@baseboard_fab2_lib.baseboard_fab2(sch_1):page90_i17" )
				( pin "R3D22.1"
					( objectStatus "a" )
				)
				( pin "R3D22.2"
					( objectStatus "b" )
				)
			)
			( gate "R3D16"
				( objectStatus "@baseboard_fab2_lib.baseboard_fab2(sch_1):page90_i24" )
				( pin "R3D16.1"
					( objectStatus "a" )
				)
				( pin "R3D16.2"
					( objectStatus "b" )
				)
			)
			( gate "R3D23"
				( objectStatus "@baseboard_fab2_lib.baseboard_fab2(sch_1):page90_i25" )
				( pin "R3D23.1"
					( objectStatus "a" )
				)
				( pin "R3D23.2"
					( objectStatus "b" )
				)
			)
			( gate "R3D26"
				( objectStatus "@baseboard_fab2_lib.baseboard_fab2(sch_1):page90_i28" )
				( pin "R3D26.1"
					( objectStatus "a" )
				)
				( pin "R3D26.2"
					( objectStatus "b" )
				)
			)
			( gate "R5D3"
				( objectStatus "@baseboard_fab2_lib.baseboard_fab2(sch_1):page90_i29" )
				( pin "R5D3.1"
					( objectStatus "a" )
				)
				( pin "R5D3.2"
					( objectStatus "b" )
				)
			)
			( gate "R6D7"
				( objectStatus "@baseboard_fab2_lib.baseboard_fab2(sch_1):page90_i31" )
				( pin "R6D7.1"
					( objectStatus "a" )
				)
				( pin "R6D7.2"
					( objectStatus "b" )
				)
			)
			( gate "R5D4"
				( objectStatus "@baseboard_fab2_lib.baseboard_fab2(sch_1):page90_i32" )
				( pin "R5D4.1"
					( objectStatus "a" )
				)
				( pin "R5D4.2"
					( objectStatus "b" )
				)
			)
			( gate "R6D13"
				( objectStatus "@baseboard_fab2_lib.baseboard_fab2(sch_1):page90_i33" )
				( pin "R6D13.1"
					( objectStatus "a" )
				)
				( pin "R6D13.2"
					( objectStatus "b" )
				)
			)
			( gate "R6D15"
				( objectStatus "@baseboard_fab2_lib.baseboard_fab2(sch_1):page90_i48" )
				( pin "R6D15.1"
					( objectStatus "a" )
				)
				( pin "R6D15.2"
					( objectStatus "b" )
				)
			)
			( gate "R6D10"
				( objectStatus "@baseboard_fab2_lib.baseboard_fab2(sch_1):page90_i49" )
				( pin "R6D10.1"
					( objectStatus "a" )
				)
				( pin "R6D10.2"
					( objectStatus "b" )
				)
			)
			( gate "R6D14"
				( objectStatus "@baseboard_fab2_lib.baseboard_fab2(sch_1):page90_i52" )
				( pin "R6D14.1"
					( objectStatus "a" )
				)
				( pin "R6D14.2"
					( objectStatus "b" )
				)
			)
			( gate "R4P14"
				( objectStatus "@baseboard_fab2_lib.baseboard_fab2(sch_1):page90_i53" )
				( pin "R4P14.1"
					( objectStatus "a" )
				)
				( pin "R4P14.2"
					( objectStatus "b" )
				)
			)
			( gate "R3D24"
				( objectStatus "@baseboard_fab2_lib.baseboard_fab2(sch_1):page90_i59" )
				( pin "R3D24.1"
					( objectStatus "a" )
				)
				( pin "R3D24.2"
					( objectStatus "b" )
				)
			)
			( gate "R3D17"
				( objectStatus "@baseboard_fab2_lib.baseboard_fab2(sch_1):page90_i60" )
				( pin "R3D17.1"
					( objectStatus "a" )
				)
				( pin "R3D17.2"
					( objectStatus "b" )
				)
			)
			( gate "R3D25"
				( objectStatus "@baseboard_fab2_lib.baseboard_fab2(sch_1):page90_i66" )
				( pin "R3D25.1"
					( objectStatus "a" )
				)
				( pin "R3D25.2"
					( objectStatus "b" )
				)
			)
			( gate "R4P6"
				( objectStatus "@baseboard_fab2_lib.baseboard_fab2(sch_1):page90_i68" )
				( pin "R4P6.1"
					( objectStatus "a" )
				)
				( pin "R4P6.2"
					( objectStatus "b" )
				)
			)
			( gate "R7P14"
				( objectStatus "@baseboard_fab2_lib.baseboard_fab2(sch_1):page90_i70" )
				( pin "R7P14.1"
					( objectStatus "a" )
				)
				( pin "R7P14.2"
					( objectStatus "b" )
				)
			)
			( gate "R4P7"
				( objectStatus "@baseboard_fab2_lib.baseboard_fab2(sch_1):page90_i72" )
				( pin "R4P7.1"
					( objectStatus "a" )
				)
				( pin "R4P7.2"
					( objectStatus "b" )
				)
			)
			( gate "R7P15"
				( objectStatus "@baseboard_fab2_lib.baseboard_fab2(sch_1):page90_i74" )
				( pin "R7P15.1"
					( objectStatus "a" )
				)
				( pin "R7P15.2"
					( objectStatus "b" )
				)
			)
			( gate "R7P22"
				( objectStatus "@baseboard_fab2_lib.baseboard_fab2(sch_1):page90_i76" )
				( pin "R7P22.1"
					( objectStatus "a" )
				)
				( pin "R7P22.2"
					( objectStatus "b" )
				)
			)
			( gate "R5P2"
				( objectStatus "@baseboard_fab2_lib.baseboard_fab2(sch_1):page90_i79" )
				( pin "R5P2.1"
					( objectStatus "a" )
				)
				( pin "R5P2.2"
					( objectStatus "b" )
				)
			)
			( gate "R5P3"
				( objectStatus "@baseboard_fab2_lib.baseboard_fab2(sch_1):page90_i80" )
				( pin "R5P3.1"
					( objectStatus "a" )
				)
				( pin "R5P3.2"
					( objectStatus "b" )
				)
			)
			( gate "R6D5"
				( objectStatus "@baseboard_fab2_lib.baseboard_fab2(sch_1):page90_i81" )
				( pin "R6D5.1"
					( objectStatus "a" )
				)
				( pin "R6D5.2"
					( objectStatus "b" )
				)
			)
			( gate "R8P1"
				( objectStatus "@baseboard_fab2_lib.baseboard_fab2(sch_1):page90_i85" )
				( pin "R8P1.1"
					( objectStatus "a" )
				)
				( pin "R8P1.2"
					( objectStatus "b" )
				)
			)
			( gate "R8P2"
				( objectStatus "@baseboard_fab2_lib.baseboard_fab2(sch_1):page90_i86" )
				( pin "R8P2.1"
					( objectStatus "a" )
				)
				( pin "R8P2.2"
					( objectStatus "b" )
				)
			)
			( gate "R3D9"
				( objectStatus "@baseboard_fab2_lib.baseboard_fab2(sch_1):page90_i88" )
				( pin "R3D9.1"
					( objectStatus "a" )
				)
				( pin "R3D9.2"
					( objectStatus "b" )
				)
			)
			( gate "J8B1"
				( objectStatus "@baseboard_fab2_lib.baseboard_fab2(sch_1):page91_i1" )
				( pin "J8B1.1"
					( objectStatus "io1" )
				)
				( pin "J8B1.2"
					( objectStatus "io2" )
				)
				( pin "J8B1.3"
					( objectStatus "io3" )
				)
				( pin "J8B1.4"
					( objectStatus "io4" )
				)
				( pin "J8B1.5"
					( objectStatus "io5" )
				)
				( pin "J8B1.6"
					( objectStatus "io6" )
				)
				( pin "J8B1.7"
					( objectStatus "io7" )
				)
				( pin "J8B1.8"
					( objectStatus "io8" )
				)
				( pin "J8B1.9"
					( objectStatus "io9" )
				)
				( pin "J8B1.10"
					( objectStatus "io10" )
				)
				( pin "J8B1.11"
					( objectStatus "io11" )
				)
				( pin "J8B1.12"
					( objectStatus "io12" )
				)
				( pin "J8B1.13"
					( objectStatus "io13" )
				)
				( pin "J8B1.14"
					( objectStatus "io14" )
				)
				( pin "J8B1.15"
					( objectStatus "io15" )
				)
				( pin "J8B1.16"
					( objectStatus "io16" )
				)
				( pin "J8B1.17"
					( objectStatus "io17" )
				)
				( pin "J8B1.18"
					( objectStatus "io18" )
				)
				( pin "J8B1.19"
					( objectStatus "io19" )
				)
				( pin "J8B1.20"
					( objectStatus "io20" )
				)
				( pin "J8B1.21"
					( objectStatus "io21" )
				)
				( pin "J8B1.22"
					( objectStatus "io22" )
				)
				( pin "J8B1.23"
					( objectStatus "io23" )
				)
				( pin "J8B1.24"
					( objectStatus "io24" )
				)
				( pin "J8B1.MP1"
					( objectStatus "mp1" )
				)
				( pin "J8B1.MP2"
					( objectStatus "mp2" )
				)
			)
			( gate "R8B8"
				( objectStatus "@baseboard_fab2_lib.baseboard_fab2(sch_1):page91_i14" )
				( pin "R8B8.1"
					( objectStatus "a" )
				)
				( pin "R8B8.2"
					( objectStatus "b" )
				)
			)
			( gate "R8B10"
				( objectStatus "@baseboard_fab2_lib.baseboard_fab2(sch_1):page91_i16" )
				( pin "R8B10.1"
					( objectStatus "a" )
				)
				( pin "R8B10.2"
					( objectStatus "b" )
				)
			)
			( gate "R8B16"
				( objectStatus "@baseboard_fab2_lib.baseboard_fab2(sch_1):page91_i17" )
				( pin "R8B16.1"
					( objectStatus "a" )
				)
				( pin "R8B16.2"
					( objectStatus "b" )
				)
			)
			( gate "R8B17"
				( objectStatus "@baseboard_fab2_lib.baseboard_fab2(sch_1):page91_i18" )
				( pin "R8B17.1"
					( objectStatus "a" )
				)
				( pin "R8B17.2"
					( objectStatus "b" )
				)
			)
			( gate "R8B18"
				( objectStatus "@baseboard_fab2_lib.baseboard_fab2(sch_1):page91_i20" )
				( pin "R8B18.1"
					( objectStatus "a" )
				)
				( pin "R8B18.2"
					( objectStatus "b" )
				)
			)
			( gate "R8B19"
				( objectStatus "@baseboard_fab2_lib.baseboard_fab2(sch_1):page91_i21" )
				( pin "R8B19.1"
					( objectStatus "a" )
				)
				( pin "R8B19.2"
					( objectStatus "b" )
				)
			)
			( gate "R8B5"
				( objectStatus "@baseboard_fab2_lib.baseboard_fab2(sch_1):page91_i22" )
				( pin "R8B5.1"
					( objectStatus "a" )
				)
				( pin "R8B5.2"
					( objectStatus "b" )
				)
			)
			( gate "R8B3"
				( objectStatus "@baseboard_fab2_lib.baseboard_fab2(sch_1):page91_i24" )
				( pin "R8B3.1"
					( objectStatus "a" )
				)
				( pin "R8B3.2"
					( objectStatus "b" )
				)
			)
			( gate "R8B13"
				( objectStatus "@baseboard_fab2_lib.baseboard_fab2(sch_1):page91_i34" )
				( pin "R8B13.1"
					( objectStatus "a" )
				)
				( pin "R8B13.2"
					( objectStatus "b" )
				)
			)
			( gate "R8B11"
				( objectStatus "@baseboard_fab2_lib.baseboard_fab2(sch_1):page91_i35" )
				( pin "R8B11.1"
					( objectStatus "a" )
				)
				( pin "R8B11.2"
					( objectStatus "b" )
				)
			)
			( gate "R8B7"
				( objectStatus "@baseboard_fab2_lib.baseboard_fab2(sch_1):page91_i36" )
				( pin "R8B7.1"
					( objectStatus "a" )
				)
				( pin "R8B7.2"
					( objectStatus "b" )
				)
			)
			( gate "R8B6"
				( objectStatus "@baseboard_fab2_lib.baseboard_fab2(sch_1):page91_i37" )
				( pin "R8B6.1"
					( objectStatus "a" )
				)
				( pin "R8B6.2"
					( objectStatus "b" )
				)
			)
			( gate "U3P2"
				( objectStatus "@baseboard_fab2_lib.baseboard_fab2(sch_1):page92_i1" )
				( pin "U3P2.13"
					( objectStatus "a0" )
				)
				( pin "U3P2.12"
					( objectStatus "a1" )
				)
				( pin "U3P2.10"
					( objectStatus "a2" )
				)
				( pin "U3P2.9"
					( objectStatus "a3" )
				)
				( pin "U3P2.2"
					( objectStatus "b0" )
				)
				( pin "U3P2.3"
					( objectStatus "b1" )
				)
				( pin "U3P2.5"
					( objectStatus "b2" )
				)
				( pin "U3P2.6"
					( objectStatus "b3" )
				)
				( pin "U3P2.1"
					( objectStatus "dir" )
				)
				( pin "U3P2.7"
					( objectStatus "gnd(0)" )
				)
				( pin "U3P2.8"
					( objectStatus "gnd(1)" )
				)
				( pin "U3P2.11"
					( objectStatus "gnd(2)" )
				)
				( pin "U3P2.14"
					( objectStatus "vcc" )
				)
				( pin "U3P2.4"
					( objectStatus "vref" )
				)
			)
			( gate "R3P41"
				( objectStatus "@baseboard_fab2_lib.baseboard_fab2(sch_1):page92_i9" )
				( pin "R3P41.1"
					( objectStatus "a" )
				)
				( pin "R3P41.2"
					( objectStatus "b" )
				)
			)
			( gate "R3P46"
				( objectStatus "@baseboard_fab2_lib.baseboard_fab2(sch_1):page92_i12" )
				( pin "R3P46.1"
					( objectStatus "a" )
				)
				( pin "R3P46.2"
					( objectStatus "b" )
				)
			)
			( gate "R3P43"
				( objectStatus "@baseboard_fab2_lib.baseboard_fab2(sch_1):page92_i13" )
				( pin "R3P43.1"
					( objectStatus "a" )
				)
				( pin "R3P43.2"
					( objectStatus "b" )
				)
			)
			( gate "R3P42"
				( objectStatus "@baseboard_fab2_lib.baseboard_fab2(sch_1):page92_i14" )
				( pin "R3P42.1"
					( objectStatus "a" )
				)
				( pin "R3P42.2"
					( objectStatus "b" )
				)
			)
			( gate "R7E2"
				( objectStatus "@baseboard_fab2_lib.baseboard_fab2(sch_1):page92_i19" )
				( pin "R7E2.1"
					( objectStatus "a" )
				)
				( pin "R7E2.2"
					( objectStatus "b" )
				)
			)
			( gate "R7D34"
				( objectStatus "@baseboard_fab2_lib.baseboard_fab2(sch_1):page92_i24" )
				( pin "R7D34.1"
					( objectStatus "a" )
				)
				( pin "R7D34.2"
					( objectStatus "b" )
				)
			)
			( gate "R7D31"
				( objectStatus "@baseboard_fab2_lib.baseboard_fab2(sch_1):page92_i29" )
				( pin "R7D31.1"
					( objectStatus "a" )
				)
				( pin "R7D31.2"
					( objectStatus "b" )
				)
			)
			( gate "R7D29"
				( objectStatus "@baseboard_fab2_lib.baseboard_fab2(sch_1):page92_i30" )
				( pin "R7D29.1"
					( objectStatus "a" )
				)
				( pin "R7D29.2"
					( objectStatus "b" )
				)
			)
			( gate "U7D2"
				( objectStatus "@baseboard_fab2_lib.baseboard_fab2(sch_1):page92_i32" )
				( pin "U7D2.13"
					( objectStatus "a0" )
				)
				( pin "U7D2.12"
					( objectStatus "a1" )
				)
				( pin "U7D2.10"
					( objectStatus "a2" )
				)
				( pin "U7D2.9"
					( objectStatus "a3" )
				)
				( pin "U7D2.2"
					( objectStatus "b0" )
				)
				( pin "U7D2.3"
					( objectStatus "b1" )
				)
				( pin "U7D2.5"
					( objectStatus "b2" )
				)
				( pin "U7D2.6"
					( objectStatus "b3" )
				)
				( pin "U7D2.1"
					( objectStatus "dir" )
				)
				( pin "U7D2.7"
					( objectStatus "gnd(0)" )
				)
				( pin "U7D2.8"
					( objectStatus "gnd(1)" )
				)
				( pin "U7D2.11"
					( objectStatus "gnd(2)" )
				)
				( pin "U7D2.14"
					( objectStatus "vcc" )
				)
				( pin "U7D2.4"
					( objectStatus "vref" )
				)
			)
			( gate "C3P49"
				( objectStatus "@baseboard_fab2_lib.baseboard_fab2(sch_1):page92_i37" )
				( pin "C3P49.1"
					( objectStatus "a" )
				)
				( pin "C3P49.2"
					( objectStatus "b" )
				)
			)
			( gate "R3P49"
				( objectStatus "@baseboard_fab2_lib.baseboard_fab2(sch_1):page92_i38" )
				( pin "R3P49.1"
					( objectStatus "a" )
				)
				( pin "R3P49.2"
					( objectStatus "b" )
				)
			)
			( gate "R3P45"
				( objectStatus "@baseboard_fab2_lib.baseboard_fab2(sch_1):page92_i39" )
				( pin "R3P45.1"
					( objectStatus "a" )
				)
				( pin "R3P45.2"
					( objectStatus "b" )
				)
			)
			( gate "R3R1"
				( objectStatus "@baseboard_fab2_lib.baseboard_fab2(sch_1):page92_i46" )
				( pin "R3R1.1"
					( objectStatus "a" )
				)
				( pin "R3R1.2"
					( objectStatus "b" )
				)
			)
			( gate "R7D32"
				( objectStatus "@baseboard_fab2_lib.baseboard_fab2(sch_1):page92_i48" )
				( pin "R7D32.1"
					( objectStatus "a" )
				)
				( pin "R7D32.2"
					( objectStatus "b" )
				)
			)
			( gate "R7D33"
				( objectStatus "@baseboard_fab2_lib.baseboard_fab2(sch_1):page92_i51" )
				( pin "R7D33.1"
					( objectStatus "a" )
				)
				( pin "R7D33.2"
					( objectStatus "b" )
				)
			)
			( gate "C7D5"
				( objectStatus "@baseboard_fab2_lib.baseboard_fab2(sch_1):page92_i52" )
				( pin "C7D5.1"
					( objectStatus "a" )
				)
				( pin "C7D5.2"
					( objectStatus "b" )
				)
			)
			( gate "R7D26"
				( objectStatus "@baseboard_fab2_lib.baseboard_fab2(sch_1):page92_i54" )
				( pin "R7D26.1"
					( objectStatus "a" )
				)
				( pin "R7D26.2"
					( objectStatus "b" )
				)
			)
			( gate "R3R3"
				( objectStatus "@baseboard_fab2_lib.baseboard_fab2(sch_1):page92_i61" )
				( pin "R3R3.1"
					( objectStatus "a" )
				)
				( pin "R3R3.2"
					( objectStatus "b" )
				)
			)
			( gate "R6D9"
				( objectStatus "@baseboard_fab2_lib.baseboard_fab2(sch_1):page92_i64" )
				( pin "R6D9.1"
					( objectStatus "a" )
				)
				( pin "R6D9.2"
					( objectStatus "b" )
				)
			)
			( gate "R7P27"
				( objectStatus "@baseboard_fab2_lib.baseboard_fab2(sch_1):page92_i65" )
				( pin "R7P27.1"
					( objectStatus "a" )
				)
				( pin "R7P27.2"
					( objectStatus "b" )
				)
			)
			( gate "R7D28"
				( objectStatus "@baseboard_fab2_lib.baseboard_fab2(sch_1):page92_i67" )
				( pin "R7D28.1"
					( objectStatus "a" )
				)
				( pin "R7D28.2"
					( objectStatus "b" )
				)
			)
			( gate "R7D27"
				( objectStatus "@baseboard_fab2_lib.baseboard_fab2(sch_1):page92_i68" )
				( pin "R7D27.1"
					( objectStatus "a" )
				)
				( pin "R7D27.2"
					( objectStatus "b" )
				)
			)
			( gate "R7D25"
				( objectStatus "@baseboard_fab2_lib.baseboard_fab2(sch_1):page92_i70" )
				( pin "R7D25.1"
					( objectStatus "a" )
				)
				( pin "R7D25.2"
					( objectStatus "b" )
				)
			)
			( gate "R3R2"
				( objectStatus "@baseboard_fab2_lib.baseboard_fab2(sch_1):page92_i75" )
				( pin "R3R2.1"
					( objectStatus "a" )
				)
				( pin "R3R2.2"
					( objectStatus "b" )
				)
			)
			( gate "C7D4"
				( objectStatus "@baseboard_fab2_lib.baseboard_fab2(sch_1):page92_i79" )
				( pin "C7D4.1"
					( objectStatus "a" )
				)
				( pin "C7D4.2"
					( objectStatus "b" )
				)
			)
			( gate "C3P50"
				( objectStatus "@baseboard_fab2_lib.baseboard_fab2(sch_1):page92_i84" )
				( pin "C3P50.1"
					( objectStatus "a" )
				)
				( pin "C3P50.2"
					( objectStatus "b" )
				)
			)
			( gate "R2T44"
				( objectStatus "@baseboard_fab2_lib.baseboard_fab2(sch_1):page92_i92" )
				( pin "R2T44.1"
					( objectStatus "a" )
				)
				( pin "R2T44.2"
					( objectStatus "b" )
				)
			)
			( gate "R2T40"
				( objectStatus "@baseboard_fab2_lib.baseboard_fab2(sch_1):page92_i93" )
				( pin "R2T40.1"
					( objectStatus "a" )
				)
				( pin "R2T40.2"
					( objectStatus "b" )
				)
			)
			( gate "R2T37"
				( objectStatus "@baseboard_fab2_lib.baseboard_fab2(sch_1):page92_i94" )
				( pin "R2T37.1"
					( objectStatus "a" )
				)
				( pin "R2T37.2"
					( objectStatus "b" )
				)
			)
			( gate "R2T43"
				( objectStatus "@baseboard_fab2_lib.baseboard_fab2(sch_1):page92_i96" )
				( pin "R2T43.1"
					( objectStatus "a" )
				)
				( pin "R2T43.2"
					( objectStatus "b" )
				)
			)
			( gate "R2T51"
				( objectStatus "@baseboard_fab2_lib.baseboard_fab2(sch_1):page92_i97" )
				( pin "R2T51.1"
					( objectStatus "a" )
				)
				( pin "R2T51.2"
					( objectStatus "b" )
				)
			)
			( gate "R2T48"
				( objectStatus "@baseboard_fab2_lib.baseboard_fab2(sch_1):page92_i98" )
				( pin "R2T48.1"
					( objectStatus "a" )
				)
				( pin "R2T48.2"
					( objectStatus "b" )
				)
			)
			( gate "R7P18"
				( objectStatus "@baseboard_fab2_lib.baseboard_fab2(sch_1):page92_i100" )
				( pin "R7P18.1"
					( objectStatus "a" )
				)
				( pin "R7P18.2"
					( objectStatus "b" )
				)
			)
			( gate "R4R2"
				( objectStatus "@baseboard_fab2_lib.baseboard_fab2(sch_1):page92_i101" )
				( pin "R4R2.1"
					( objectStatus "a" )
				)
				( pin "R4R2.2"
					( objectStatus "b" )
				)
			)
			( gate "R2T27"
				( objectStatus "@baseboard_fab2_lib.baseboard_fab2(sch_1):page93_i13" )
				( pin "R2T27.1"
					( objectStatus "a" )
				)
				( pin "R2T27.2"
					( objectStatus "b" )
				)
			)
			( gate "R2T32"
				( objectStatus "@baseboard_fab2_lib.baseboard_fab2(sch_1):page93_i15" )
				( pin "R2T32.1"
					( objectStatus "a" )
				)
				( pin "R2T32.2"
					( objectStatus "b" )
				)
			)
			( gate "R2T20"
				( objectStatus "@baseboard_fab2_lib.baseboard_fab2(sch_1):page93_i16" )
				( pin "R2T20.1"
					( objectStatus "a" )
				)
				( pin "R2T20.2"
					( objectStatus "b" )
				)
			)
			( gate "R2T17"
				( objectStatus "@baseboard_fab2_lib.baseboard_fab2(sch_1):page93_i23" )
				( pin "R2T17.1"
					( objectStatus "a" )
				)
				( pin "R2T17.2"
					( objectStatus "b" )
				)
			)
			( gate "U2T4"
				( objectStatus "@baseboard_fab2_lib.baseboard_fab2(sch_1):page93_i30" )
				( pin "U2T4.13"
					( objectStatus "a0" )
				)
				( pin "U2T4.12"
					( objectStatus "a1" )
				)
				( pin "U2T4.10"
					( objectStatus "a2" )
				)
				( pin "U2T4.9"
					( objectStatus "a3" )
				)
				( pin "U2T4.2"
					( objectStatus "b0" )
				)
				( pin "U2T4.3"
					( objectStatus "b1" )
				)
				( pin "U2T4.5"
					( objectStatus "b2" )
				)
				( pin "U2T4.6"
					( objectStatus "b3" )
				)
				( pin "U2T4.1"
					( objectStatus "dir" )
				)
				( pin "U2T4.7"
					( objectStatus "gnd(0)" )
				)
				( pin "U2T4.8"
					( objectStatus "gnd(1)" )
				)
				( pin "U2T4.11"
					( objectStatus "gnd(2)" )
				)
				( pin "U2T4.14"
					( objectStatus "vcc" )
				)
				( pin "U2T4.4"
					( objectStatus "vref" )
				)
			)
			( gate "R2T38"
				( objectStatus "@baseboard_fab2_lib.baseboard_fab2(sch_1):page93_i39" )
				( pin "R2T38.1"
					( objectStatus "a" )
				)
				( pin "R2T38.2"
					( objectStatus "b" )
				)
			)
			( gate "R2T33"
				( objectStatus "@baseboard_fab2_lib.baseboard_fab2(sch_1):page93_i40" )
				( pin "R2T33.1"
					( objectStatus "a" )
				)
				( pin "R2T33.2"
					( objectStatus "b" )
				)
			)
			( gate "R2T30"
				( objectStatus "@baseboard_fab2_lib.baseboard_fab2(sch_1):page93_i42" )
				( pin "R2T30.1"
					( objectStatus "a" )
				)
				( pin "R2T30.2"
					( objectStatus "b" )
				)
			)
			( gate "R7D24"
				( objectStatus "@baseboard_fab2_lib.baseboard_fab2(sch_1):page93_i62" )
				( pin "R7D24.1"
					( objectStatus "a" )
				)
				( pin "R7D24.2"
					( objectStatus "b" )
				)
			)
			( gate "R2T19"
				( objectStatus "@baseboard_fab2_lib.baseboard_fab2(sch_1):page93_i63" )
				( pin "R2T19.1"
					( objectStatus "a" )
				)
				( pin "R2T19.2"
					( objectStatus "b" )
				)
			)
			( gate "R2T16"
				( objectStatus "@baseboard_fab2_lib.baseboard_fab2(sch_1):page93_i67" )
				( pin "R2T16.1"
					( objectStatus "a" )
				)
				( pin "R2T16.2"
					( objectStatus "b" )
				)
			)
			( gate "R2T31"
				( objectStatus "@baseboard_fab2_lib.baseboard_fab2(sch_1):page93_i68" )
				( pin "R2T31.1"
					( objectStatus "a" )
				)
				( pin "R2T31.2"
					( objectStatus "b" )
				)
			)
			( gate "C2T33"
				( objectStatus "@baseboard_fab2_lib.baseboard_fab2(sch_1):page93_i72" )
				( pin "C2T33.1"
					( objectStatus "a" )
				)
				( pin "C2T33.2"
					( objectStatus "b" )
				)
			)
			( gate "R4R3"
				( objectStatus "@baseboard_fab2_lib.baseboard_fab2(sch_1):page93_i79" )
				( pin "R4R3.1"
					( objectStatus "a" )
				)
				( pin "R4R3.2"
					( objectStatus "b" )
				)
			)
			( gate "R7E1"
				( objectStatus "@baseboard_fab2_lib.baseboard_fab2(sch_1):page93_i80" )
				( pin "R7E1.1"
					( objectStatus "a" )
				)
				( pin "R7E1.2"
					( objectStatus "b" )
				)
			)
			( gate "R2T26"
				( objectStatus "@baseboard_fab2_lib.baseboard_fab2(sch_1):page93_i87" )
				( pin "R2T26.1"
					( objectStatus "a" )
				)
				( pin "R2T26.2"
					( objectStatus "b" )
				)
			)
			( gate "R89"
				( objectStatus "@baseboard_fab2_lib.baseboard_fab2(sch_1):page93_i88" )
				( pin "R89.1"
					( objectStatus "a" )
				)
				( pin "R89.2"
					( objectStatus "b" )
				)
			)
			( gate "R91"
				( objectStatus "@baseboard_fab2_lib.baseboard_fab2(sch_1):page93_i89" )
				( pin "R91.1"
					( objectStatus "a" )
				)
				( pin "R91.2"
					( objectStatus "b" )
				)
			)
			( gate "R95"
				( objectStatus "@baseboard_fab2_lib.baseboard_fab2(sch_1):page93_i93" )
				( pin "R95.1"
					( objectStatus "a" )
				)
				( pin "R95.2"
					( objectStatus "b" )
				)
			)
			( gate "R98"
				( objectStatus "@baseboard_fab2_lib.baseboard_fab2(sch_1):page93_i94" )
				( pin "R98.1"
					( objectStatus "a" )
				)
				( pin "R98.2"
					( objectStatus "b" )
				)
			)
			( gate "C2T32"
				( objectStatus "@baseboard_fab2_lib.baseboard_fab2(sch_1):page93_i95" )
				( pin "C2T32.1"
					( objectStatus "a" )
				)
				( pin "C2T32.2"
					( objectStatus "b" )
				)
			)
			( gate "R2T36"
				( objectStatus "@baseboard_fab2_lib.baseboard_fab2(sch_1):page93_i97" )
				( pin "R2T36.1"
					( objectStatus "a" )
				)
				( pin "R2T36.2"
					( objectStatus "b" )
				)
			)
			( gate "R2T39"
				( objectStatus "@baseboard_fab2_lib.baseboard_fab2(sch_1):page93_i98" )
				( pin "R2T39.1"
					( objectStatus "a" )
				)
				( pin "R2T39.2"
					( objectStatus "b" )
				)
			)
			( gate "R94"
				( objectStatus "@baseboard_fab2_lib.baseboard_fab2(sch_1):page93_i102" )
				( pin "R94.1"
					( objectStatus "a" )
				)
				( pin "R94.2"
					( objectStatus "b" )
				)
			)
			( gate "R93"
				( objectStatus "@baseboard_fab2_lib.baseboard_fab2(sch_1):page93_i103" )
				( pin "R93.1"
					( objectStatus "a" )
				)
				( pin "R93.2"
					( objectStatus "b" )
				)
			)
			( gate "R3P40"
				( objectStatus "@baseboard_fab2_lib.baseboard_fab2(sch_1):page93_i104" )
				( pin "R3P40.1"
					( objectStatus "a" )
				)
				( pin "R3P40.2"
					( objectStatus "b" )
				)
			)
			( gate "R7P28"
				( objectStatus "@baseboard_fab2_lib.baseboard_fab2(sch_1):page93_i106" )
				( pin "R7P28.1"
					( objectStatus "a" )
				)
				( pin "R7P28.2"
					( objectStatus "b" )
				)
			)
			( gate "R92"
				( objectStatus "@baseboard_fab2_lib.baseboard_fab2(sch_1):page93_i107" )
				( pin "R92.1"
					( objectStatus "a" )
				)
				( pin "R92.2"
					( objectStatus "b" )
				)
			)
			( gate "R90"
				( objectStatus "@baseboard_fab2_lib.baseboard_fab2(sch_1):page93_i108" )
				( pin "R90.1"
					( objectStatus "a" )
				)
				( pin "R90.2"
					( objectStatus "b" )
				)
			)
			( gate "R96"
				( objectStatus "@baseboard_fab2_lib.baseboard_fab2(sch_1):page93_i109" )
				( pin "R96.1"
					( objectStatus "a" )
				)
				( pin "R96.2"
					( objectStatus "b" )
				)
			)
			( gate "R97"
				( objectStatus "@baseboard_fab2_lib.baseboard_fab2(sch_1):page93_i110" )
				( pin "R97.1"
					( objectStatus "a" )
				)
				( pin "R97.2"
					( objectStatus "b" )
				)
			)
			( gate "R114"
				( objectStatus "@baseboard_fab2_lib.baseboard_fab2(sch_1):page93_i111" )
				( pin "R114.1"
					( objectStatus "a" )
				)
				( pin "R114.2"
					( objectStatus "b" )
				)
			)
			( gate "R115"
				( objectStatus "@baseboard_fab2_lib.baseboard_fab2(sch_1):page93_i112" )
				( pin "R115.1"
					( objectStatus "a" )
				)
				( pin "R115.2"
					( objectStatus "b" )
				)
			)
			( gate "R116"
				( objectStatus "@baseboard_fab2_lib.baseboard_fab2(sch_1):page93_i113" )
				( pin "R116.1"
					( objectStatus "a" )
				)
				( pin "R116.2"
					( objectStatus "b" )
				)
			)
			( gate "R117"
				( objectStatus "@baseboard_fab2_lib.baseboard_fab2(sch_1):page93_i114" )
				( pin "R117.1"
					( objectStatus "a" )
				)
				( pin "R117.2"
					( objectStatus "b" )
				)
			)
			( gate "R118"
				( objectStatus "@baseboard_fab2_lib.baseboard_fab2(sch_1):page93_i119" )
				( pin "R118.1"
					( objectStatus "a" )
				)
				( pin "R118.2"
					( objectStatus "b" )
				)
			)
			( gate "R119"
				( objectStatus "@baseboard_fab2_lib.baseboard_fab2(sch_1):page93_i121" )
				( pin "R119.1"
					( objectStatus "a" )
				)
				( pin "R119.2"
					( objectStatus "b" )
				)
			)
			( gate "R120"
				( objectStatus "@baseboard_fab2_lib.baseboard_fab2(sch_1):page93_i122" )
				( pin "R120.1"
					( objectStatus "a" )
				)
				( pin "R120.2"
					( objectStatus "b" )
				)
			)
			( gate "R121"
				( objectStatus "@baseboard_fab2_lib.baseboard_fab2(sch_1):page93_i123" )
				( pin "R121.1"
					( objectStatus "a" )
				)
				( pin "R121.2"
					( objectStatus "b" )
				)
			)
			( gate "R2T50"
				( objectStatus "@baseboard_fab2_lib.baseboard_fab2(sch_1):page93_i127" )
				( pin "R2T50.1"
					( objectStatus "a" )
				)
				( pin "R2T50.2"
					( objectStatus "b" )
				)
			)
			( gate "R164"
				( objectStatus "@baseboard_fab2_lib.baseboard_fab2(sch_1):page93_i131" )
				( pin "R164.1"
					( objectStatus "a" )
				)
				( pin "R164.2"
					( objectStatus "b" )
				)
			)
			( gate "R165"
				( objectStatus "@baseboard_fab2_lib.baseboard_fab2(sch_1):page93_i133" )
				( pin "R165.1"
					( objectStatus "a" )
				)
				( pin "R165.2"
					( objectStatus "b" )
				)
			)
			( gate "R166"
				( objectStatus "@baseboard_fab2_lib.baseboard_fab2(sch_1):page93_i135" )
				( pin "R166.1"
					( objectStatus "a" )
				)
				( pin "R166.2"
					( objectStatus "b" )
				)
			)
			( gate "R167"
				( objectStatus "@baseboard_fab2_lib.baseboard_fab2(sch_1):page93_i137" )
				( pin "R167.1"
					( objectStatus "a" )
				)
				( pin "R167.2"
					( objectStatus "b" )
				)
			)
			( gate "Q3U1"
				( objectStatus "@baseboard_fab2_lib.baseboard_fab2(sch_1):page94_i49" )
				( pin "Q3U1.6"
					( objectStatus "drain(0)" )
				)
				( pin "Q3U1.2"
					( objectStatus "gate(0)" )
				)
				( pin "Q3U1.1"
					( objectStatus "source(0)" )
				)
			)
			( gate "R7G7"
				( objectStatus "@baseboard_fab2_lib.baseboard_fab2(sch_1):page94_i51" )
				( pin "R7G7.1"
					( objectStatus "a" )
				)
				( pin "R7G7.2"
					( objectStatus "b" )
				)
			)
			( gate "Q7E1"
				( objectStatus "@baseboard_fab2_lib.baseboard_fab2(sch_1):page94_i60" )
				( pin "Q7E1.6"
					( objectStatus "drain(0)" )
				)
				( pin "Q7E1.2"
					( objectStatus "gate(0)" )
				)
				( pin "Q7E1.1"
					( objectStatus "source(0)" )
				)
			)
			( gate "Q7E1"
				( objectStatus "@baseboard_fab2_lib.baseboard_fab2(sch_1):page94_i64" )
				( pin "Q7E1.3"
					( objectStatus "drain(0)" )
				)
				( pin "Q7E1.5"
					( objectStatus "gate(0)" )
				)
				( pin "Q7E1.4"
					( objectStatus "source(0)" )
				)
			)
			( gate "R3R4"
				( objectStatus "@baseboard_fab2_lib.baseboard_fab2(sch_1):page94_i66" )
				( pin "R3R4.1"
					( objectStatus "a" )
				)
				( pin "R3R4.2"
					( objectStatus "b" )
				)
			)
			( gate "Q7E2"
				( objectStatus "@baseboard_fab2_lib.baseboard_fab2(sch_1):page94_i69" )
				( pin "Q7E2.6"
					( objectStatus "drain(0)" )
				)
				( pin "Q7E2.2"
					( objectStatus "gate(0)" )
				)
				( pin "Q7E2.1"
					( objectStatus "source(0)" )
				)
			)
			( gate "Q7E2"
				( objectStatus "@baseboard_fab2_lib.baseboard_fab2(sch_1):page94_i75" )
				( pin "Q7E2.3"
					( objectStatus "drain(0)" )
				)
				( pin "Q7E2.5"
					( objectStatus "gate(0)" )
				)
				( pin "Q7E2.4"
					( objectStatus "source(0)" )
				)
			)
			( gate "Q4B1"
				( objectStatus "@baseboard_fab2_lib.baseboard_fab2(sch_1):page94_i77" )
				( pin "Q4B1.3"
					( objectStatus "drain(0)" )
				)
				( pin "Q4B1.5"
					( objectStatus "gate(0)" )
				)
				( pin "Q4B1.4"
					( objectStatus "source(0)" )
				)
			)
			( gate "R3R10"
				( objectStatus "@baseboard_fab2_lib.baseboard_fab2(sch_1):page94_i79" )
				( pin "R3R10.1"
					( objectStatus "a" )
				)
				( pin "R3R10.2"
					( objectStatus "b" )
				)
			)
			( gate "R6M4"
				( objectStatus "@baseboard_fab2_lib.baseboard_fab2(sch_1):page94_i82" )
				( pin "R6M4.1"
					( objectStatus "a" )
				)
				( pin "R6M4.2"
					( objectStatus "b" )
				)
			)
			( gate "Q4B1"
				( objectStatus "@baseboard_fab2_lib.baseboard_fab2(sch_1):page94_i84" )
				( pin "Q4B1.6"
					( objectStatus "drain(0)" )
				)
				( pin "Q4B1.2"
					( objectStatus "gate(0)" )
				)
				( pin "Q4B1.1"
					( objectStatus "source(0)" )
				)
			)
			( gate "Q3U1"
				( objectStatus "@baseboard_fab2_lib.baseboard_fab2(sch_1):page94_i89" )
				( pin "Q3U1.3"
					( objectStatus "drain(0)" )
				)
				( pin "Q3U1.5"
					( objectStatus "gate(0)" )
				)
				( pin "Q3U1.4"
					( objectStatus "source(0)" )
				)
			)
			( gate "R4U1"
				( objectStatus "@baseboard_fab2_lib.baseboard_fab2(sch_1):page94_i91" )
				( pin "R4U1.1"
					( objectStatus "a" )
				)
				( pin "R4U1.2"
					( objectStatus "b" )
				)
			)
			( gate "R4U3"
				( objectStatus "@baseboard_fab2_lib.baseboard_fab2(sch_1):page94_i94" )
				( pin "R4U3.1"
					( objectStatus "a" )
				)
				( pin "R4U3.2"
					( objectStatus "b" )
				)
			)
			( gate "Q4U1"
				( objectStatus "@baseboard_fab2_lib.baseboard_fab2(sch_1):page94_i98" )
				( pin "Q4U1.6"
					( objectStatus "drain(0)" )
				)
				( pin "Q4U1.2"
					( objectStatus "gate(0)" )
				)
				( pin "Q4U1.1"
					( objectStatus "source(0)" )
				)
			)
			( gate "R4U2"
				( objectStatus "@baseboard_fab2_lib.baseboard_fab2(sch_1):page94_i100" )
				( pin "R4U2.1"
					( objectStatus "a" )
				)
				( pin "R4U2.2"
					( objectStatus "b" )
				)
			)
			( gate "Q4U1"
				( objectStatus "@baseboard_fab2_lib.baseboard_fab2(sch_1):page94_i102" )
				( pin "Q4U1.3"
					( objectStatus "drain(0)" )
				)
				( pin "Q4U1.5"
					( objectStatus "gate(0)" )
				)
				( pin "Q4U1.4"
					( objectStatus "source(0)" )
				)
			)
			( gate "R4U4"
				( objectStatus "@baseboard_fab2_lib.baseboard_fab2(sch_1):page94_i104" )
				( pin "R4U4.1"
					( objectStatus "a" )
				)
				( pin "R4U4.2"
					( objectStatus "b" )
				)
			)
			( gate "Q2U1"
				( objectStatus "@baseboard_fab2_lib.baseboard_fab2(sch_1):page95_i28" )
				( pin "Q2U1.6"
					( objectStatus "drain(0)" )
				)
				( pin "Q2U1.2"
					( objectStatus "gate(0)" )
				)
				( pin "Q2U1.1"
					( objectStatus "source(0)" )
				)
			)
			( gate "Q4B2"
				( objectStatus "@baseboard_fab2_lib.baseboard_fab2(sch_1):page95_i32" )
				( pin "Q4B2.6"
					( objectStatus "drain(0)" )
				)
				( pin "Q4B2.2"
					( objectStatus "gate(0)" )
				)
				( pin "Q4B2.1"
					( objectStatus "source(0)" )
				)
			)
			( gate "Q4B2"
				( objectStatus "@baseboard_fab2_lib.baseboard_fab2(sch_1):page95_i33" )
				( pin "Q4B2.3"
					( objectStatus "drain(0)" )
				)
				( pin "Q4B2.5"
					( objectStatus "gate(0)" )
				)
				( pin "Q4B2.4"
					( objectStatus "source(0)" )
				)
			)
			( gate "Q7E3"
				( objectStatus "@baseboard_fab2_lib.baseboard_fab2(sch_1):page95_i51" )
				( pin "Q7E3.3"
					( objectStatus "drain(0)" )
				)
				( pin "Q7E3.5"
					( objectStatus "gate(0)" )
				)
				( pin "Q7E3.4"
					( objectStatus "source(0)" )
				)
			)
			( gate "Q7E3"
				( objectStatus "@baseboard_fab2_lib.baseboard_fab2(sch_1):page95_i52" )
				( pin "Q7E3.6"
					( objectStatus "drain(0)" )
				)
				( pin "Q7E3.2"
					( objectStatus "gate(0)" )
				)
				( pin "Q7E3.1"
					( objectStatus "source(0)" )
				)
			)
			( gate "Q7E5"
				( objectStatus "@baseboard_fab2_lib.baseboard_fab2(sch_1):page95_i59" )
				( pin "Q7E5.3"
					( objectStatus "drain(0)" )
				)
				( pin "Q7E5.5"
					( objectStatus "gate(0)" )
				)
				( pin "Q7E5.4"
					( objectStatus "source(0)" )
				)
			)
			( gate "R7E10"
				( objectStatus "@baseboard_fab2_lib.baseboard_fab2(sch_1):page95_i62" )
				( pin "R7E10.1"
					( objectStatus "a" )
				)
				( pin "R7E10.2"
					( objectStatus "b" )
				)
			)
			( gate "Q7E6"
				( objectStatus "@baseboard_fab2_lib.baseboard_fab2(sch_1):page95_i69" )
				( pin "Q7E6.3"
					( objectStatus "drain(0)" )
				)
				( pin "Q7E6.5"
					( objectStatus "gate(0)" )
				)
				( pin "Q7E6.4"
					( objectStatus "source(0)" )
				)
			)
			( gate "R7E11"
				( objectStatus "@baseboard_fab2_lib.baseboard_fab2(sch_1):page95_i72" )
				( pin "R7E11.1"
					( objectStatus "a" )
				)
				( pin "R7E11.2"
					( objectStatus "b" )
				)
			)
			( gate "C7E3"
				( objectStatus "@baseboard_fab2_lib.baseboard_fab2(sch_1):page95_i92" )
				( pin "C7E3.1"
					( objectStatus "a" )
				)
				( pin "C7E3.2"
					( objectStatus "b" )
				)
			)
			( gate "Q7E4"
				( objectStatus "@baseboard_fab2_lib.baseboard_fab2(sch_1):page95_i104" )
				( pin "Q7E4.3"
					( objectStatus "drn" )
				)
				( pin "Q7E4.1"
					( objectStatus "gate" )
				)
				( pin "Q7E4.2"
					( objectStatus "src" )
				)
			)
			( gate "R7E7"
				( objectStatus "@baseboard_fab2_lib.baseboard_fab2(sch_1):page95_i106" )
				( pin "R7E7.1"
					( objectStatus "a" )
				)
				( pin "R7E7.2"
					( objectStatus "b" )
				)
			)
			( gate "R7E9"
				( objectStatus "@baseboard_fab2_lib.baseboard_fab2(sch_1):page95_i108" )
				( pin "R7E9.1"
					( objectStatus "a" )
				)
				( pin "R7E9.2"
					( objectStatus "b" )
				)
			)
			( gate "Q7E5"
				( objectStatus "@baseboard_fab2_lib.baseboard_fab2(sch_1):page95_i111" )
				( pin "Q7E5.6"
					( objectStatus "drain(0)" )
				)
				( pin "Q7E5.2"
					( objectStatus "gate(0)" )
				)
				( pin "Q7E5.1"
					( objectStatus "source(0)" )
				)
			)
			( gate "Q7E6"
				( objectStatus "@baseboard_fab2_lib.baseboard_fab2(sch_1):page95_i112" )
				( pin "Q7E6.6"
					( objectStatus "drain(0)" )
				)
				( pin "Q7E6.2"
					( objectStatus "gate(0)" )
				)
				( pin "Q7E6.1"
					( objectStatus "source(0)" )
				)
			)
			( gate "Q2U1"
				( objectStatus "@baseboard_fab2_lib.baseboard_fab2(sch_1):page95_i113" )
				( pin "Q2U1.3"
					( objectStatus "drain(0)" )
				)
				( pin "Q2U1.5"
					( objectStatus "gate(0)" )
				)
				( pin "Q2U1.4"
					( objectStatus "source(0)" )
				)
			)
			( gate "C7E4"
				( objectStatus "@baseboard_fab2_lib.baseboard_fab2(sch_1):page95_i115" )
				( pin "C7E4.1"
					( objectStatus "a" )
				)
				( pin "C7E4.2"
					( objectStatus "b" )
				)
			)
			( gate "U7E2"
				( objectStatus "@baseboard_fab2_lib.baseboard_fab2(sch_1):page95_i117" )
				( pin "U7E2.1"
					( objectStatus "a(0)" )
				)
				( pin "U7E2.2"
					( objectStatus "b(0)" )
				)
				( pin "U7E2.4"
					( objectStatus "y(0)" )
				)
			)
			( gate "U7E3"
				( objectStatus "@baseboard_fab2_lib.baseboard_fab2(sch_1):page95_i118" )
				( pin "U7E3.1"
					( objectStatus "a(0)" )
				)
				( pin "U7E3.2"
					( objectStatus "b(0)" )
				)
				( pin "U7E3.4"
					( objectStatus "y(0)" )
				)
			)
			( gate "Q4"
				( objectStatus "@baseboard_fab2_lib.baseboard_fab2(sch_1):page95_i119" )
				( pin "Q4.3"
					( objectStatus "drn" )
				)
				( pin "Q4.1"
					( objectStatus "gate" )
				)
				( pin "Q4.2"
					( objectStatus "src" )
				)
			)
			( gate "R6D12"
				( objectStatus "@baseboard_fab2_lib.baseboard_fab2(sch_1):page96_i2" )
				( pin "R6D12.1"
					( objectStatus "a" )
				)
				( pin "R6D12.2"
					( objectStatus "b" )
				)
			)
			( gate "R6D8"
				( objectStatus "@baseboard_fab2_lib.baseboard_fab2(sch_1):page96_i3" )
				( pin "R6D8.1"
					( objectStatus "a" )
				)
				( pin "R6D8.2"
					( objectStatus "b" )
				)
			)
			( gate "R3P29"
				( objectStatus "@baseboard_fab2_lib.baseboard_fab2(sch_1):page96_i5" )
				( pin "R3P29.1"
					( objectStatus "a" )
				)
				( pin "R3P29.2"
					( objectStatus "b" )
				)
			)
			( gate "R3P38"
				( objectStatus "@baseboard_fab2_lib.baseboard_fab2(sch_1):page96_i7" )
				( pin "R3P38.1"
					( objectStatus "a" )
				)
				( pin "R3P38.2"
					( objectStatus "b" )
				)
			)
			( gate "R3D20"
				( objectStatus "@baseboard_fab2_lib.baseboard_fab2(sch_1):page96_i25" )
				( pin "R3D20.1"
					( objectStatus "a" )
				)
				( pin "R3D20.2"
					( objectStatus "b" )
				)
			)
			( gate "R3D15"
				( objectStatus "@baseboard_fab2_lib.baseboard_fab2(sch_1):page96_i26" )
				( pin "R3D15.1"
					( objectStatus "a" )
				)
				( pin "R3D15.2"
					( objectStatus "b" )
				)
			)
			( gate "R7M9"
				( objectStatus "@baseboard_fab2_lib.baseboard_fab2(sch_1):page96_i28" )
				( pin "R7M9.1"
					( objectStatus "a" )
				)
				( pin "R7M9.2"
					( objectStatus "b" )
				)
			)
			( gate "R3D21"
				( objectStatus "@baseboard_fab2_lib.baseboard_fab2(sch_1):page96_i30" )
				( pin "R3D21.1"
					( objectStatus "a" )
				)
				( pin "R3D21.2"
					( objectStatus "b" )
				)
			)
			( gate "R3P36"
				( objectStatus "@baseboard_fab2_lib.baseboard_fab2(sch_1):page96_i36" )
				( pin "R3P36.1"
					( objectStatus "a" )
				)
				( pin "R3P36.2"
					( objectStatus "b" )
				)
			)
			( gate "U3P1"
				( objectStatus "@baseboard_fab2_lib.baseboard_fab2(sch_1):page96_i42" )
				( pin "U3P1.13"
					( objectStatus "a0" )
				)
				( pin "U3P1.12"
					( objectStatus "a1" )
				)
				( pin "U3P1.10"
					( objectStatus "a2" )
				)
				( pin "U3P1.9"
					( objectStatus "a3" )
				)
				( pin "U3P1.2"
					( objectStatus "b0" )
				)
				( pin "U3P1.3"
					( objectStatus "b1" )
				)
				( pin "U3P1.5"
					( objectStatus "b2" )
				)
				( pin "U3P1.6"
					( objectStatus "b3" )
				)
				( pin "U3P1.1"
					( objectStatus "dir" )
				)
				( pin "U3P1.7"
					( objectStatus "gnd(0)" )
				)
				( pin "U3P1.8"
					( objectStatus "gnd(1)" )
				)
				( pin "U3P1.11"
					( objectStatus "gnd(2)" )
				)
				( pin "U3P1.14"
					( objectStatus "vcc" )
				)
				( pin "U3P1.4"
					( objectStatus "vref" )
				)
			)
			( gate "U4C2"
				( objectStatus "@baseboard_fab2_lib.baseboard_fab2(sch_1):page96_i46" )
				( pin "U4C2.13"
					( objectStatus "a0" )
				)
				( pin "U4C2.12"
					( objectStatus "a1" )
				)
				( pin "U4C2.10"
					( objectStatus "a2" )
				)
				( pin "U4C2.9"
					( objectStatus "a3" )
				)
				( pin "U4C2.2"
					( objectStatus "b0" )
				)
				( pin "U4C2.3"
					( objectStatus "b1" )
				)
				( pin "U4C2.5"
					( objectStatus "b2" )
				)
				( pin "U4C2.6"
					( objectStatus "b3" )
				)
				( pin "U4C2.1"
					( objectStatus "dir" )
				)
				( pin "U4C2.7"
					( objectStatus "gnd(0)" )
				)
				( pin "U4C2.8"
					( objectStatus "gnd(1)" )
				)
				( pin "U4C2.11"
					( objectStatus "gnd(2)" )
				)
				( pin "U4C2.14"
					( objectStatus "vcc" )
				)
				( pin "U4C2.4"
					( objectStatus "vref" )
				)
			)
			( gate "R4C8"
				( objectStatus "@baseboard_fab2_lib.baseboard_fab2(sch_1):page96_i55" )
				( pin "R4C8.1"
					( objectStatus "a" )
				)
				( pin "R4C8.2"
					( objectStatus "b" )
				)
			)
			( gate "R4C9"
				( objectStatus "@baseboard_fab2_lib.baseboard_fab2(sch_1):page96_i69" )
				( pin "R4C9.1"
					( objectStatus "a" )
				)
				( pin "R4C9.2"
					( objectStatus "b" )
				)
			)
			( gate "R3P32"
				( objectStatus "@baseboard_fab2_lib.baseboard_fab2(sch_1):page96_i71" )
				( pin "R3P32.1"
					( objectStatus "a" )
				)
				( pin "R3P32.2"
					( objectStatus "b" )
				)
			)
			( gate "C3P42"
				( objectStatus "@baseboard_fab2_lib.baseboard_fab2(sch_1):page96_i73" )
				( pin "C3P42.1"
					( objectStatus "a" )
				)
				( pin "C3P42.2"
					( objectStatus "b" )
				)
			)
			( gate "C4C3"
				( objectStatus "@baseboard_fab2_lib.baseboard_fab2(sch_1):page96_i75" )
				( pin "C4C3.1"
					( objectStatus "a" )
				)
				( pin "C4C3.2"
					( objectStatus "b" )
				)
			)
			( gate "R3D18"
				( objectStatus "@baseboard_fab2_lib.baseboard_fab2(sch_1):page97_i33" )
				( pin "R3D18.1"
					( objectStatus "a" )
				)
				( pin "R3D18.2"
					( objectStatus "b" )
				)
			)
			( gate "R4R4"
				( objectStatus "@baseboard_fab2_lib.baseboard_fab2(sch_1):page97_i42" )
				( pin "R4R4.1"
					( objectStatus "a" )
				)
				( pin "R4R4.2"
					( objectStatus "b" )
				)
			)
			( gate "R7P20"
				( objectStatus "@baseboard_fab2_lib.baseboard_fab2(sch_1):page97_i44" )
				( pin "R7P20.1"
					( objectStatus "a" )
				)
				( pin "R7P20.2"
					( objectStatus "b" )
				)
			)
			( gate "R4P21"
				( objectStatus "@baseboard_fab2_lib.baseboard_fab2(sch_1):page97_i72" )
				( pin "R4P21.1"
					( objectStatus "a" )
				)
				( pin "R4P21.2"
					( objectStatus "b" )
				)
			)
			( gate "R4C10"
				( objectStatus "@baseboard_fab2_lib.baseboard_fab2(sch_1):page97_i76" )
				( pin "R4C10.1"
					( objectStatus "a" )
				)
				( pin "R4C10.2"
					( objectStatus "b" )
				)
			)
			( gate "R4P5"
				( objectStatus "@baseboard_fab2_lib.baseboard_fab2(sch_1):page97_i80" )
				( pin "R4P5.1"
					( objectStatus "a" )
				)
				( pin "R4P5.2"
					( objectStatus "b" )
				)
			)
			( gate "R7P13"
				( objectStatus "@baseboard_fab2_lib.baseboard_fab2(sch_1):page97_i81" )
				( pin "R7P13.1"
					( objectStatus "a" )
				)
				( pin "R7P13.2"
					( objectStatus "b" )
				)
			)
			( gate "R4F5"
				( objectStatus "@baseboard_fab2_lib.baseboard_fab2(sch_1):page98_i4" )
				( pin "R4F5.1"
					( objectStatus "a" )
				)
				( pin "R4F5.2"
					( objectStatus "b" )
				)
			)
			( gate "R4F3"
				( objectStatus "@baseboard_fab2_lib.baseboard_fab2(sch_1):page98_i5" )
				( pin "R4F3.1"
					( objectStatus "a" )
				)
				( pin "R4F3.2"
					( objectStatus "b" )
				)
			)
			( gate "C4F9"
				( objectStatus "@baseboard_fab2_lib.baseboard_fab2(sch_1):page98_i7" )
				( pin "C4F9.1"
					( objectStatus "a" )
				)
				( pin "C4F9.2"
					( objectStatus "b" )
				)
			)
			( gate "R6M1"
				( objectStatus "@baseboard_fab2_lib.baseboard_fab2(sch_1):page98_i9" )
				( pin "R6M1.1"
					( objectStatus "a" )
				)
				( pin "R6M1.2"
					( objectStatus "b" )
				)
			)
			( gate "R6L16"
				( objectStatus "@baseboard_fab2_lib.baseboard_fab2(sch_1):page98_i12" )
				( pin "R6L16.1"
					( objectStatus "a" )
				)
				( pin "R6L16.2"
					( objectStatus "b" )
				)
			)
			( gate "R6M2"
				( objectStatus "@baseboard_fab2_lib.baseboard_fab2(sch_1):page98_i14" )
				( pin "R6M2.1"
					( objectStatus "a" )
				)
				( pin "R6M2.2"
					( objectStatus "b" )
				)
			)
			( gate "C6M2"
				( objectStatus "@baseboard_fab2_lib.baseboard_fab2(sch_1):page98_i33" )
				( pin "C6M2.1"
					( objectStatus "a" )
				)
				( pin "C6M2.2"
					( objectStatus "b" )
				)
			)
			( gate "R4F4"
				( objectStatus "@baseboard_fab2_lib.baseboard_fab2(sch_1):page98_i36" )
				( pin "R4F4.1"
					( objectStatus "a" )
				)
				( pin "R4F4.2"
					( objectStatus "b" )
				)
			)
			( gate "R4G2"
				( objectStatus "@baseboard_fab2_lib.baseboard_fab2(sch_1):page98_i38" )
				( pin "R4G2.1"
					( objectStatus "a" )
				)
				( pin "R4G2.2"
					( objectStatus "b" )
				)
			)
			( gate "R4G3"
				( objectStatus "@baseboard_fab2_lib.baseboard_fab2(sch_1):page98_i40" )
				( pin "R4G3.1"
					( objectStatus "a" )
				)
				( pin "R4G3.2"
					( objectStatus "b" )
				)
			)
			( gate "R4G1"
				( objectStatus "@baseboard_fab2_lib.baseboard_fab2(sch_1):page98_i42" )
				( pin "R4G1.1"
					( objectStatus "a" )
				)
				( pin "R4G1.2"
					( objectStatus "b" )
				)
			)
			( gate "C4G1"
				( objectStatus "@baseboard_fab2_lib.baseboard_fab2(sch_1):page98_i43" )
				( pin "C4G1.1"
					( objectStatus "a" )
				)
				( pin "C4G1.2"
					( objectStatus "b" )
				)
			)
			( gate "R4G21"
				( objectStatus "@baseboard_fab2_lib.baseboard_fab2(sch_1):page98_i46" )
				( pin "R4G21.1"
					( objectStatus "a" )
				)
				( pin "R4G21.2"
					( objectStatus "b" )
				)
			)
			( gate "R4G22"
				( objectStatus "@baseboard_fab2_lib.baseboard_fab2(sch_1):page98_i48" )
				( pin "R4G22.1"
					( objectStatus "a" )
				)
				( pin "R4G22.2"
					( objectStatus "b" )
				)
			)
			( gate "R4G20"
				( objectStatus "@baseboard_fab2_lib.baseboard_fab2(sch_1):page98_i50" )
				( pin "R4G20.1"
					( objectStatus "a" )
				)
				( pin "R4G20.2"
					( objectStatus "b" )
				)
			)
			( gate "C4G17"
				( objectStatus "@baseboard_fab2_lib.baseboard_fab2(sch_1):page98_i51" )
				( pin "C4G17.1"
					( objectStatus "a" )
				)
				( pin "C4G17.2"
					( objectStatus "b" )
				)
			)
			( gate "R6L13"
				( objectStatus "@baseboard_fab2_lib.baseboard_fab2(sch_1):page98_i54" )
				( pin "R6L13.1"
					( objectStatus "a" )
				)
				( pin "R6L13.2"
					( objectStatus "b" )
				)
			)
			( gate "R6L12"
				( objectStatus "@baseboard_fab2_lib.baseboard_fab2(sch_1):page98_i56" )
				( pin "R6L12.1"
					( objectStatus "a" )
				)
				( pin "R6L12.2"
					( objectStatus "b" )
				)
			)
			( gate "R6L14"
				( objectStatus "@baseboard_fab2_lib.baseboard_fab2(sch_1):page98_i58" )
				( pin "R6L14.1"
					( objectStatus "a" )
				)
				( pin "R6L14.2"
					( objectStatus "b" )
				)
			)
			( gate "C6L7"
				( objectStatus "@baseboard_fab2_lib.baseboard_fab2(sch_1):page98_i59" )
				( pin "C6L7.1"
					( objectStatus "a" )
				)
				( pin "C6L7.2"
					( objectStatus "b" )
				)
			)
			( gate "R6L2"
				( objectStatus "@baseboard_fab2_lib.baseboard_fab2(sch_1):page98_i62" )
				( pin "R6L2.1"
					( objectStatus "a" )
				)
				( pin "R6L2.2"
					( objectStatus "b" )
				)
			)
			( gate "R6L1"
				( objectStatus "@baseboard_fab2_lib.baseboard_fab2(sch_1):page98_i64" )
				( pin "R6L1.1"
					( objectStatus "a" )
				)
				( pin "R6L1.2"
					( objectStatus "b" )
				)
			)
			( gate "R6L3"
				( objectStatus "@baseboard_fab2_lib.baseboard_fab2(sch_1):page98_i66" )
				( pin "R6L3.1"
					( objectStatus "a" )
				)
				( pin "R6L3.2"
					( objectStatus "b" )
				)
			)
			( gate "C6L2"
				( objectStatus "@baseboard_fab2_lib.baseboard_fab2(sch_1):page98_i67" )
				( pin "C6L2.1"
					( objectStatus "a" )
				)
				( pin "C6L2.2"
					( objectStatus "b" )
				)
			)
			( gate "C6F2"
				( objectStatus "@baseboard_fab2_lib.baseboard_fab2(sch_1):page99_i2" )
				( pin "C6F2.1"
					( objectStatus "a" )
				)
				( pin "C6F2.2"
					( objectStatus "b" )
				)
			)
			( gate "C6F3"
				( objectStatus "@baseboard_fab2_lib.baseboard_fab2(sch_1):page99_i7" )
				( pin "C6F3.1"
					( objectStatus "a" )
				)
				( pin "C6F3.2"
					( objectStatus "b" )
				)
			)
			( gate "R4T9"
				( objectStatus "@baseboard_fab2_lib.baseboard_fab2(sch_1):page99_i9" )
				( pin "R4T9.1"
					( objectStatus "a" )
				)
				( pin "R4T9.2"
					( objectStatus "b" )
				)
			)
			( gate "R4T10"
				( objectStatus "@baseboard_fab2_lib.baseboard_fab2(sch_1):page99_i10" )
				( pin "R4T10.1"
					( objectStatus "a" )
				)
				( pin "R4T10.2"
					( objectStatus "b" )
				)
			)
			( gate "R4T8"
				( objectStatus "@baseboard_fab2_lib.baseboard_fab2(sch_1):page99_i11" )
				( pin "R4T8.1"
					( objectStatus "a" )
				)
				( pin "R4T8.2"
					( objectStatus "b" )
				)
			)
			( gate "R4T7"
				( objectStatus "@baseboard_fab2_lib.baseboard_fab2(sch_1):page99_i13" )
				( pin "R4T7.1"
					( objectStatus "a" )
				)
				( pin "R4T7.2"
					( objectStatus "b" )
				)
			)
			( gate "U6F1"
				( objectStatus "@baseboard_fab2_lib.baseboard_fab2(sch_1):page99_i15" )
				( pin "U6F1.5"
					( objectStatus "en" )
				)
				( pin "U6F1.2"
					( objectStatus "scla" )
				)
				( pin "U6F1.7"
					( objectStatus "sclb" )
				)
				( pin "U6F1.3"
					( objectStatus "sdaa" )
				)
				( pin "U6F1.6"
					( objectStatus "sdab" )
				)
				( pin "U6F1.1"
					( objectStatus "vcca" )
				)
				( pin "U6F1.8"
					( objectStatus "vccb" )
				)
			)
			( gate "R4T6"
				( objectStatus "@baseboard_fab2_lib.baseboard_fab2(sch_1):page99_i17" )
				( pin "R4T6.1"
					( objectStatus "a" )
				)
				( pin "R4T6.2"
					( objectStatus "b" )
				)
			)
			( gate "R4T5"
				( objectStatus "@baseboard_fab2_lib.baseboard_fab2(sch_1):page99_i19" )
				( pin "R4T5.1"
					( objectStatus "a" )
				)
				( pin "R4T5.2"
					( objectStatus "b" )
				)
			)
			( gate "R4T4"
				( objectStatus "@baseboard_fab2_lib.baseboard_fab2(sch_1):page99_i20" )
				( pin "R4T4.1"
					( objectStatus "a" )
				)
				( pin "R4T4.2"
					( objectStatus "b" )
				)
			)
			( gate "C7E1"
				( objectStatus "@baseboard_fab2_lib.baseboard_fab2(sch_1):page99_i23" )
				( pin "C7E1.1"
					( objectStatus "a" )
				)
				( pin "C7E1.2"
					( objectStatus "b" )
				)
			)
			( gate "C4G22"
				( objectStatus "@baseboard_fab2_lib.baseboard_fab2(sch_1):page99_i27" )
				( pin "C4G22.1"
					( objectStatus "a" )
				)
				( pin "C4G22.2"
					( objectStatus "b" )
				)
			)
			( gate "C7E2"
				( objectStatus "@baseboard_fab2_lib.baseboard_fab2(sch_1):page99_i32" )
				( pin "C7E2.1"
					( objectStatus "a" )
				)
				( pin "C7E2.2"
					( objectStatus "b" )
				)
			)
			( gate "R3R9"
				( objectStatus "@baseboard_fab2_lib.baseboard_fab2(sch_1):page99_i34" )
				( pin "R3R9.1"
					( objectStatus "a" )
				)
				( pin "R3R9.2"
					( objectStatus "b" )
				)
			)
			( gate "R3R8"
				( objectStatus "@baseboard_fab2_lib.baseboard_fab2(sch_1):page99_i35" )
				( pin "R3R8.1"
					( objectStatus "a" )
				)
				( pin "R3R8.2"
					( objectStatus "b" )
				)
			)
			( gate "C4G25"
				( objectStatus "@baseboard_fab2_lib.baseboard_fab2(sch_1):page99_i41" )
				( pin "C4G25.1"
					( objectStatus "a" )
				)
				( pin "C4G25.2"
					( objectStatus "b" )
				)
			)
			( gate "R6U13"
				( objectStatus "@baseboard_fab2_lib.baseboard_fab2(sch_1):page99_i42" )
				( pin "R6U13.1"
					( objectStatus "a" )
				)
				( pin "R6U13.2"
					( objectStatus "b" )
				)
			)
			( gate "R6U14"
				( objectStatus "@baseboard_fab2_lib.baseboard_fab2(sch_1):page99_i43" )
				( pin "R6U14.1"
					( objectStatus "a" )
				)
				( pin "R6U14.2"
					( objectStatus "b" )
				)
			)
			( gate "C3B4"
				( objectStatus "@baseboard_fab2_lib.baseboard_fab2(sch_1):page99_i47" )
				( pin "C3B4.1"
					( objectStatus "a" )
				)
				( pin "C3B4.2"
					( objectStatus "b" )
				)
			)
			( gate "C3B5"
				( objectStatus "@baseboard_fab2_lib.baseboard_fab2(sch_1):page99_i53" )
				( pin "C3B5.1"
					( objectStatus "a" )
				)
				( pin "C3B5.2"
					( objectStatus "b" )
				)
			)
			( gate "R7M5"
				( objectStatus "@baseboard_fab2_lib.baseboard_fab2(sch_1):page99_i55" )
				( pin "R7M5.1"
					( objectStatus "a" )
				)
				( pin "R7M5.2"
					( objectStatus "b" )
				)
			)
			( gate "R7M4"
				( objectStatus "@baseboard_fab2_lib.baseboard_fab2(sch_1):page99_i56" )
				( pin "R7M4.1"
					( objectStatus "a" )
				)
				( pin "R7M4.2"
					( objectStatus "b" )
				)
			)
			( gate "U7E1"
				( objectStatus "@baseboard_fab2_lib.baseboard_fab2(sch_1):page99_i61" )
				( pin "U7E1.5"
					( objectStatus "en" )
				)
				( pin "U7E1.2"
					( objectStatus "scla" )
				)
				( pin "U7E1.7"
					( objectStatus "sclb" )
				)
				( pin "U7E1.3"
					( objectStatus "sdaa" )
				)
				( pin "U7E1.6"
					( objectStatus "sdab" )
				)
				( pin "U7E1.1"
					( objectStatus "vcca" )
				)
				( pin "U7E1.8"
					( objectStatus "vccb" )
				)
			)
			( gate "U4G1"
				( objectStatus "@baseboard_fab2_lib.baseboard_fab2(sch_1):page99_i63" )
				( pin "U4G1.5"
					( objectStatus "en" )
				)
				( pin "U4G1.2"
					( objectStatus "scla" )
				)
				( pin "U4G1.7"
					( objectStatus "sclb" )
				)
				( pin "U4G1.3"
					( objectStatus "sdaa" )
				)
				( pin "U4G1.6"
					( objectStatus "sdab" )
				)
				( pin "U4G1.1"
					( objectStatus "vcca" )
				)
				( pin "U4G1.8"
					( objectStatus "vccb" )
				)
			)
			( gate "R3R13"
				( objectStatus "@baseboard_fab2_lib.baseboard_fab2(sch_1):page99_i65" )
				( pin "R3R13.1"
					( objectStatus "a" )
				)
				( pin "R3R13.2"
					( objectStatus "b" )
				)
			)
			( gate "R3R6"
				( objectStatus "@baseboard_fab2_lib.baseboard_fab2(sch_1):page99_i67" )
				( pin "R3R6.1"
					( objectStatus "a" )
				)
				( pin "R3R6.2"
					( objectStatus "b" )
				)
			)
			( gate "R6T1"
				( objectStatus "@baseboard_fab2_lib.baseboard_fab2(sch_1):page99_i70" )
				( pin "R6T1.1"
					( objectStatus "a" )
				)
				( pin "R6T1.2"
					( objectStatus "b" )
				)
			)
			( gate "R6T2"
				( objectStatus "@baseboard_fab2_lib.baseboard_fab2(sch_1):page99_i72" )
				( pin "R6T2.1"
					( objectStatus "a" )
				)
				( pin "R6T2.2"
					( objectStatus "b" )
				)
			)
			( gate "U3B1"
				( objectStatus "@baseboard_fab2_lib.baseboard_fab2(sch_1):page99_i75" )
				( pin "U3B1.5"
					( objectStatus "en" )
				)
				( pin "U3B1.2"
					( objectStatus "scla" )
				)
				( pin "U3B1.7"
					( objectStatus "sclb" )
				)
				( pin "U3B1.3"
					( objectStatus "sdaa" )
				)
				( pin "U3B1.6"
					( objectStatus "sdab" )
				)
				( pin "U3B1.1"
					( objectStatus "vcca" )
				)
				( pin "U3B1.8"
					( objectStatus "vccb" )
				)
			)
			( gate "R7M7"
				( objectStatus "@baseboard_fab2_lib.baseboard_fab2(sch_1):page99_i77" )
				( pin "R7M7.1"
					( objectStatus "a" )
				)
				( pin "R7M7.2"
					( objectStatus "b" )
				)
			)
			( gate "R7M2"
				( objectStatus "@baseboard_fab2_lib.baseboard_fab2(sch_1):page99_i79" )
				( pin "R7M2.1"
					( objectStatus "a" )
				)
				( pin "R7M2.2"
					( objectStatus "b" )
				)
			)
			( gate "R4T3"
				( objectStatus "@baseboard_fab2_lib.baseboard_fab2(sch_1):page99_i83" )
				( pin "R4T3.1"
					( objectStatus "a" )
				)
				( pin "R4T3.2"
					( objectStatus "b" )
				)
			)
			( gate "R3R7"
				( objectStatus "@baseboard_fab2_lib.baseboard_fab2(sch_1):page99_i88" )
				( pin "R3R7.1"
					( objectStatus "a" )
				)
				( pin "R3R7.2"
					( objectStatus "b" )
				)
			)
			( gate "R6T3"
				( objectStatus "@baseboard_fab2_lib.baseboard_fab2(sch_1):page99_i92" )
				( pin "R6T3.1"
					( objectStatus "a" )
				)
				( pin "R6T3.2"
					( objectStatus "b" )
				)
			)
			( gate "R7M3"
				( objectStatus "@baseboard_fab2_lib.baseboard_fab2(sch_1):page99_i98" )
				( pin "R7M3.1"
					( objectStatus "a" )
				)
				( pin "R7M3.2"
					( objectStatus "b" )
				)
			)
			( gate "R3R12"
				( objectStatus "@baseboard_fab2_lib.baseboard_fab2(sch_1):page99_i101" )
				( pin "R3R12.1"
					( objectStatus "a" )
				)
				( pin "R3R12.2"
					( objectStatus "b" )
				)
			)
			( gate "R3R5"
				( objectStatus "@baseboard_fab2_lib.baseboard_fab2(sch_1):page99_i103" )
				( pin "R3R5.1"
					( objectStatus "a" )
				)
				( pin "R3R5.2"
					( objectStatus "b" )
				)
			)
			( gate "R6U18"
				( objectStatus "@baseboard_fab2_lib.baseboard_fab2(sch_1):page99_i104" )
				( pin "R6U18.1"
					( objectStatus "a" )
				)
				( pin "R6U18.2"
					( objectStatus "b" )
				)
			)
			( gate "R6U17"
				( objectStatus "@baseboard_fab2_lib.baseboard_fab2(sch_1):page99_i106" )
				( pin "R6U17.1"
					( objectStatus "a" )
				)
				( pin "R6U17.2"
					( objectStatus "b" )
				)
			)
			( gate "R7M6"
				( objectStatus "@baseboard_fab2_lib.baseboard_fab2(sch_1):page99_i107" )
				( pin "R7M6.1"
					( objectStatus "a" )
				)
				( pin "R7M6.2"
					( objectStatus "b" )
				)
			)
			( gate "R7M1"
				( objectStatus "@baseboard_fab2_lib.baseboard_fab2(sch_1):page99_i109" )
				( pin "R7M1.1"
					( objectStatus "a" )
				)
				( pin "R7M1.2"
					( objectStatus "b" )
				)
			)
			( gate "R3R14"
				( objectStatus "@baseboard_fab2_lib.baseboard_fab2(sch_1):page99_i110" )
				( pin "R3R14.1"
					( objectStatus "a" )
				)
				( pin "R3R14.2"
					( objectStatus "b" )
				)
			)
			( gate "R6T4"
				( objectStatus "@baseboard_fab2_lib.baseboard_fab2(sch_1):page99_i111" )
				( pin "R6T4.1"
					( objectStatus "a" )
				)
				( pin "R6T4.2"
					( objectStatus "b" )
				)
			)
			( gate "R7M8"
				( objectStatus "@baseboard_fab2_lib.baseboard_fab2(sch_1):page99_i112" )
				( pin "R7M8.1"
					( objectStatus "a" )
				)
				( pin "R7M8.2"
					( objectStatus "b" )
				)
			)
			( gate "R1F6"
				( objectStatus "@baseboard_fab2_lib.baseboard_fab2(sch_1):page100_i2" )
				( pin "R1F6.1"
					( objectStatus "a" )
				)
				( pin "R1F6.2"
					( objectStatus "b" )
				)
			)
			( gate "R9L11"
				( objectStatus "@baseboard_fab2_lib.baseboard_fab2(sch_1):page100_i4" )
				( pin "R9L11.1"
					( objectStatus "a" )
				)
				( pin "R9L11.2"
					( objectStatus "b" )
				)
			)
			( gate "R1F5"
				( objectStatus "@baseboard_fab2_lib.baseboard_fab2(sch_1):page100_i6" )
				( pin "R1F5.1"
					( objectStatus "a" )
				)
				( pin "R1F5.2"
					( objectStatus "b" )
				)
			)
			( gate "R1F4"
				( objectStatus "@baseboard_fab2_lib.baseboard_fab2(sch_1):page100_i7" )
				( pin "R1F4.1"
					( objectStatus "a" )
				)
				( pin "R1F4.2"
					( objectStatus "b" )
				)
			)
			( gate "C1F19"
				( objectStatus "@baseboard_fab2_lib.baseboard_fab2(sch_1):page100_i8" )
				( pin "C1F19.1"
					( objectStatus "a" )
				)
				( pin "C1F19.2"
					( objectStatus "b" )
				)
			)
			( gate "R9M1"
				( objectStatus "@baseboard_fab2_lib.baseboard_fab2(sch_1):page100_i11" )
				( pin "R9M1.1"
					( objectStatus "a" )
				)
				( pin "R9M1.2"
					( objectStatus "b" )
				)
			)
			( gate "R9M2"
				( objectStatus "@baseboard_fab2_lib.baseboard_fab2(sch_1):page100_i13" )
				( pin "R9M2.1"
					( objectStatus "a" )
				)
				( pin "R9M2.2"
					( objectStatus "b" )
				)
			)
			( gate "C9M2"
				( objectStatus "@baseboard_fab2_lib.baseboard_fab2(sch_1):page100_i15" )
				( pin "C9M2.1"
					( objectStatus "a" )
				)
				( pin "C9M2.2"
					( objectStatus "b" )
				)
			)
			( gate "R1G2"
				( objectStatus "@baseboard_fab2_lib.baseboard_fab2(sch_1):page100_i19" )
				( pin "R1G2.1"
					( objectStatus "a" )
				)
				( pin "R1G2.2"
					( objectStatus "b" )
				)
			)
			( gate "R1G3"
				( objectStatus "@baseboard_fab2_lib.baseboard_fab2(sch_1):page100_i20" )
				( pin "R1G3.1"
					( objectStatus "a" )
				)
				( pin "R1G3.2"
					( objectStatus "b" )
				)
			)
			( gate "R9L7"
				( objectStatus "@baseboard_fab2_lib.baseboard_fab2(sch_1):page100_i22" )
				( pin "R9L7.1"
					( objectStatus "a" )
				)
				( pin "R9L7.2"
					( objectStatus "b" )
				)
			)
			( gate "R9L6"
				( objectStatus "@baseboard_fab2_lib.baseboard_fab2(sch_1):page100_i24" )
				( pin "R9L6.1"
					( objectStatus "a" )
				)
				( pin "R9L6.2"
					( objectStatus "b" )
				)
			)
			( gate "R1G1"
				( objectStatus "@baseboard_fab2_lib.baseboard_fab2(sch_1):page100_i25" )
				( pin "R1G1.1"
					( objectStatus "a" )
				)
				( pin "R1G1.2"
					( objectStatus "b" )
				)
			)
			( gate "C1G8"
				( objectStatus "@baseboard_fab2_lib.baseboard_fab2(sch_1):page100_i26" )
				( pin "C1G8.1"
					( objectStatus "a" )
				)
				( pin "C1G8.2"
					( objectStatus "b" )
				)
			)
			( gate "R9L8"
				( objectStatus "@baseboard_fab2_lib.baseboard_fab2(sch_1):page100_i29" )
				( pin "R9L8.1"
					( objectStatus "a" )
				)
				( pin "R9L8.2"
					( objectStatus "b" )
				)
			)
			( gate "C9L8"
				( objectStatus "@baseboard_fab2_lib.baseboard_fab2(sch_1):page100_i30" )
				( pin "C9L8.1"
					( objectStatus "a" )
				)
				( pin "C9L8.2"
					( objectStatus "b" )
				)
			)
			( gate "R1G15"
				( objectStatus "@baseboard_fab2_lib.baseboard_fab2(sch_1):page100_i35" )
				( pin "R1G15.1"
					( objectStatus "a" )
				)
				( pin "R1G15.2"
					( objectStatus "b" )
				)
			)
			( gate "R1G17"
				( objectStatus "@baseboard_fab2_lib.baseboard_fab2(sch_1):page100_i36" )
				( pin "R1G17.1"
					( objectStatus "a" )
				)
				( pin "R1G17.2"
					( objectStatus "b" )
				)
			)
			( gate "R9L2"
				( objectStatus "@baseboard_fab2_lib.baseboard_fab2(sch_1):page100_i38" )
				( pin "R9L2.1"
					( objectStatus "a" )
				)
				( pin "R9L2.2"
					( objectStatus "b" )
				)
			)
			( gate "R9L1"
				( objectStatus "@baseboard_fab2_lib.baseboard_fab2(sch_1):page100_i40" )
				( pin "R9L1.1"
					( objectStatus "a" )
				)
				( pin "R9L1.2"
					( objectStatus "b" )
				)
			)
			( gate "R1G14"
				( objectStatus "@baseboard_fab2_lib.baseboard_fab2(sch_1):page100_i41" )
				( pin "R1G14.1"
					( objectStatus "a" )
				)
				( pin "R1G14.2"
					( objectStatus "b" )
				)
			)
			( gate "C1G18"
				( objectStatus "@baseboard_fab2_lib.baseboard_fab2(sch_1):page100_i42" )
				( pin "C1G18.1"
					( objectStatus "a" )
				)
				( pin "C1G18.2"
					( objectStatus "b" )
				)
			)
			( gate "R9L3"
				( objectStatus "@baseboard_fab2_lib.baseboard_fab2(sch_1):page100_i45" )
				( pin "R9L3.1"
					( objectStatus "a" )
				)
				( pin "R9L3.2"
					( objectStatus "b" )
				)
			)
			( gate "C9L3"
				( objectStatus "@baseboard_fab2_lib.baseboard_fab2(sch_1):page100_i46" )
				( pin "C9L3.1"
					( objectStatus "a" )
				)
				( pin "C9L3.2"
					( objectStatus "b" )
				)
			)
			( gate "R8F29"
				( objectStatus "@baseboard_fab2_lib.baseboard_fab2(sch_1):page101_i20" )
				( pin "R8F29.1"
					( objectStatus "a" )
				)
				( pin "R8F29.2"
					( objectStatus "b" )
				)
			)
			( gate "R8F25"
				( objectStatus "@baseboard_fab2_lib.baseboard_fab2(sch_1):page101_i28" )
				( pin "R8F25.1"
					( objectStatus "a" )
				)
				( pin "R8F25.2"
					( objectStatus "b" )
				)
			)
			( gate "EU8F2"
				( objectStatus "@baseboard_fab2_lib.baseboard_fab2(sch_1):page101_i34" )
				( pin "EU8F2.16"
					( objectStatus "\25mhz_0\" )
				)
				( pin "EU8F2.17"
					( objectStatus "\25mhz_1\" )
				)
				( pin "EU8F2.13"
					( objectStatus "\32khz\" )
				)
				( pin "EU8F2.22"
					( objectStatus "\33mhz_smbadr\" )
				)
				( pin "EU8F2.8"
					( objectStatus "cpuclkc0" )
				)
				( pin "EU8F2.7"
					( objectStatus "cpuclkt0" )
				)
				( pin "EU8F2.4"
					( objectStatus "dot96ssc" )
				)
				( pin "EU8F2.3"
					( objectStatus "dot96sst" )
				)
				( pin "EU8F2.1"
					( objectStatus "gnd(0)" )
				)
				( pin "EU8F2.41"
					( objectStatus "gnd(1)" )
				)
				( pin "EU8F2.14"
					( objectStatus "gnd32k" )
				)
				( pin "EU8F2.21"
					( objectStatus "gnd33" )
				)
				( pin "EU8F2.35"
					( objectStatus "gnd_rgmii" )
				)
				( pin "EU8F2.10"
					( objectStatus "gndcpu" )
				)
				( pin "EU8F2.18"
					( objectStatus "gndref" )
				)
				( pin "EU8F2.27"
					( objectStatus "gndrmii(0)" )
				)
				( pin "EU8F2.30"
					( objectStatus "gndrmii(1)" )
				)
				( pin "EU8F2.11"
					( objectStatus "iref" )
				)
				( pin "EU8F2.5"
					( objectStatus "oe_96" )
				)
				( pin "EU8F2.6"
					( objectStatus "oe_cpu" )
				)
				( pin "EU8F2.37"
					( objectStatus "rgmii(0)" )
				)
				( pin "EU8F2.36"
					( objectStatus "rgmii(1)" )
				)
				( pin "EU8F2.33"
					( objectStatus "rmii(0)" )
				)
				( pin "EU8F2.32"
					( objectStatus "rmii(1)" )
				)
				( pin "EU8F2.29"
					( objectStatus "rmii(2)" )
				)
				( pin "EU8F2.28"
					( objectStatus "rmii(3)" )
				)
				( pin "EU8F2.25"
					( objectStatus "rmii(4)" )
				)
				( pin "EU8F2.24"
					( objectStatus "rmii(5)" )
				)
				( pin "EU8F2.38"
					( objectStatus "smbclk" )
				)
				( pin "EU8F2.39"
					( objectStatus "smbdat" )
				)
				( pin "EU8F2.12"
					( objectStatus "vdd32k" )
				)
				( pin "EU8F2.23"
					( objectStatus "vdd33" )
				)
				( pin "EU8F2.2"
					( objectStatus "vdd96" )
				)
				( pin "EU8F2.34"
					( objectStatus "vdd_rgmii" )
				)
				( pin "EU8F2.9"
					( objectStatus "vddcpu" )
				)
				( pin "EU8F2.15"
					( objectStatus "vddref" )
				)
				( pin "EU8F2.26"
					( objectStatus "vddrmii(0)" )
				)
				( pin "EU8F2.31"
					( objectStatus "vddrmii(1)" )
				)
				( pin "EU8F2.40"
					( objectStatus "vttpwr_gd_pd_n" )
				)
				( pin "EU8F2.19"
					( objectStatus "x1_25" )
				)
				( pin "EU8F2.20"
					( objectStatus "x2_25" )
				)
			)
			( gate "R2T25"
				( objectStatus "@baseboard_fab2_lib.baseboard_fab2(sch_1):page101_i48" )
				( pin "R2T25.1"
					( objectStatus "a" )
				)
				( pin "R2T25.2"
					( objectStatus "b" )
				)
			)
			( gate "C8F18"
				( objectStatus "@baseboard_fab2_lib.baseboard_fab2(sch_1):page101_i49" )
				( pin "C8F18.1"
					( objectStatus "a" )
				)
				( pin "C8F18.2"
					( objectStatus "b" )
				)
			)
			( gate "Y8F1"
				( objectStatus "@baseboard_fab2_lib.baseboard_fab2(sch_1):page101_i52" )
				( pin "Y8F1.1"
					( objectStatus "a" )
				)
				( pin "Y8F1.3"
					( objectStatus "b" )
				)
			)
			( gate "C8F19"
				( objectStatus "@baseboard_fab2_lib.baseboard_fab2(sch_1):page101_i53" )
				( pin "C8F19.1"
					( objectStatus "a" )
				)
				( pin "C8F19.2"
					( objectStatus "b" )
				)
			)
			( gate "C2T31"
				( objectStatus "@baseboard_fab2_lib.baseboard_fab2(sch_1):page101_i89" )
				( pin "C2T31.1"
					( objectStatus "a" )
				)
				( pin "C2T31.2"
					( objectStatus "b" )
				)
			)
			( gate "C2T27"
				( objectStatus "@baseboard_fab2_lib.baseboard_fab2(sch_1):page101_i90" )
				( pin "C2T27.1"
					( objectStatus "a" )
				)
				( pin "C2T27.2"
					( objectStatus "b" )
				)
			)
			( gate "R2T23"
				( objectStatus "@baseboard_fab2_lib.baseboard_fab2(sch_1):page101_i94" )
				( pin "R2T23.1"
					( objectStatus "a" )
				)
				( pin "R2T23.2"
					( objectStatus "b" )
				)
			)
			( gate "R2T52"
				( objectStatus "@baseboard_fab2_lib.baseboard_fab2(sch_1):page101_i95" )
				( pin "R2T52.1"
					( objectStatus "a" )
				)
				( pin "R2T52.2"
					( objectStatus "b" )
				)
			)
			( gate "C2T38"
				( objectStatus "@baseboard_fab2_lib.baseboard_fab2(sch_1):page101_i97" )
				( pin "C2T38.1"
					( objectStatus "a" )
				)
				( pin "C2T38.2"
					( objectStatus "b" )
				)
			)
			( gate "C2T37"
				( objectStatus "@baseboard_fab2_lib.baseboard_fab2(sch_1):page101_i99" )
				( pin "C2T37.1"
					( objectStatus "a" )
				)
				( pin "C2T37.2"
					( objectStatus "b" )
				)
			)
			( gate "C2T18"
				( objectStatus "@baseboard_fab2_lib.baseboard_fab2(sch_1):page101_i104" )
				( pin "C2T18.1"
					( objectStatus "a" )
				)
				( pin "C2T18.2"
					( objectStatus "b" )
				)
			)
			( gate "R2T21"
				( objectStatus "@baseboard_fab2_lib.baseboard_fab2(sch_1):page101_i105" )
				( pin "R2T21.1"
					( objectStatus "a" )
				)
				( pin "R2T21.2"
					( objectStatus "b" )
				)
			)
			( gate "C2T19"
				( objectStatus "@baseboard_fab2_lib.baseboard_fab2(sch_1):page101_i106" )
				( pin "C2T19.1"
					( objectStatus "a" )
				)
				( pin "C2T19.2"
					( objectStatus "b" )
				)
			)
			( gate "C2T34"
				( objectStatus "@baseboard_fab2_lib.baseboard_fab2(sch_1):page101_i109" )
				( pin "C2T34.1"
					( objectStatus "a" )
				)
				( pin "C2T34.2"
					( objectStatus "b" )
				)
			)
			( gate "C2T30"
				( objectStatus "@baseboard_fab2_lib.baseboard_fab2(sch_1):page101_i110" )
				( pin "C2T30.1"
					( objectStatus "a" )
				)
				( pin "C2T30.2"
					( objectStatus "b" )
				)
			)
			( gate "C2T25"
				( objectStatus "@baseboard_fab2_lib.baseboard_fab2(sch_1):page101_i111" )
				( pin "C2T25.1"
					( objectStatus "a" )
				)
				( pin "C2T25.2"
					( objectStatus "b" )
				)
			)
			( gate "C2T17"
				( objectStatus "@baseboard_fab2_lib.baseboard_fab2(sch_1):page101_i112" )
				( pin "C2T17.1"
					( objectStatus "a" )
				)
				( pin "C2T17.2"
					( objectStatus "b" )
				)
			)
			( gate "C2T22"
				( objectStatus "@baseboard_fab2_lib.baseboard_fab2(sch_1):page101_i113" )
				( pin "C2T22.1"
					( objectStatus "a" )
				)
				( pin "C2T22.2"
					( objectStatus "b" )
				)
			)
			( gate "FB2T2"
				( objectStatus "@baseboard_fab2_lib.baseboard_fab2(sch_1):page101_i114" )
				( pin "FB2T2.1"
					( objectStatus "a" )
				)
				( pin "FB2T2.2"
					( objectStatus "b" )
				)
			)
			( gate "C2T28"
				( objectStatus "@baseboard_fab2_lib.baseboard_fab2(sch_1):page101_i116" )
				( pin "C2T28.1"
					( objectStatus "a" )
				)
				( pin "C2T28.2"
					( objectStatus "b" )
				)
			)
			( gate "R2T42"
				( objectStatus "@baseboard_fab2_lib.baseboard_fab2(sch_1):page101_i124" )
				( pin "R2T42.1"
					( objectStatus "a" )
				)
				( pin "R2T42.2"
					( objectStatus "b" )
				)
			)
			( gate "R2T46"
				( objectStatus "@baseboard_fab2_lib.baseboard_fab2(sch_1):page101_i125" )
				( pin "R2T46.1"
					( objectStatus "a" )
				)
				( pin "R2T46.2"
					( objectStatus "b" )
				)
			)
			( gate "R8F27"
				( objectStatus "@baseboard_fab2_lib.baseboard_fab2(sch_1):page101_i129" )
				( pin "R8F27.1"
					( objectStatus "a" )
				)
				( pin "R8F27.2"
					( objectStatus "b" )
				)
			)
			( gate "R2T47"
				( objectStatus "@baseboard_fab2_lib.baseboard_fab2(sch_1):page101_i130" )
				( pin "R2T47.1"
					( objectStatus "a" )
				)
				( pin "R2T47.2"
					( objectStatus "b" )
				)
			)
			( gate "R1T31"
				( objectStatus "@baseboard_fab2_lib.baseboard_fab2(sch_1):page101_i131" )
				( pin "R1T31.1"
					( objectStatus "a" )
				)
				( pin "R1T31.2"
					( objectStatus "b" )
				)
			)
			( gate "R7D14"
				( objectStatus "@baseboard_fab2_lib.baseboard_fab2(sch_1):page101_i132" )
				( pin "R7D14.1"
					( objectStatus "a" )
				)
				( pin "R7D14.2"
					( objectStatus "b" )
				)
			)
			( gate "R8G1"
				( objectStatus "@baseboard_fab2_lib.baseboard_fab2(sch_1):page101_i133" )
				( pin "R8G1.1"
					( objectStatus "a" )
				)
				( pin "R8G1.2"
					( objectStatus "b" )
				)
			)
			( gate "EU4D2"
				( objectStatus "@baseboard_fab2_lib.baseboard_fab2(sch_1):page102_i1" )
				( pin "EU4D2.4"
					( objectStatus "\100m_133m_n\" )
				)
				( pin "EU4D2.10"
					( objectStatus "clk_inn" )
				)
				( pin "EU4D2.9"
					( objectStatus "clk_inp" )
				)
				( pin "EU4D2.18"
					( objectStatus "dif_0n" )
				)
				( pin "EU4D2.17"
					( objectStatus "dif_0p" )
				)
				( pin "EU4D2.22"
					( objectStatus "dif_1n" )
				)
				( pin "EU4D2.21"
					( objectStatus "dif_1p" )
				)
				( pin "EU4D2.27"
					( objectStatus "dif_2n" )
				)
				( pin "EU4D2.26"
					( objectStatus "dif_2p" )
				)
				( pin "EU4D2.31"
					( objectStatus "dif_3n" )
				)
				( pin "EU4D2.30"
					( objectStatus "dif_3p" )
				)
				( pin "EU4D2.35"
					( objectStatus "dif_4n" )
				)
				( pin "EU4D2.34"
					( objectStatus "dif_4p" )
				)
				( pin "EU4D2.39"
					( objectStatus "dif_5n" )
				)
				( pin "EU4D2.38"
					( objectStatus "dif_5p" )
				)
				( pin "EU4D2.43"
					( objectStatus "dif_6n" )
				)
				( pin "EU4D2.42"
					( objectStatus "dif_6p" )
				)
				( pin "EU4D2.47"
					( objectStatus "dif_7n" )
				)
				( pin "EU4D2.46"
					( objectStatus "dif_7p" )
				)
				( pin "EU4D2.51"
					( objectStatus "dif_8n" )
				)
				( pin "EU4D2.50"
					( objectStatus "dif_8p" )
				)
				( pin "EU4D2.55"
					( objectStatus "dif_9n" )
				)
				( pin "EU4D2.54"
					( objectStatus "dif_9p" )
				)
				( pin "EU4D2.60"
					( objectStatus "dif_10n" )
				)
				( pin "EU4D2.59"
					( objectStatus "dif_10p" )
				)
				( pin "EU4D2.64"
					( objectStatus "dif_11n" )
				)
				( pin "EU4D2.63"
					( objectStatus "dif_11p" )
				)
				( pin "EU4D2.7"
					( objectStatus "gnd(0)" )
				)
				( pin "EU4D2.23"
					( objectStatus "gnd(1)" )
				)
				( pin "EU4D2.33"
					( objectStatus "gnd(2)" )
				)
				( pin "EU4D2.41"
					( objectStatus "gnd(3)" )
				)
				( pin "EU4D2.48"
					( objectStatus "gnd(4)" )
				)
				( pin "EU4D2.58"
					( objectStatus "gnd(5)" )
				)
				( pin "EU4D2.2"
					( objectStatus "gnda" )
				)
				( pin "EU4D2.5"
					( objectStatus "hbw_bypass_lobw_n" )
				)
				( pin "EU4D2.3"
					( objectStatus "nc(0)" )
				)
				( pin "EU4D2.16"
					( objectStatus "nc(1)" )
				)
				( pin "EU4D2.15"
					( objectStatus "nc(2)" )
				)
				( pin "EU4D2.19"
					( objectStatus "oe_0_n" )
				)
				( pin "EU4D2.20"
					( objectStatus "oe_1_n" )
				)
				( pin "EU4D2.28"
					( objectStatus "oe_2_n" )
				)
				( pin "EU4D2.29"
					( objectStatus "oe_3_n" )
				)
				( pin "EU4D2.36"
					( objectStatus "oe_4_n" )
				)
				( pin "EU4D2.37"
					( objectStatus "oe_5_n" )
				)
				( pin "EU4D2.44"
					( objectStatus "oe_6_n" )
				)
				( pin "EU4D2.45"
					( objectStatus "oe_7_n" )
				)
				( pin "EU4D2.52"
					( objectStatus "oe_8_n" )
				)
				( pin "EU4D2.53"
					( objectStatus "oe_9_n" )
				)
				( pin "EU4D2.61"
					( objectStatus "oe_10_n" )
				)
				( pin "EU4D2.62"
					( objectStatus "oe_11_n" )
				)
				( pin "EU4D2.6"
					( objectStatus "pwrgd_pwrdn_n" )
				)
				( pin "EU4D2.11"
					( objectStatus "sa_0" )
				)
				( pin "EU4D2.14"
					( objectStatus "sa_1" )
				)
				( pin "EU4D2.13"
					( objectStatus "scl" )
				)
				( pin "EU4D2.12"
					( objectStatus "sda" )
				)
				( pin "EU4D2.65"
					( objectStatus "thpad" )
				)
				( pin "EU4D2.24"
					( objectStatus "vdd(0)" )
				)
				( pin "EU4D2.40"
					( objectStatus "vdd(1)" )
				)
				( pin "EU4D2.57"
					( objectStatus "vdd(2)" )
				)
				( pin "EU4D2.1"
					( objectStatus "vdda" )
				)
				( pin "EU4D2.25"
					( objectStatus "vddio(0)" )
				)
				( pin "EU4D2.32"
					( objectStatus "vddio(1)" )
				)
				( pin "EU4D2.49"
					( objectStatus "vddio(2)" )
				)
				( pin "EU4D2.56"
					( objectStatus "vddio(3)" )
				)
				( pin "EU4D2.8"
					( objectStatus "vddr" )
				)
			)
			( gate "FB6P1"
				( objectStatus "@baseboard_fab2_lib.baseboard_fab2(sch_1):page102_i8" )
				( pin "FB6P1.1"
					( objectStatus "a" )
				)
				( pin "FB6P1.2"
					( objectStatus "b" )
				)
			)
			( gate "C3D22"
				( objectStatus "@baseboard_fab2_lib.baseboard_fab2(sch_1):page102_i10" )
				( pin "C3D22.1"
					( objectStatus "a" )
				)
				( pin "C3D22.2"
					( objectStatus "b" )
				)
			)
			( gate "C6P4"
				( objectStatus "@baseboard_fab2_lib.baseboard_fab2(sch_1):page102_i11" )
				( pin "C6P4.1"
					( objectStatus "a" )
				)
				( pin "C6P4.2"
					( objectStatus "b" )
				)
			)
			( gate "C6P6"
				( objectStatus "@baseboard_fab2_lib.baseboard_fab2(sch_1):page102_i12" )
				( pin "C6P6.1"
					( objectStatus "a" )
				)
				( pin "C6P6.2"
					( objectStatus "b" )
				)
			)
			( gate "C6P10"
				( objectStatus "@baseboard_fab2_lib.baseboard_fab2(sch_1):page102_i13" )
				( pin "C6P10.1"
					( objectStatus "a" )
				)
				( pin "C6P10.2"
					( objectStatus "b" )
				)
			)
			( gate "C6P5"
				( objectStatus "@baseboard_fab2_lib.baseboard_fab2(sch_1):page102_i14" )
				( pin "C6P5.1"
					( objectStatus "a" )
				)
				( pin "C6P5.2"
					( objectStatus "b" )
				)
			)
			( gate "C6P12"
				( objectStatus "@baseboard_fab2_lib.baseboard_fab2(sch_1):page102_i15" )
				( pin "C6P12.1"
					( objectStatus "a" )
				)
				( pin "C6P12.2"
					( objectStatus "b" )
				)
			)
			( gate "C6P11"
				( objectStatus "@baseboard_fab2_lib.baseboard_fab2(sch_1):page102_i16" )
				( pin "C6P11.1"
					( objectStatus "a" )
				)
				( pin "C6P11.2"
					( objectStatus "b" )
				)
			)
			( gate "C4D24"
				( objectStatus "@baseboard_fab2_lib.baseboard_fab2(sch_1):page102_i18" )
				( pin "C4D24.1"
					( objectStatus "a" )
				)
				( pin "C4D24.2"
					( objectStatus "b" )
				)
			)
			( gate "C4D23"
				( objectStatus "@baseboard_fab2_lib.baseboard_fab2(sch_1):page102_i19" )
				( pin "C4D23.1"
					( objectStatus "a" )
				)
				( pin "C4D23.2"
					( objectStatus "b" )
				)
			)
			( gate "R3D14"
				( objectStatus "@baseboard_fab2_lib.baseboard_fab2(sch_1):page102_i21" )
				( pin "R3D14.1"
					( objectStatus "a" )
				)
				( pin "R3D14.2"
					( objectStatus "b" )
				)
			)
			( gate "R6P25"
				( objectStatus "@baseboard_fab2_lib.baseboard_fab2(sch_1):page102_i26" )
				( pin "R6P25.1"
					( objectStatus "a" )
				)
				( pin "R6P25.2"
					( objectStatus "b" )
				)
			)
			( gate "C4D22"
				( objectStatus "@baseboard_fab2_lib.baseboard_fab2(sch_1):page102_i28" )
				( pin "C4D22.1"
					( objectStatus "a" )
				)
				( pin "C4D22.2"
					( objectStatus "b" )
				)
			)
			( gate "C4D27"
				( objectStatus "@baseboard_fab2_lib.baseboard_fab2(sch_1):page102_i30" )
				( pin "C4D27.1"
					( objectStatus "a" )
				)
				( pin "C4D27.2"
					( objectStatus "b" )
				)
			)
			( gate "R4D38"
				( objectStatus "@baseboard_fab2_lib.baseboard_fab2(sch_1):page102_i37" )
				( pin "R4D38.1"
					( objectStatus "a" )
				)
				( pin "R4D38.2"
					( objectStatus "b" )
				)
			)
			( gate "R4D35"
				( objectStatus "@baseboard_fab2_lib.baseboard_fab2(sch_1):page102_i38" )
				( pin "R4D35.1"
					( objectStatus "a" )
				)
				( pin "R4D35.2"
					( objectStatus "b" )
				)
			)
			( gate "R4D40"
				( objectStatus "@baseboard_fab2_lib.baseboard_fab2(sch_1):page102_i45" )
				( pin "R4D40.1"
					( objectStatus "a" )
				)
				( pin "R4D40.2"
					( objectStatus "b" )
				)
			)
			( gate "R6P23"
				( objectStatus "@baseboard_fab2_lib.baseboard_fab2(sch_1):page102_i46" )
				( pin "R6P23.1"
					( objectStatus "a" )
				)
				( pin "R6P23.2"
					( objectStatus "b" )
				)
			)
			( gate "R6P22"
				( objectStatus "@baseboard_fab2_lib.baseboard_fab2(sch_1):page102_i47" )
				( pin "R6P22.1"
					( objectStatus "a" )
				)
				( pin "R6P22.2"
					( objectStatus "b" )
				)
			)
			( gate "R4D41"
				( objectStatus "@baseboard_fab2_lib.baseboard_fab2(sch_1):page102_i53" )
				( pin "R4D41.1"
					( objectStatus "a" )
				)
				( pin "R4D41.2"
					( objectStatus "b" )
				)
			)
			( gate "C6P9"
				( objectStatus "@baseboard_fab2_lib.baseboard_fab2(sch_1):page102_i79" )
				( pin "C6P9.1"
					( objectStatus "a" )
				)
				( pin "C6P9.2"
					( objectStatus "b" )
				)
			)
			( gate "R6P21"
				( objectStatus "@baseboard_fab2_lib.baseboard_fab2(sch_1):page102_i80" )
				( pin "R6P21.1"
					( objectStatus "a" )
				)
				( pin "R6P21.2"
					( objectStatus "b" )
				)
			)
			( gate "R6P20"
				( objectStatus "@baseboard_fab2_lib.baseboard_fab2(sch_1):page102_i81" )
				( pin "R6P20.1"
					( objectStatus "a" )
				)
				( pin "R6P20.2"
					( objectStatus "b" )
				)
			)
			( gate "R4D36"
				( objectStatus "@baseboard_fab2_lib.baseboard_fab2(sch_1):page102_i82" )
				( pin "R4D36.1"
					( objectStatus "a" )
				)
				( pin "R4D36.2"
					( objectStatus "b" )
				)
			)
			( gate "R4D37"
				( objectStatus "@baseboard_fab2_lib.baseboard_fab2(sch_1):page102_i87" )
				( pin "R4D37.1"
					( objectStatus "a" )
				)
				( pin "R4D37.2"
					( objectStatus "b" )
				)
			)
			( gate "R3P30"
				( objectStatus "@baseboard_fab2_lib.baseboard_fab2(sch_1):page102_i91" )
				( pin "R3P30.1"
					( objectStatus "a" )
				)
				( pin "R3P30.2"
					( objectStatus "b" )
				)
			)
			( gate "R6"
				( objectStatus "@baseboard_fab2_lib.baseboard_fab2(sch_1):page102_i93" )
				( pin "R6.1"
					( objectStatus "a" )
				)
				( pin "R6.2"
					( objectStatus "b" )
				)
			)
			( gate "R7"
				( objectStatus "@baseboard_fab2_lib.baseboard_fab2(sch_1):page102_i94" )
				( pin "R7.1"
					( objectStatus "a" )
				)
				( pin "R7.2"
					( objectStatus "b" )
				)
			)
			( gate "R4D25"
				( objectStatus "@baseboard_fab2_lib.baseboard_fab2(sch_1):page103_i1" )
				( pin "R4D25.1"
					( objectStatus "a" )
				)
				( pin "R4D25.2"
					( objectStatus "b" )
				)
			)
			( gate "R4D23"
				( objectStatus "@baseboard_fab2_lib.baseboard_fab2(sch_1):page103_i9" )
				( pin "R4D23.1"
					( objectStatus "a" )
				)
				( pin "R4D23.2"
					( objectStatus "b" )
				)
			)
			( gate "R4D28"
				( objectStatus "@baseboard_fab2_lib.baseboard_fab2(sch_1):page103_i14" )
				( pin "R4D28.1"
					( objectStatus "a" )
				)
				( pin "R4D28.2"
					( objectStatus "b" )
				)
			)
			( gate "R4D19"
				( objectStatus "@baseboard_fab2_lib.baseboard_fab2(sch_1):page103_i19" )
				( pin "R4D19.1"
					( objectStatus "a" )
				)
				( pin "R4D19.2"
					( objectStatus "b" )
				)
			)
			( gate "R4D21"
				( objectStatus "@baseboard_fab2_lib.baseboard_fab2(sch_1):page103_i24" )
				( pin "R4D21.1"
					( objectStatus "a" )
				)
				( pin "R4D21.2"
					( objectStatus "b" )
				)
			)
			( gate "R4D13"
				( objectStatus "@baseboard_fab2_lib.baseboard_fab2(sch_1):page103_i29" )
				( pin "R4D13.1"
					( objectStatus "a" )
				)
				( pin "R4D13.2"
					( objectStatus "b" )
				)
			)
			( gate "R4D16"
				( objectStatus "@baseboard_fab2_lib.baseboard_fab2(sch_1):page103_i34" )
				( pin "R4D16.1"
					( objectStatus "a" )
				)
				( pin "R4D16.2"
					( objectStatus "b" )
				)
			)
			( gate "R4D9"
				( objectStatus "@baseboard_fab2_lib.baseboard_fab2(sch_1):page103_i39" )
				( pin "R4D9.1"
					( objectStatus "a" )
				)
				( pin "R4D9.2"
					( objectStatus "b" )
				)
			)
			( gate "R4D11"
				( objectStatus "@baseboard_fab2_lib.baseboard_fab2(sch_1):page103_i44" )
				( pin "R4D11.1"
					( objectStatus "a" )
				)
				( pin "R4D11.2"
					( objectStatus "b" )
				)
			)
			( gate "R4D2"
				( objectStatus "@baseboard_fab2_lib.baseboard_fab2(sch_1):page103_i49" )
				( pin "R4D2.1"
					( objectStatus "a" )
				)
				( pin "R4D2.2"
					( objectStatus "b" )
				)
			)
			( gate "R4D1"
				( objectStatus "@baseboard_fab2_lib.baseboard_fab2(sch_1):page103_i54" )
				( pin "R4D1.1"
					( objectStatus "a" )
				)
				( pin "R4D1.2"
					( objectStatus "b" )
				)
			)
			( gate "R4D4"
				( objectStatus "@baseboard_fab2_lib.baseboard_fab2(sch_1):page103_i59" )
				( pin "R4D4.1"
					( objectStatus "a" )
				)
				( pin "R4D4.2"
					( objectStatus "b" )
				)
			)
			( gate "R4D3"
				( objectStatus "@baseboard_fab2_lib.baseboard_fab2(sch_1):page103_i64" )
				( pin "R4D3.1"
					( objectStatus "a" )
				)
				( pin "R4D3.2"
					( objectStatus "b" )
				)
			)
			( gate "R4D29"
				( objectStatus "@baseboard_fab2_lib.baseboard_fab2(sch_1):page103_i69" )
				( pin "R4D29.1"
					( objectStatus "a" )
				)
				( pin "R4D29.2"
					( objectStatus "b" )
				)
			)
			( gate "R4D6"
				( objectStatus "@baseboard_fab2_lib.baseboard_fab2(sch_1):page103_i74" )
				( pin "R4D6.1"
					( objectStatus "a" )
				)
				( pin "R4D6.2"
					( objectStatus "b" )
				)
			)
			( gate "R4D5"
				( objectStatus "@baseboard_fab2_lib.baseboard_fab2(sch_1):page103_i79" )
				( pin "R4D5.1"
					( objectStatus "a" )
				)
				( pin "R4D5.2"
					( objectStatus "b" )
				)
			)
			( gate "R4D8"
				( objectStatus "@baseboard_fab2_lib.baseboard_fab2(sch_1):page103_i84" )
				( pin "R4D8.1"
					( objectStatus "a" )
				)
				( pin "R4D8.2"
					( objectStatus "b" )
				)
			)
			( gate "R4D7"
				( objectStatus "@baseboard_fab2_lib.baseboard_fab2(sch_1):page103_i89" )
				( pin "R4D7.1"
					( objectStatus "a" )
				)
				( pin "R4D7.2"
					( objectStatus "b" )
				)
			)
			( gate "R4D12"
				( objectStatus "@baseboard_fab2_lib.baseboard_fab2(sch_1):page103_i94" )
				( pin "R4D12.1"
					( objectStatus "a" )
				)
				( pin "R4D12.2"
					( objectStatus "b" )
				)
			)
			( gate "R4D10"
				( objectStatus "@baseboard_fab2_lib.baseboard_fab2(sch_1):page103_i99" )
				( pin "R4D10.1"
					( objectStatus "a" )
				)
				( pin "R4D10.2"
					( objectStatus "b" )
				)
			)
			( gate "R4D17"
				( objectStatus "@baseboard_fab2_lib.baseboard_fab2(sch_1):page103_i104" )
				( pin "R4D17.1"
					( objectStatus "a" )
				)
				( pin "R4D17.2"
					( objectStatus "b" )
				)
			)
			( gate "R4D14"
				( objectStatus "@baseboard_fab2_lib.baseboard_fab2(sch_1):page103_i109" )
				( pin "R4D14.1"
					( objectStatus "a" )
				)
				( pin "R4D14.2"
					( objectStatus "b" )
				)
			)
			( gate "R4D22"
				( objectStatus "@baseboard_fab2_lib.baseboard_fab2(sch_1):page103_i114" )
				( pin "R4D22.1"
					( objectStatus "a" )
				)
				( pin "R4D22.2"
					( objectStatus "b" )
				)
			)
			( gate "R4D20"
				( objectStatus "@baseboard_fab2_lib.baseboard_fab2(sch_1):page103_i119" )
				( pin "R4D20.1"
					( objectStatus "a" )
				)
				( pin "R4D20.2"
					( objectStatus "b" )
				)
			)
			( gate "R7P9"
				( objectStatus "@baseboard_fab2_lib.baseboard_fab2(sch_1):page103_i121" )
				( pin "R7P9.1"
					( objectStatus "a" )
				)
				( pin "R7P9.2"
					( objectStatus "b" )
				)
			)
			( gate "R7P12"
				( objectStatus "@baseboard_fab2_lib.baseboard_fab2(sch_1):page103_i123" )
				( pin "R7P12.1"
					( objectStatus "a" )
				)
				( pin "R7P12.2"
					( objectStatus "b" )
				)
			)
			( gate "R7P6"
				( objectStatus "@baseboard_fab2_lib.baseboard_fab2(sch_1):page103_i125" )
				( pin "R7P6.1"
					( objectStatus "a" )
				)
				( pin "R7P6.2"
					( objectStatus "b" )
				)
			)
			( gate "R7P7"
				( objectStatus "@baseboard_fab2_lib.baseboard_fab2(sch_1):page103_i127" )
				( pin "R7P7.1"
					( objectStatus "a" )
				)
				( pin "R7P7.2"
					( objectStatus "b" )
				)
			)
			( gate "R7P3"
				( objectStatus "@baseboard_fab2_lib.baseboard_fab2(sch_1):page103_i129" )
				( pin "R7P3.1"
					( objectStatus "a" )
				)
				( pin "R7P3.2"
					( objectStatus "b" )
				)
			)
			( gate "R7P4"
				( objectStatus "@baseboard_fab2_lib.baseboard_fab2(sch_1):page103_i131" )
				( pin "R7P4.1"
					( objectStatus "a" )
				)
				( pin "R7P4.2"
					( objectStatus "b" )
				)
			)
			( gate "R7P1"
				( objectStatus "@baseboard_fab2_lib.baseboard_fab2(sch_1):page103_i133" )
				( pin "R7P1.1"
					( objectStatus "a" )
				)
				( pin "R7P1.2"
					( objectStatus "b" )
				)
			)
			( gate "R7P2"
				( objectStatus "@baseboard_fab2_lib.baseboard_fab2(sch_1):page103_i135" )
				( pin "R7P2.1"
					( objectStatus "a" )
				)
				( pin "R7P2.2"
					( objectStatus "b" )
				)
			)
			( gate "R6P7"
				( objectStatus "@baseboard_fab2_lib.baseboard_fab2(sch_1):page103_i137" )
				( pin "R6P7.1"
					( objectStatus "a" )
				)
				( pin "R6P7.2"
					( objectStatus "b" )
				)
			)
			( gate "R6P8"
				( objectStatus "@baseboard_fab2_lib.baseboard_fab2(sch_1):page103_i139" )
				( pin "R6P8.1"
					( objectStatus "a" )
				)
				( pin "R6P8.2"
					( objectStatus "b" )
				)
			)
			( gate "R6P5"
				( objectStatus "@baseboard_fab2_lib.baseboard_fab2(sch_1):page103_i141" )
				( pin "R6P5.1"
					( objectStatus "a" )
				)
				( pin "R6P5.2"
					( objectStatus "b" )
				)
			)
			( gate "R6P6"
				( objectStatus "@baseboard_fab2_lib.baseboard_fab2(sch_1):page103_i143" )
				( pin "R6P6.1"
					( objectStatus "a" )
				)
				( pin "R6P6.2"
					( objectStatus "b" )
				)
			)
			( gate "R6P3"
				( objectStatus "@baseboard_fab2_lib.baseboard_fab2(sch_1):page103_i145" )
				( pin "R6P3.1"
					( objectStatus "a" )
				)
				( pin "R6P3.2"
					( objectStatus "b" )
				)
			)
			( gate "R6P4"
				( objectStatus "@baseboard_fab2_lib.baseboard_fab2(sch_1):page103_i147" )
				( pin "R6P4.1"
					( objectStatus "a" )
				)
				( pin "R6P4.2"
					( objectStatus "b" )
				)
			)
			( gate "R6P1"
				( objectStatus "@baseboard_fab2_lib.baseboard_fab2(sch_1):page103_i149" )
				( pin "R6P1.1"
					( objectStatus "a" )
				)
				( pin "R6P1.2"
					( objectStatus "b" )
				)
			)
			( gate "R6P2"
				( objectStatus "@baseboard_fab2_lib.baseboard_fab2(sch_1):page103_i151" )
				( pin "R6P2.1"
					( objectStatus "a" )
				)
				( pin "R6P2.2"
					( objectStatus "b" )
				)
			)
			( gate "R6P11"
				( objectStatus "@baseboard_fab2_lib.baseboard_fab2(sch_1):page103_i153" )
				( pin "R6P11.1"
					( objectStatus "a" )
				)
				( pin "R6P11.2"
					( objectStatus "b" )
				)
			)
			( gate "R6P9"
				( objectStatus "@baseboard_fab2_lib.baseboard_fab2(sch_1):page103_i155" )
				( pin "R6P9.1"
					( objectStatus "a" )
				)
				( pin "R6P9.2"
					( objectStatus "b" )
				)
			)
			( gate "R6P13"
				( objectStatus "@baseboard_fab2_lib.baseboard_fab2(sch_1):page103_i157" )
				( pin "R6P13.1"
					( objectStatus "a" )
				)
				( pin "R6P13.2"
					( objectStatus "b" )
				)
			)
			( gate "R6P12"
				( objectStatus "@baseboard_fab2_lib.baseboard_fab2(sch_1):page103_i159" )
				( pin "R6P12.1"
					( objectStatus "a" )
				)
				( pin "R6P12.2"
					( objectStatus "b" )
				)
			)
			( gate "R4D24"
				( objectStatus "@baseboard_fab2_lib.baseboard_fab2(sch_1):page103_i161" )
				( pin "R4D24.1"
					( objectStatus "a" )
				)
				( pin "R4D24.2"
					( objectStatus "b" )
				)
			)
			( gate "R4D18"
				( objectStatus "@baseboard_fab2_lib.baseboard_fab2(sch_1):page103_i163" )
				( pin "R4D18.1"
					( objectStatus "a" )
				)
				( pin "R4D18.2"
					( objectStatus "b" )
				)
			)
			( gate "R6P17"
				( objectStatus "@baseboard_fab2_lib.baseboard_fab2(sch_1):page103_i165" )
				( pin "R6P17.1"
					( objectStatus "a" )
				)
				( pin "R6P17.2"
					( objectStatus "b" )
				)
			)
			( gate "R6P15"
				( objectStatus "@baseboard_fab2_lib.baseboard_fab2(sch_1):page103_i167" )
				( pin "R6P15.1"
					( objectStatus "a" )
				)
				( pin "R6P15.2"
					( objectStatus "b" )
				)
			)
			( gate "C6F1"
				( objectStatus "@baseboard_fab2_lib.baseboard_fab2(sch_1):page104_i25" )
				( pin "C6F1.1"
					( objectStatus "a" )
				)
				( pin "C6F1.2"
					( objectStatus "b" )
				)
			)
			( gate "C3F2"
				( objectStatus "@baseboard_fab2_lib.baseboard_fab2(sch_1):page104_i34" )
				( pin "C3F2.1"
					( objectStatus "a" )
				)
				( pin "C3F2.2"
					( objectStatus "b" )
				)
			)
			( gate "R6F8"
				( objectStatus "@baseboard_fab2_lib.baseboard_fab2(sch_1):page104_i37" )
				( pin "R6F8.1"
					( objectStatus "a" )
				)
				( pin "R6F8.2"
					( objectStatus "b" )
				)
			)
			( gate "R6F6"
				( objectStatus "@baseboard_fab2_lib.baseboard_fab2(sch_1):page104_i41" )
				( pin "R6F6.1"
					( objectStatus "a" )
				)
				( pin "R6F6.2"
					( objectStatus "b" )
				)
			)
			( gate "R3F1"
				( objectStatus "@baseboard_fab2_lib.baseboard_fab2(sch_1):page104_i51" )
				( pin "R3F1.1"
					( objectStatus "a" )
				)
				( pin "R3F1.2"
					( objectStatus "b" )
				)
			)
			( gate "R3F3"
				( objectStatus "@baseboard_fab2_lib.baseboard_fab2(sch_1):page104_i53" )
				( pin "R3F3.1"
					( objectStatus "a" )
				)
				( pin "R3F3.2"
					( objectStatus "b" )
				)
			)
			( gate "R6F7"
				( objectStatus "@baseboard_fab2_lib.baseboard_fab2(sch_1):page104_i67" )
				( pin "R6F7.1"
					( objectStatus "a" )
				)
				( pin "R6F7.2"
					( objectStatus "b" )
				)
			)
			( gate "R6F9"
				( objectStatus "@baseboard_fab2_lib.baseboard_fab2(sch_1):page104_i68" )
				( pin "R6F9.1"
					( objectStatus "a" )
				)
				( pin "R6F9.2"
					( objectStatus "b" )
				)
			)
			( gate "R3F2"
				( objectStatus "@baseboard_fab2_lib.baseboard_fab2(sch_1):page104_i69" )
				( pin "R3F2.1"
					( objectStatus "a" )
				)
				( pin "R3F2.2"
					( objectStatus "b" )
				)
			)
			( gate "R3F4"
				( objectStatus "@baseboard_fab2_lib.baseboard_fab2(sch_1):page104_i70" )
				( pin "R3F4.1"
					( objectStatus "a" )
				)
				( pin "R3F4.2"
					( objectStatus "b" )
				)
			)
			( gate "Y6F1"
				( objectStatus "@baseboard_fab2_lib.baseboard_fab2(sch_1):page104_i71" )
				( pin "Y6F1.1"
					( objectStatus "enable_disable" )
				)
				( pin "Y6F1.3"
					( objectStatus "gnd" )
				)
				( pin "Y6F1.2"
					( objectStatus "nc_gnd" )
				)
				( pin "Y6F1.4"
					( objectStatus "\out\" )
				)
				( pin "Y6F1.5"
					( objectStatus "out_n" )
				)
				( pin "Y6F1.6"
					( objectStatus "vcc" )
				)
			)
			( gate "Y3F1"
				( objectStatus "@baseboard_fab2_lib.baseboard_fab2(sch_1):page104_i72" )
				( pin "Y3F1.1"
					( objectStatus "enable_disable" )
				)
				( pin "Y3F1.3"
					( objectStatus "gnd" )
				)
				( pin "Y3F1.2"
					( objectStatus "nc_gnd" )
				)
				( pin "Y3F1.4"
					( objectStatus "\out\" )
				)
				( pin "Y3F1.5"
					( objectStatus "out_n" )
				)
				( pin "Y3F1.6"
					( objectStatus "vcc" )
				)
			)
			( gate "R16"
				( objectStatus "@baseboard_fab2_lib.baseboard_fab2(sch_1):page104_i78" )
				( pin "R16.1"
					( objectStatus "a" )
				)
				( pin "R16.2"
					( objectStatus "b" )
				)
			)
			( gate "R17"
				( objectStatus "@baseboard_fab2_lib.baseboard_fab2(sch_1):page104_i79" )
				( pin "R17.1"
					( objectStatus "a" )
				)
				( pin "R17.2"
					( objectStatus "b" )
				)
			)
			( gate "R18"
				( objectStatus "@baseboard_fab2_lib.baseboard_fab2(sch_1):page104_i84" )
				( pin "R18.1"
					( objectStatus "a" )
				)
				( pin "R18.2"
					( objectStatus "b" )
				)
			)
			( gate "R19"
				( objectStatus "@baseboard_fab2_lib.baseboard_fab2(sch_1):page104_i88" )
				( pin "R19.1"
					( objectStatus "a" )
				)
				( pin "R19.2"
					( objectStatus "b" )
				)
			)
			( gate "R10"
				( objectStatus "@baseboard_fab2_lib.baseboard_fab2(sch_1):page104_i93" )
				( pin "R10.1"
					( objectStatus "a" )
				)
				( pin "R10.2"
					( objectStatus "b" )
				)
			)
			( gate "R11"
				( objectStatus "@baseboard_fab2_lib.baseboard_fab2(sch_1):page104_i94" )
				( pin "R11.1"
					( objectStatus "a" )
				)
				( pin "R11.2"
					( objectStatus "b" )
				)
			)
			( gate "R20"
				( objectStatus "@baseboard_fab2_lib.baseboard_fab2(sch_1):page104_i95" )
				( pin "R20.1"
					( objectStatus "a" )
				)
				( pin "R20.2"
					( objectStatus "b" )
				)
			)
			( gate "R12"
				( objectStatus "@baseboard_fab2_lib.baseboard_fab2(sch_1):page104_i96" )
				( pin "R12.1"
					( objectStatus "a" )
				)
				( pin "R12.2"
					( objectStatus "b" )
				)
			)
			( gate "R13"
				( objectStatus "@baseboard_fab2_lib.baseboard_fab2(sch_1):page104_i97" )
				( pin "R13.1"
					( objectStatus "a" )
				)
				( pin "R13.2"
					( objectStatus "b" )
				)
			)
			( gate "R21"
				( objectStatus "@baseboard_fab2_lib.baseboard_fab2(sch_1):page104_i98" )
				( pin "R21.1"
					( objectStatus "a" )
				)
				( pin "R21.2"
					( objectStatus "b" )
				)
			)
			( gate "C7G24"
				( objectStatus "@baseboard_fab2_lib.baseboard_fab2(sch_1):page105_i1" )
				( pin "C7G24.1"
					( objectStatus "a" )
				)
				( pin "C7G24.2"
					( objectStatus "b" )
				)
			)
			( gate "C7G6"
				( objectStatus "@baseboard_fab2_lib.baseboard_fab2(sch_1):page105_i6" )
				( pin "C7G6.1"
					( objectStatus "a" )
				)
				( pin "C7G6.2"
					( objectStatus "b" )
				)
			)
			( gate "C7G7"
				( objectStatus "@baseboard_fab2_lib.baseboard_fab2(sch_1):page105_i7" )
				( pin "C7G7.1"
					( objectStatus "a" )
				)
				( pin "C7G7.2"
					( objectStatus "b" )
				)
			)
			( gate "C7G10"
				( objectStatus "@baseboard_fab2_lib.baseboard_fab2(sch_1):page105_i8" )
				( pin "C7G10.1"
					( objectStatus "a" )
				)
				( pin "C7G10.2"
					( objectStatus "b" )
				)
			)
			( gate "C7G12"
				( objectStatus "@baseboard_fab2_lib.baseboard_fab2(sch_1):page105_i12" )
				( pin "C7G12.1"
					( objectStatus "a" )
				)
				( pin "C7G12.2"
					( objectStatus "b" )
				)
			)
			( gate "C7G13"
				( objectStatus "@baseboard_fab2_lib.baseboard_fab2(sch_1):page105_i13" )
				( pin "C7G13.1"
					( objectStatus "a" )
				)
				( pin "C7G13.2"
					( objectStatus "b" )
				)
			)
			( gate "C7G5"
				( objectStatus "@baseboard_fab2_lib.baseboard_fab2(sch_1):page105_i20" )
				( pin "C7G5.1"
					( objectStatus "a" )
				)
				( pin "C7G5.2"
					( objectStatus "b" )
				)
			)
			( gate "C7G9"
				( objectStatus "@baseboard_fab2_lib.baseboard_fab2(sch_1):page105_i21" )
				( pin "C7G9.1"
					( objectStatus "a" )
				)
				( pin "C7G9.2"
					( objectStatus "b" )
				)
			)
			( gate "C7G8"
				( objectStatus "@baseboard_fab2_lib.baseboard_fab2(sch_1):page105_i22" )
				( pin "C7G8.1"
					( objectStatus "a" )
				)
				( pin "C7G8.2"
					( objectStatus "b" )
				)
			)
			( gate "C7G11"
				( objectStatus "@baseboard_fab2_lib.baseboard_fab2(sch_1):page105_i27" )
				( pin "C7G11.1"
					( objectStatus "a" )
				)
				( pin "C7G11.2"
					( objectStatus "b" )
				)
			)
			( gate "C7G14"
				( objectStatus "@baseboard_fab2_lib.baseboard_fab2(sch_1):page105_i28" )
				( pin "C7G14.1"
					( objectStatus "a" )
				)
				( pin "C7G14.2"
					( objectStatus "b" )
				)
			)
			( gate "C7G16"
				( objectStatus "@baseboard_fab2_lib.baseboard_fab2(sch_1):page105_i31" )
				( pin "C7G16.1"
					( objectStatus "a" )
				)
				( pin "C7G16.2"
					( objectStatus "b" )
				)
			)
			( gate "C7G18"
				( objectStatus "@baseboard_fab2_lib.baseboard_fab2(sch_1):page105_i32" )
				( pin "C7G18.1"
					( objectStatus "a" )
				)
				( pin "C7G18.2"
					( objectStatus "b" )
				)
			)
			( gate "C7G20"
				( objectStatus "@baseboard_fab2_lib.baseboard_fab2(sch_1):page105_i34" )
				( pin "C7G20.1"
					( objectStatus "a" )
				)
				( pin "C7G20.2"
					( objectStatus "b" )
				)
			)
			( gate "C7G22"
				( objectStatus "@baseboard_fab2_lib.baseboard_fab2(sch_1):page105_i37" )
				( pin "C7G22.1"
					( objectStatus "a" )
				)
				( pin "C7G22.2"
					( objectStatus "b" )
				)
			)
			( gate "C7G17"
				( objectStatus "@baseboard_fab2_lib.baseboard_fab2(sch_1):page105_i44" )
				( pin "C7G17.1"
					( objectStatus "a" )
				)
				( pin "C7G17.2"
					( objectStatus "b" )
				)
			)
			( gate "C7G15"
				( objectStatus "@baseboard_fab2_lib.baseboard_fab2(sch_1):page105_i45" )
				( pin "C7G15.1"
					( objectStatus "a" )
				)
				( pin "C7G15.2"
					( objectStatus "b" )
				)
			)
			( gate "C7G19"
				( objectStatus "@baseboard_fab2_lib.baseboard_fab2(sch_1):page105_i46" )
				( pin "C7G19.1"
					( objectStatus "a" )
				)
				( pin "C7G19.2"
					( objectStatus "b" )
				)
			)
			( gate "C7G21"
				( objectStatus "@baseboard_fab2_lib.baseboard_fab2(sch_1):page105_i51" )
				( pin "C7G21.1"
					( objectStatus "a" )
				)
				( pin "C7G21.2"
					( objectStatus "b" )
				)
			)
			( gate "C7G23"
				( objectStatus "@baseboard_fab2_lib.baseboard_fab2(sch_1):page105_i52" )
				( pin "C7G23.1"
					( objectStatus "a" )
				)
				( pin "C7G23.2"
					( objectStatus "b" )
				)
			)
			( gate "C7G26"
				( objectStatus "@baseboard_fab2_lib.baseboard_fab2(sch_1):page105_i55" )
				( pin "C7G26.1"
					( objectStatus "a" )
				)
				( pin "C7G26.2"
					( objectStatus "b" )
				)
			)
			( gate "C8G4"
				( objectStatus "@baseboard_fab2_lib.baseboard_fab2(sch_1):page105_i56" )
				( pin "C8G4.1"
					( objectStatus "a" )
				)
				( pin "C8G4.2"
					( objectStatus "b" )
				)
			)
			( gate "C8G2"
				( objectStatus "@baseboard_fab2_lib.baseboard_fab2(sch_1):page105_i58" )
				( pin "C8G2.1"
					( objectStatus "a" )
				)
				( pin "C8G2.2"
					( objectStatus "b" )
				)
			)
			( gate "C8G6"
				( objectStatus "@baseboard_fab2_lib.baseboard_fab2(sch_1):page105_i61" )
				( pin "C8G6.1"
					( objectStatus "a" )
				)
				( pin "C8G6.2"
					( objectStatus "b" )
				)
			)
			( gate "C8G7"
				( objectStatus "@baseboard_fab2_lib.baseboard_fab2(sch_1):page105_i62" )
				( pin "C8G7.1"
					( objectStatus "a" )
				)
				( pin "C8G7.2"
					( objectStatus "b" )
				)
			)
			( gate "C7G25"
				( objectStatus "@baseboard_fab2_lib.baseboard_fab2(sch_1):page105_i69" )
				( pin "C7G25.1"
					( objectStatus "a" )
				)
				( pin "C7G25.2"
					( objectStatus "b" )
				)
			)
			( gate "C8G1"
				( objectStatus "@baseboard_fab2_lib.baseboard_fab2(sch_1):page105_i70" )
				( pin "C8G1.1"
					( objectStatus "a" )
				)
				( pin "C8G1.2"
					( objectStatus "b" )
				)
			)
			( gate "C8G3"
				( objectStatus "@baseboard_fab2_lib.baseboard_fab2(sch_1):page105_i71" )
				( pin "C8G3.1"
					( objectStatus "a" )
				)
				( pin "C8G3.2"
					( objectStatus "b" )
				)
			)
			( gate "C8G5"
				( objectStatus "@baseboard_fab2_lib.baseboard_fab2(sch_1):page105_i75" )
				( pin "C8G5.1"
					( objectStatus "a" )
				)
				( pin "C8G5.2"
					( objectStatus "b" )
				)
			)
			( gate "C8G8"
				( objectStatus "@baseboard_fab2_lib.baseboard_fab2(sch_1):page105_i76" )
				( pin "C8G8.1"
					( objectStatus "a" )
				)
				( pin "C8G8.2"
					( objectStatus "b" )
				)
			)
			( gate "C8G9"
				( objectStatus "@baseboard_fab2_lib.baseboard_fab2(sch_1):page105_i93" )
				( pin "C8G9.1"
					( objectStatus "a" )
				)
				( pin "C8G9.2"
					( objectStatus "b" )
				)
			)
			( gate "C8G10"
				( objectStatus "@baseboard_fab2_lib.baseboard_fab2(sch_1):page105_i96" )
				( pin "C8G10.1"
					( objectStatus "a" )
				)
				( pin "C8G10.2"
					( objectStatus "b" )
				)
			)
			( gate "C6B18"
				( objectStatus "@baseboard_fab2_lib.baseboard_fab2(sch_1):page105_i153" )
				( pin "C6B18.1"
					( objectStatus "a" )
				)
				( pin "C6B18.2"
					( objectStatus "b" )
				)
			)
			( gate "C6B19"
				( objectStatus "@baseboard_fab2_lib.baseboard_fab2(sch_1):page105_i160" )
				( pin "C6B19.1"
					( objectStatus "a" )
				)
				( pin "C6B19.2"
					( objectStatus "b" )
				)
			)
			( gate "C6B15"
				( objectStatus "@baseboard_fab2_lib.baseboard_fab2(sch_1):page105_i163" )
				( pin "C6B15.1"
					( objectStatus "a" )
				)
				( pin "C6B15.2"
					( objectStatus "b" )
				)
			)
			( gate "C6B11"
				( objectStatus "@baseboard_fab2_lib.baseboard_fab2(sch_1):page105_i166" )
				( pin "C6B11.1"
					( objectStatus "a" )
				)
				( pin "C6B11.2"
					( objectStatus "b" )
				)
			)
			( gate "C6B6"
				( objectStatus "@baseboard_fab2_lib.baseboard_fab2(sch_1):page105_i169" )
				( pin "C6B6.1"
					( objectStatus "a" )
				)
				( pin "C6B6.2"
					( objectStatus "b" )
				)
			)
			( gate "C6B20"
				( objectStatus "@baseboard_fab2_lib.baseboard_fab2(sch_1):page105_i173" )
				( pin "C6B20.1"
					( objectStatus "a" )
				)
				( pin "C6B20.2"
					( objectStatus "b" )
				)
			)
			( gate "C6B17"
				( objectStatus "@baseboard_fab2_lib.baseboard_fab2(sch_1):page105_i175" )
				( pin "C6B17.1"
					( objectStatus "a" )
				)
				( pin "C6B17.2"
					( objectStatus "b" )
				)
			)
			( gate "C6B16"
				( objectStatus "@baseboard_fab2_lib.baseboard_fab2(sch_1):page105_i180" )
				( pin "C6B16.1"
					( objectStatus "a" )
				)
				( pin "C6B16.2"
					( objectStatus "b" )
				)
			)
			( gate "C6B14"
				( objectStatus "@baseboard_fab2_lib.baseboard_fab2(sch_1):page105_i181" )
				( pin "C6B14.1"
					( objectStatus "a" )
				)
				( pin "C6B14.2"
					( objectStatus "b" )
				)
			)
			( gate "C6B9"
				( objectStatus "@baseboard_fab2_lib.baseboard_fab2(sch_1):page105_i185" )
				( pin "C6B9.1"
					( objectStatus "a" )
				)
				( pin "C6B9.2"
					( objectStatus "b" )
				)
			)
			( gate "C6B12"
				( objectStatus "@baseboard_fab2_lib.baseboard_fab2(sch_1):page105_i187" )
				( pin "C6B12.1"
					( objectStatus "a" )
				)
				( pin "C6B12.2"
					( objectStatus "b" )
				)
			)
			( gate "C6B13"
				( objectStatus "@baseboard_fab2_lib.baseboard_fab2(sch_1):page105_i189" )
				( pin "C6B13.1"
					( objectStatus "a" )
				)
				( pin "C6B13.2"
					( objectStatus "b" )
				)
			)
			( gate "C6B10"
				( objectStatus "@baseboard_fab2_lib.baseboard_fab2(sch_1):page105_i193" )
				( pin "C6B10.1"
					( objectStatus "a" )
				)
				( pin "C6B10.2"
					( objectStatus "b" )
				)
			)
			( gate "C6B4"
				( objectStatus "@baseboard_fab2_lib.baseboard_fab2(sch_1):page105_i196" )
				( pin "C6B4.1"
					( objectStatus "a" )
				)
				( pin "C6B4.2"
					( objectStatus "b" )
				)
			)
			( gate "C6B8"
				( objectStatus "@baseboard_fab2_lib.baseboard_fab2(sch_1):page105_i198" )
				( pin "C6B8.1"
					( objectStatus "a" )
				)
				( pin "C6B8.2"
					( objectStatus "b" )
				)
			)
			( gate "C6B5"
				( objectStatus "@baseboard_fab2_lib.baseboard_fab2(sch_1):page105_i201" )
				( pin "C6B5.1"
					( objectStatus "a" )
				)
				( pin "C6B5.2"
					( objectStatus "b" )
				)
			)
			( gate "C3M25"
				( objectStatus "@baseboard_fab2_lib.baseboard_fab2(sch_1):page105_i205" )
				( pin "C3M25.1"
					( objectStatus "a" )
				)
				( pin "C3M25.2"
					( objectStatus "b" )
				)
			)
			( gate "C3M34"
				( objectStatus "@baseboard_fab2_lib.baseboard_fab2(sch_1):page105_i206" )
				( pin "C3M34.1"
					( objectStatus "a" )
				)
				( pin "C3M34.2"
					( objectStatus "b" )
				)
			)
			( gate "C3M28"
				( objectStatus "@baseboard_fab2_lib.baseboard_fab2(sch_1):page105_i212" )
				( pin "C3M28.1"
					( objectStatus "a" )
				)
				( pin "C3M28.2"
					( objectStatus "b" )
				)
			)
			( gate "C3M33"
				( objectStatus "@baseboard_fab2_lib.baseboard_fab2(sch_1):page105_i217" )
				( pin "C3M33.1"
					( objectStatus "a" )
				)
				( pin "C3M33.2"
					( objectStatus "b" )
				)
			)
			( gate "C3M36"
				( objectStatus "@baseboard_fab2_lib.baseboard_fab2(sch_1):page105_i218" )
				( pin "C3M36.1"
					( objectStatus "a" )
				)
				( pin "C3M36.2"
					( objectStatus "b" )
				)
			)
			( gate "C3M32"
				( objectStatus "@baseboard_fab2_lib.baseboard_fab2(sch_1):page105_i223" )
				( pin "C3M32.1"
					( objectStatus "a" )
				)
				( pin "C3M32.2"
					( objectStatus "b" )
				)
			)
			( gate "C3M35"
				( objectStatus "@baseboard_fab2_lib.baseboard_fab2(sch_1):page105_i225" )
				( pin "C3M35.1"
					( objectStatus "a" )
				)
				( pin "C3M35.2"
					( objectStatus "b" )
				)
			)
			( gate "C3M26"
				( objectStatus "@baseboard_fab2_lib.baseboard_fab2(sch_1):page105_i229" )
				( pin "C3M26.1"
					( objectStatus "a" )
				)
				( pin "C3M26.2"
					( objectStatus "b" )
				)
			)
			( gate "C3M3"
				( objectStatus "@baseboard_fab2_lib.baseboard_fab2(sch_1):page105_i232" )
				( pin "C3M3.1"
					( objectStatus "a" )
				)
				( pin "C3M3.2"
					( objectStatus "b" )
				)
			)
			( gate "C3M11"
				( objectStatus "@baseboard_fab2_lib.baseboard_fab2(sch_1):page105_i234" )
				( pin "C3M11.1"
					( objectStatus "a" )
				)
				( pin "C3M11.2"
					( objectStatus "b" )
				)
			)
			( gate "C3M13"
				( objectStatus "@baseboard_fab2_lib.baseboard_fab2(sch_1):page105_i239" )
				( pin "C3M13.1"
					( objectStatus "a" )
				)
				( pin "C3M13.2"
					( objectStatus "b" )
				)
			)
			( gate "C3M4"
				( objectStatus "@baseboard_fab2_lib.baseboard_fab2(sch_1):page105_i244" )
				( pin "C3M4.1"
					( objectStatus "a" )
				)
				( pin "C3M4.2"
					( objectStatus "b" )
				)
			)
			( gate "C3M12"
				( objectStatus "@baseboard_fab2_lib.baseboard_fab2(sch_1):page105_i246" )
				( pin "C3M12.1"
					( objectStatus "a" )
				)
				( pin "C3M12.2"
					( objectStatus "b" )
				)
			)
			( gate "C3M2"
				( objectStatus "@baseboard_fab2_lib.baseboard_fab2(sch_1):page105_i247" )
				( pin "C3M2.1"
					( objectStatus "a" )
				)
				( pin "C3M2.2"
					( objectStatus "b" )
				)
			)
			( gate "C3M14"
				( objectStatus "@baseboard_fab2_lib.baseboard_fab2(sch_1):page105_i253" )
				( pin "C3M14.1"
					( objectStatus "a" )
				)
				( pin "C3M14.2"
					( objectStatus "b" )
				)
			)
			( gate "C3M1"
				( objectStatus "@baseboard_fab2_lib.baseboard_fab2(sch_1):page105_i255" )
				( pin "C3M1.1"
					( objectStatus "a" )
				)
				( pin "C3M1.2"
					( objectStatus "b" )
				)
			)
			( gate "C1R2"
				( objectStatus "@baseboard_fab2_lib.baseboard_fab2(sch_1):page106_i10" )
				( pin "C1R2.1"
					( objectStatus "a" )
				)
				( pin "C1R2.2"
					( objectStatus "b" )
				)
			)
			( gate "C1R4"
				( objectStatus "@baseboard_fab2_lib.baseboard_fab2(sch_1):page106_i26" )
				( pin "C1R4.1"
					( objectStatus "a" )
				)
				( pin "C1R4.2"
					( objectStatus "b" )
				)
			)
			( gate "C1R1"
				( objectStatus "@baseboard_fab2_lib.baseboard_fab2(sch_1):page106_i29" )
				( pin "C1R1.1"
					( objectStatus "a" )
				)
				( pin "C1R1.2"
					( objectStatus "b" )
				)
			)
			( gate "C1R3"
				( objectStatus "@baseboard_fab2_lib.baseboard_fab2(sch_1):page106_i37" )
				( pin "C1R3.1"
					( objectStatus "a" )
				)
				( pin "C1R3.2"
					( objectStatus "b" )
				)
			)
			( gate "C1R6"
				( objectStatus "@baseboard_fab2_lib.baseboard_fab2(sch_1):page106_i40" )
				( pin "C1R6.1"
					( objectStatus "a" )
				)
				( pin "C1R6.2"
					( objectStatus "b" )
				)
			)
			( gate "C1R8"
				( objectStatus "@baseboard_fab2_lib.baseboard_fab2(sch_1):page106_i55" )
				( pin "C1R8.1"
					( objectStatus "a" )
				)
				( pin "C1R8.2"
					( objectStatus "b" )
				)
			)
			( gate "C1R5"
				( objectStatus "@baseboard_fab2_lib.baseboard_fab2(sch_1):page106_i59" )
				( pin "C1R5.1"
					( objectStatus "a" )
				)
				( pin "C1R5.2"
					( objectStatus "b" )
				)
			)
			( gate "C1R7"
				( objectStatus "@baseboard_fab2_lib.baseboard_fab2(sch_1):page106_i70" )
				( pin "C1R7.1"
					( objectStatus "a" )
				)
				( pin "C1R7.2"
					( objectStatus "b" )
				)
			)
			( gate "C2M14"
				( objectStatus "@baseboard_fab2_lib.baseboard_fab2(sch_1):page106_i76" )
				( pin "C2M14.1"
					( objectStatus "a" )
				)
				( pin "C2M14.2"
					( objectStatus "b" )
				)
			)
			( gate "C1M18"
				( objectStatus "@baseboard_fab2_lib.baseboard_fab2(sch_1):page106_i78" )
				( pin "C1M18.1"
					( objectStatus "a" )
				)
				( pin "C1M18.2"
					( objectStatus "b" )
				)
			)
			( gate "C1M16"
				( objectStatus "@baseboard_fab2_lib.baseboard_fab2(sch_1):page106_i82" )
				( pin "C1M16.1"
					( objectStatus "a" )
				)
				( pin "C1M16.2"
					( objectStatus "b" )
				)
			)
			( gate "C1M14"
				( objectStatus "@baseboard_fab2_lib.baseboard_fab2(sch_1):page106_i85" )
				( pin "C1M14.1"
					( objectStatus "a" )
				)
				( pin "C1M14.2"
					( objectStatus "b" )
				)
			)
			( gate "C2M15"
				( objectStatus "@baseboard_fab2_lib.baseboard_fab2(sch_1):page106_i86" )
				( pin "C2M15.1"
					( objectStatus "a" )
				)
				( pin "C2M15.2"
					( objectStatus "b" )
				)
			)
			( gate "C1M19"
				( objectStatus "@baseboard_fab2_lib.baseboard_fab2(sch_1):page106_i90" )
				( pin "C1M19.1"
					( objectStatus "a" )
				)
				( pin "C1M19.2"
					( objectStatus "b" )
				)
			)
			( gate "C1M17"
				( objectStatus "@baseboard_fab2_lib.baseboard_fab2(sch_1):page106_i92" )
				( pin "C1M17.1"
					( objectStatus "a" )
				)
				( pin "C1M17.2"
					( objectStatus "b" )
				)
			)
			( gate "C1M15"
				( objectStatus "@baseboard_fab2_lib.baseboard_fab2(sch_1):page106_i95" )
				( pin "C1M15.1"
					( objectStatus "a" )
				)
				( pin "C1M15.2"
					( objectStatus "b" )
				)
			)
			( gate "C1M12"
				( objectStatus "@baseboard_fab2_lib.baseboard_fab2(sch_1):page106_i100" )
				( pin "C1M12.1"
					( objectStatus "a" )
				)
				( pin "C1M12.2"
					( objectStatus "b" )
				)
			)
			( gate "C1M10"
				( objectStatus "@baseboard_fab2_lib.baseboard_fab2(sch_1):page106_i102" )
				( pin "C1M10.1"
					( objectStatus "a" )
				)
				( pin "C1M10.2"
					( objectStatus "b" )
				)
			)
			( gate "C1M8"
				( objectStatus "@baseboard_fab2_lib.baseboard_fab2(sch_1):page106_i105" )
				( pin "C1M8.1"
					( objectStatus "a" )
				)
				( pin "C1M8.2"
					( objectStatus "b" )
				)
			)
			( gate "C1M6"
				( objectStatus "@baseboard_fab2_lib.baseboard_fab2(sch_1):page106_i109" )
				( pin "C1M6.1"
					( objectStatus "a" )
				)
				( pin "C1M6.2"
					( objectStatus "b" )
				)
			)
			( gate "C1M13"
				( objectStatus "@baseboard_fab2_lib.baseboard_fab2(sch_1):page106_i111" )
				( pin "C1M13.1"
					( objectStatus "a" )
				)
				( pin "C1M13.2"
					( objectStatus "b" )
				)
			)
			( gate "C1M9"
				( objectStatus "@baseboard_fab2_lib.baseboard_fab2(sch_1):page106_i114" )
				( pin "C1M9.1"
					( objectStatus "a" )
				)
				( pin "C1M9.2"
					( objectStatus "b" )
				)
			)
			( gate "C1M11"
				( objectStatus "@baseboard_fab2_lib.baseboard_fab2(sch_1):page106_i117" )
				( pin "C1M11.1"
					( objectStatus "a" )
				)
				( pin "C1M11.2"
					( objectStatus "b" )
				)
			)
			( gate "C1M7"
				( objectStatus "@baseboard_fab2_lib.baseboard_fab2(sch_1):page106_i122" )
				( pin "C1M7.1"
					( objectStatus "a" )
				)
				( pin "C1M7.2"
					( objectStatus "b" )
				)
			)
			( gate "C2R7"
				( objectStatus "@baseboard_fab2_lib.baseboard_fab2(sch_1):page106_i123" )
				( pin "C2R7.1"
					( objectStatus "a" )
				)
				( pin "C2R7.2"
					( objectStatus "b" )
				)
			)
			( gate "C1R10"
				( objectStatus "@baseboard_fab2_lib.baseboard_fab2(sch_1):page106_i128" )
				( pin "C1R10.1"
					( objectStatus "a" )
				)
				( pin "C1R10.2"
					( objectStatus "b" )
				)
			)
			( gate "C1R12"
				( objectStatus "@baseboard_fab2_lib.baseboard_fab2(sch_1):page106_i130" )
				( pin "C1R12.1"
					( objectStatus "a" )
				)
				( pin "C1R12.2"
					( objectStatus "b" )
				)
			)
			( gate "C1R9"
				( objectStatus "@baseboard_fab2_lib.baseboard_fab2(sch_1):page106_i134" )
				( pin "C1R9.1"
					( objectStatus "a" )
				)
				( pin "C1R9.2"
					( objectStatus "b" )
				)
			)
			( gate "C1R11"
				( objectStatus "@baseboard_fab2_lib.baseboard_fab2(sch_1):page106_i137" )
				( pin "C1R11.1"
					( objectStatus "a" )
				)
				( pin "C1R11.2"
					( objectStatus "b" )
				)
			)
			( gate "C2R8"
				( objectStatus "@baseboard_fab2_lib.baseboard_fab2(sch_1):page106_i141" )
				( pin "C2R8.1"
					( objectStatus "a" )
				)
				( pin "C2R8.2"
					( objectStatus "b" )
				)
			)
			( gate "C2R10"
				( objectStatus "@baseboard_fab2_lib.baseboard_fab2(sch_1):page106_i142" )
				( pin "C2R10.1"
					( objectStatus "a" )
				)
				( pin "C2R10.2"
					( objectStatus "b" )
				)
			)
			( gate "C2R9"
				( objectStatus "@baseboard_fab2_lib.baseboard_fab2(sch_1):page106_i147" )
				( pin "C2R9.1"
					( objectStatus "a" )
				)
				( pin "C2R9.2"
					( objectStatus "b" )
				)
			)
			( gate "C3P13"
				( objectStatus "@baseboard_fab2_lib.baseboard_fab2(sch_1):page107_i207" )
				( pin "C3P13.1"
					( objectStatus "a" )
				)
				( pin "C3P13.2"
					( objectStatus "b" )
				)
			)
			( gate "C3P17"
				( objectStatus "@baseboard_fab2_lib.baseboard_fab2(sch_1):page107_i208" )
				( pin "C3P17.1"
					( objectStatus "a" )
				)
				( pin "C3P17.2"
					( objectStatus "b" )
				)
			)
			( gate "C3P11"
				( objectStatus "@baseboard_fab2_lib.baseboard_fab2(sch_1):page107_i212" )
				( pin "C3P11.1"
					( objectStatus "a" )
				)
				( pin "C3P11.2"
					( objectStatus "b" )
				)
			)
			( gate "C3P20"
				( objectStatus "@baseboard_fab2_lib.baseboard_fab2(sch_1):page107_i215" )
				( pin "C3P20.1"
					( objectStatus "a" )
				)
				( pin "C3P20.2"
					( objectStatus "b" )
				)
			)
			( gate "C3P25"
				( objectStatus "@baseboard_fab2_lib.baseboard_fab2(sch_1):page107_i216" )
				( pin "C3P25.1"
					( objectStatus "a" )
				)
				( pin "C3P25.2"
					( objectStatus "b" )
				)
			)
			( gate "C3P18"
				( objectStatus "@baseboard_fab2_lib.baseboard_fab2(sch_1):page107_i219" )
				( pin "C3P18.1"
					( objectStatus "a" )
				)
				( pin "C3P18.2"
					( objectStatus "b" )
				)
			)
			( gate "C3P27"
				( objectStatus "@baseboard_fab2_lib.baseboard_fab2(sch_1):page107_i223" )
				( pin "C3P27.1"
					( objectStatus "a" )
				)
				( pin "C3P27.2"
					( objectStatus "b" )
				)
			)
			( gate "C3P15"
				( objectStatus "@baseboard_fab2_lib.baseboard_fab2(sch_1):page107_i226" )
				( pin "C3P15.1"
					( objectStatus "a" )
				)
				( pin "C3P15.2"
					( objectStatus "b" )
				)
			)
			( gate "C3P23"
				( objectStatus "@baseboard_fab2_lib.baseboard_fab2(sch_1):page107_i229" )
				( pin "C3P23.1"
					( objectStatus "a" )
				)
				( pin "C3P23.2"
					( objectStatus "b" )
				)
			)
			( gate "C3P28"
				( objectStatus "@baseboard_fab2_lib.baseboard_fab2(sch_1):page107_i232" )
				( pin "C3P28.1"
					( objectStatus "a" )
				)
				( pin "C3P28.2"
					( objectStatus "b" )
				)
			)
			( gate "C3P32"
				( objectStatus "@baseboard_fab2_lib.baseboard_fab2(sch_1):page107_i234" )
				( pin "C3P32.1"
					( objectStatus "a" )
				)
				( pin "C3P32.2"
					( objectStatus "b" )
				)
			)
			( gate "C3P37"
				( objectStatus "@baseboard_fab2_lib.baseboard_fab2(sch_1):page107_i235" )
				( pin "C3P37.1"
					( objectStatus "a" )
				)
				( pin "C3P37.2"
					( objectStatus "b" )
				)
			)
			( gate "C3P35"
				( objectStatus "@baseboard_fab2_lib.baseboard_fab2(sch_1):page107_i240" )
				( pin "C3P35.1"
					( objectStatus "a" )
				)
				( pin "C3P35.2"
					( objectStatus "b" )
				)
			)
			( gate "C3P40"
				( objectStatus "@baseboard_fab2_lib.baseboard_fab2(sch_1):page107_i241" )
				( pin "C3P40.1"
					( objectStatus "a" )
				)
				( pin "C3P40.2"
					( objectStatus "b" )
				)
			)
			( gate "C3P30"
				( objectStatus "@baseboard_fab2_lib.baseboard_fab2(sch_1):page107_i245" )
				( pin "C3P30.1"
					( objectStatus "a" )
				)
				( pin "C3P30.2"
					( objectStatus "b" )
				)
			)
			( gate "C3P39"
				( objectStatus "@baseboard_fab2_lib.baseboard_fab2(sch_1):page107_i248" )
				( pin "C3P39.1"
					( objectStatus "a" )
				)
				( pin "C3P39.2"
					( objectStatus "b" )
				)
			)
			( gate "C2U4"
				( objectStatus "@baseboard_fab2_lib.baseboard_fab2(sch_1):page107_i257" )
				( pin "C2U4.1"
					( objectStatus "a" )
				)
				( pin "C2U4.2"
					( objectStatus "b" )
				)
			)
			( gate "C2U6"
				( objectStatus "@baseboard_fab2_lib.baseboard_fab2(sch_1):page107_i260" )
				( pin "C2U6.1"
					( objectStatus "a" )
				)
				( pin "C2U6.2"
					( objectStatus "b" )
				)
			)
			( gate "C2U8"
				( objectStatus "@baseboard_fab2_lib.baseboard_fab2(sch_1):page107_i264" )
				( pin "C2U8.1"
					( objectStatus "a" )
				)
				( pin "C2U8.2"
					( objectStatus "b" )
				)
			)
			( gate "C2U12"
				( objectStatus "@baseboard_fab2_lib.baseboard_fab2(sch_1):page107_i265" )
				( pin "C2U12.1"
					( objectStatus "a" )
				)
				( pin "C2U12.2"
					( objectStatus "b" )
				)
			)
			( gate "C2U10"
				( objectStatus "@baseboard_fab2_lib.baseboard_fab2(sch_1):page107_i267" )
				( pin "C2U10.1"
					( objectStatus "a" )
				)
				( pin "C2U10.2"
					( objectStatus "b" )
				)
			)
			( gate "C2U3"
				( objectStatus "@baseboard_fab2_lib.baseboard_fab2(sch_1):page107_i272" )
				( pin "C2U3.1"
					( objectStatus "a" )
				)
				( pin "C2U3.2"
					( objectStatus "b" )
				)
			)
			( gate "C2U5"
				( objectStatus "@baseboard_fab2_lib.baseboard_fab2(sch_1):page107_i274" )
				( pin "C2U5.1"
					( objectStatus "a" )
				)
				( pin "C2U5.2"
					( objectStatus "b" )
				)
			)
			( gate "C2U7"
				( objectStatus "@baseboard_fab2_lib.baseboard_fab2(sch_1):page107_i277" )
				( pin "C2U7.1"
					( objectStatus "a" )
				)
				( pin "C2U7.2"
					( objectStatus "b" )
				)
			)
			( gate "C2U11"
				( objectStatus "@baseboard_fab2_lib.baseboard_fab2(sch_1):page107_i278" )
				( pin "C2U11.1"
					( objectStatus "a" )
				)
				( pin "C2U11.2"
					( objectStatus "b" )
				)
			)
			( gate "C2U9"
				( objectStatus "@baseboard_fab2_lib.baseboard_fab2(sch_1):page107_i279" )
				( pin "C2U9.1"
					( objectStatus "a" )
				)
				( pin "C2U9.2"
					( objectStatus "b" )
				)
			)
			( gate "C2U16"
				( objectStatus "@baseboard_fab2_lib.baseboard_fab2(sch_1):page107_i286" )
				( pin "C2U16.1"
					( objectStatus "a" )
				)
				( pin "C2U16.2"
					( objectStatus "b" )
				)
			)
			( gate "C2U14"
				( objectStatus "@baseboard_fab2_lib.baseboard_fab2(sch_1):page107_i287" )
				( pin "C2U14.1"
					( objectStatus "a" )
				)
				( pin "C2U14.2"
					( objectStatus "b" )
				)
			)
			( gate "C2U18"
				( objectStatus "@baseboard_fab2_lib.baseboard_fab2(sch_1):page107_i294" )
				( pin "C2U18.1"
					( objectStatus "a" )
				)
				( pin "C2U18.2"
					( objectStatus "b" )
				)
			)
			( gate "C2U15"
				( objectStatus "@baseboard_fab2_lib.baseboard_fab2(sch_1):page107_i296" )
				( pin "C2U15.1"
					( objectStatus "a" )
				)
				( pin "C2U15.2"
					( objectStatus "b" )
				)
			)
			( gate "C2U13"
				( objectStatus "@baseboard_fab2_lib.baseboard_fab2(sch_1):page107_i297" )
				( pin "C2U13.1"
					( objectStatus "a" )
				)
				( pin "C2U13.2"
					( objectStatus "b" )
				)
			)
			( gate "C2U17"
				( objectStatus "@baseboard_fab2_lib.baseboard_fab2(sch_1):page107_i300" )
				( pin "C2U17.1"
					( objectStatus "a" )
				)
				( pin "C2U17.2"
					( objectStatus "b" )
				)
			)
			( gate "C3P12"
				( objectStatus "@baseboard_fab2_lib.baseboard_fab2(sch_1):page107_i415" )
				( pin "C3P12.1"
					( objectStatus "a" )
				)
				( pin "C3P12.2"
					( objectStatus "b" )
				)
			)
			( gate "C3P10"
				( objectStatus "@baseboard_fab2_lib.baseboard_fab2(sch_1):page107_i417" )
				( pin "C3P10.1"
					( objectStatus "a" )
				)
				( pin "C3P10.2"
					( objectStatus "b" )
				)
			)
			( gate "C3P16"
				( objectStatus "@baseboard_fab2_lib.baseboard_fab2(sch_1):page107_i422" )
				( pin "C3P16.1"
					( objectStatus "a" )
				)
				( pin "C3P16.2"
					( objectStatus "b" )
				)
			)
			( gate "C3P21"
				( objectStatus "@baseboard_fab2_lib.baseboard_fab2(sch_1):page107_i423" )
				( pin "C3P21.1"
					( objectStatus "a" )
				)
				( pin "C3P21.2"
					( objectStatus "b" )
				)
			)
			( gate "C3P24"
				( objectStatus "@baseboard_fab2_lib.baseboard_fab2(sch_1):page107_i424" )
				( pin "C3P24.1"
					( objectStatus "a" )
				)
				( pin "C3P24.2"
					( objectStatus "b" )
				)
			)
			( gate "C3P19"
				( objectStatus "@baseboard_fab2_lib.baseboard_fab2(sch_1):page107_i427" )
				( pin "C3P19.1"
					( objectStatus "a" )
				)
				( pin "C3P19.2"
					( objectStatus "b" )
				)
			)
			( gate "C3P14"
				( objectStatus "@baseboard_fab2_lib.baseboard_fab2(sch_1):page107_i431" )
				( pin "C3P14.1"
					( objectStatus "a" )
				)
				( pin "C3P14.2"
					( objectStatus "b" )
				)
			)
			( gate "C3P22"
				( objectStatus "@baseboard_fab2_lib.baseboard_fab2(sch_1):page107_i435" )
				( pin "C3P22.1"
					( objectStatus "a" )
				)
				( pin "C3P22.2"
					( objectStatus "b" )
				)
			)
			( gate "C3P29"
				( objectStatus "@baseboard_fab2_lib.baseboard_fab2(sch_1):page107_i437" )
				( pin "C3P29.1"
					( objectStatus "a" )
				)
				( pin "C3P29.2"
					( objectStatus "b" )
				)
			)
			( gate "C3P36"
				( objectStatus "@baseboard_fab2_lib.baseboard_fab2(sch_1):page107_i438" )
				( pin "C3P36.1"
					( objectStatus "a" )
				)
				( pin "C3P36.2"
					( objectStatus "b" )
				)
			)
			( gate "C3P33"
				( objectStatus "@baseboard_fab2_lib.baseboard_fab2(sch_1):page107_i439" )
				( pin "C3P33.1"
					( objectStatus "a" )
				)
				( pin "C3P33.2"
					( objectStatus "b" )
				)
			)
			( gate "C3P26"
				( objectStatus "@baseboard_fab2_lib.baseboard_fab2(sch_1):page107_i444" )
				( pin "C3P26.1"
					( objectStatus "a" )
				)
				( pin "C3P26.2"
					( objectStatus "b" )
				)
			)
			( gate "C3P34"
				( objectStatus "@baseboard_fab2_lib.baseboard_fab2(sch_1):page107_i447" )
				( pin "C3P34.1"
					( objectStatus "a" )
				)
				( pin "C3P34.2"
					( objectStatus "b" )
				)
			)
			( gate "C3P41"
				( objectStatus "@baseboard_fab2_lib.baseboard_fab2(sch_1):page107_i448" )
				( pin "C3P41.1"
					( objectStatus "a" )
				)
				( pin "C3P41.2"
					( objectStatus "b" )
				)
			)
			( gate "C3P31"
				( objectStatus "@baseboard_fab2_lib.baseboard_fab2(sch_1):page107_i452" )
				( pin "C3P31.1"
					( objectStatus "a" )
				)
				( pin "C3P31.2"
					( objectStatus "b" )
				)
			)
			( gate "C3P38"
				( objectStatus "@baseboard_fab2_lib.baseboard_fab2(sch_1):page107_i455" )
				( pin "C3P38.1"
					( objectStatus "a" )
				)
				( pin "C3P38.2"
					( objectStatus "b" )
				)
			)
			( gate "R2U29"
				( objectStatus "@baseboard_fab2_lib.baseboard_fab2(sch_1):page107_i458" )
				( pin "R2U29.1"
					( objectStatus "a" )
				)
				( pin "R2U29.2"
					( objectStatus "b" )
				)
			)
			( gate "R2U27"
				( objectStatus "@baseboard_fab2_lib.baseboard_fab2(sch_1):page107_i459" )
				( pin "R2U27.1"
					( objectStatus "a" )
				)
				( pin "R2U27.2"
					( objectStatus "b" )
				)
			)
			( gate "R2U25"
				( objectStatus "@baseboard_fab2_lib.baseboard_fab2(sch_1):page107_i460" )
				( pin "R2U25.1"
					( objectStatus "a" )
				)
				( pin "R2U25.2"
					( objectStatus "b" )
				)
			)
			( gate "R2U23"
				( objectStatus "@baseboard_fab2_lib.baseboard_fab2(sch_1):page107_i461" )
				( pin "R2U23.1"
					( objectStatus "a" )
				)
				( pin "R2U23.2"
					( objectStatus "b" )
				)
			)
			( gate "R2U21"
				( objectStatus "@baseboard_fab2_lib.baseboard_fab2(sch_1):page107_i462" )
				( pin "R2U21.1"
					( objectStatus "a" )
				)
				( pin "R2U21.2"
					( objectStatus "b" )
				)
			)
			( gate "R2U19"
				( objectStatus "@baseboard_fab2_lib.baseboard_fab2(sch_1):page107_i463" )
				( pin "R2U19.1"
					( objectStatus "a" )
				)
				( pin "R2U19.2"
					( objectStatus "b" )
				)
			)
			( gate "R2U17"
				( objectStatus "@baseboard_fab2_lib.baseboard_fab2(sch_1):page107_i464" )
				( pin "R2U17.1"
					( objectStatus "a" )
				)
				( pin "R2U17.2"
					( objectStatus "b" )
				)
			)
			( gate "R2U15"
				( objectStatus "@baseboard_fab2_lib.baseboard_fab2(sch_1):page107_i465" )
				( pin "R2U15.1"
					( objectStatus "a" )
				)
				( pin "R2U15.2"
					( objectStatus "b" )
				)
			)
			( gate "R2U14"
				( objectStatus "@baseboard_fab2_lib.baseboard_fab2(sch_1):page107_i466" )
				( pin "R2U14.1"
					( objectStatus "a" )
				)
				( pin "R2U14.2"
					( objectStatus "b" )
				)
			)
			( gate "R2U16"
				( objectStatus "@baseboard_fab2_lib.baseboard_fab2(sch_1):page107_i467" )
				( pin "R2U16.1"
					( objectStatus "a" )
				)
				( pin "R2U16.2"
					( objectStatus "b" )
				)
			)
			( gate "R2U18"
				( objectStatus "@baseboard_fab2_lib.baseboard_fab2(sch_1):page107_i468" )
				( pin "R2U18.1"
					( objectStatus "a" )
				)
				( pin "R2U18.2"
					( objectStatus "b" )
				)
			)
			( gate "R2U20"
				( objectStatus "@baseboard_fab2_lib.baseboard_fab2(sch_1):page107_i469" )
				( pin "R2U20.1"
					( objectStatus "a" )
				)
				( pin "R2U20.2"
					( objectStatus "b" )
				)
			)
			( gate "R2U22"
				( objectStatus "@baseboard_fab2_lib.baseboard_fab2(sch_1):page107_i470" )
				( pin "R2U22.1"
					( objectStatus "a" )
				)
				( pin "R2U22.2"
					( objectStatus "b" )
				)
			)
			( gate "R2U24"
				( objectStatus "@baseboard_fab2_lib.baseboard_fab2(sch_1):page107_i471" )
				( pin "R2U24.1"
					( objectStatus "a" )
				)
				( pin "R2U24.2"
					( objectStatus "b" )
				)
			)
			( gate "R2U26"
				( objectStatus "@baseboard_fab2_lib.baseboard_fab2(sch_1):page107_i472" )
				( pin "R2U26.1"
					( objectStatus "a" )
				)
				( pin "R2U26.2"
					( objectStatus "b" )
				)
			)
			( gate "R2U28"
				( objectStatus "@baseboard_fab2_lib.baseboard_fab2(sch_1):page107_i473" )
				( pin "R2U28.1"
					( objectStatus "a" )
				)
				( pin "R2U28.2"
					( objectStatus "b" )
				)
			)
			( gate "C2U20"
				( objectStatus "@baseboard_fab2_lib.baseboard_fab2(sch_1):page108_i1" )
				( pin "C2U20.1"
					( objectStatus "a" )
				)
				( pin "C2U20.2"
					( objectStatus "b" )
				)
			)
			( gate "C2U24"
				( objectStatus "@baseboard_fab2_lib.baseboard_fab2(sch_1):page108_i2" )
				( pin "C2U24.1"
					( objectStatus "a" )
				)
				( pin "C2U24.2"
					( objectStatus "b" )
				)
			)
			( gate "C2U21"
				( objectStatus "@baseboard_fab2_lib.baseboard_fab2(sch_1):page108_i5" )
				( pin "C2U21.1"
					( objectStatus "a" )
				)
				( pin "C2U21.2"
					( objectStatus "b" )
				)
			)
			( gate "C2U25"
				( objectStatus "@baseboard_fab2_lib.baseboard_fab2(sch_1):page108_i7" )
				( pin "C2U25.1"
					( objectStatus "a" )
				)
				( pin "C2U25.2"
					( objectStatus "b" )
				)
			)
			( gate "R2U37"
				( objectStatus "@baseboard_fab2_lib.baseboard_fab2(sch_1):page108_i173" )
				( pin "R2U37.1"
					( objectStatus "a" )
				)
				( pin "R2U37.2"
					( objectStatus "b" )
				)
			)
			( gate "J8G1"
				( objectStatus "@baseboard_fab2_lib.baseboard_fab2(sch_1):page108_i258" )
				( pin "J8G1.1"
					( objectStatus "io1" )
				)
				( pin "J8G1.2"
					( objectStatus "io2" )
				)
				( pin "J8G1.3"
					( objectStatus "io3" )
				)
				( pin "J8G1.4"
					( objectStatus "io4" )
				)
				( pin "J8G1.5"
					( objectStatus "io5" )
				)
				( pin "J8G1.6"
					( objectStatus "io6" )
				)
				( pin "J8G1.7"
					( objectStatus "io7" )
				)
				( pin "J8G1.8"
					( objectStatus "io8" )
				)
				( pin "J8G1.9"
					( objectStatus "io9" )
				)
				( pin "J8G1.10"
					( objectStatus "io10" )
				)
				( pin "J8G1.11"
					( objectStatus "io11" )
				)
				( pin "J8G1.12"
					( objectStatus "io12" )
				)
				( pin "J8G1.13"
					( objectStatus "io13" )
				)
				( pin "J8G1.14"
					( objectStatus "io14" )
				)
				( pin "J8G1.15"
					( objectStatus "io15" )
				)
				( pin "J8G1.16"
					( objectStatus "io16" )
				)
				( pin "J8G1.17"
					( objectStatus "io17" )
				)
				( pin "J8G1.18"
					( objectStatus "io18" )
				)
				( pin "J8G1.19"
					( objectStatus "io19" )
				)
				( pin "J8G1.20"
					( objectStatus "io20" )
				)
				( pin "J8G1.21"
					( objectStatus "io21" )
				)
				( pin "J8G1.22"
					( objectStatus "io22" )
				)
				( pin "J8G1.23"
					( objectStatus "io23" )
				)
				( pin "J8G1.24"
					( objectStatus "io24" )
				)
				( pin "J8G1.25"
					( objectStatus "io25" )
				)
				( pin "J8G1.26"
					( objectStatus "io26" )
				)
				( pin "J8G1.27"
					( objectStatus "io27" )
				)
				( pin "J8G1.28"
					( objectStatus "io28" )
				)
				( pin "J8G1.29"
					( objectStatus "io29" )
				)
				( pin "J8G1.30"
					( objectStatus "io30" )
				)
				( pin "J8G1.31"
					( objectStatus "io31" )
				)
				( pin "J8G1.32"
					( objectStatus "io32" )
				)
				( pin "J8G1.33"
					( objectStatus "io33" )
				)
				( pin "J8G1.34"
					( objectStatus "io34" )
				)
				( pin "J8G1.35"
					( objectStatus "io35" )
				)
				( pin "J8G1.36"
					( objectStatus "io36" )
				)
				( pin "J8G1.37"
					( objectStatus "io37" )
				)
				( pin "J8G1.38"
					( objectStatus "io38" )
				)
				( pin "J8G1.39"
					( objectStatus "io39" )
				)
				( pin "J8G1.40"
					( objectStatus "io40" )
				)
				( pin "J8G1.41"
					( objectStatus "io41" )
				)
				( pin "J8G1.42"
					( objectStatus "io42" )
				)
				( pin "J8G1.43"
					( objectStatus "io43" )
				)
				( pin "J8G1.44"
					( objectStatus "io44" )
				)
				( pin "J8G1.45"
					( objectStatus "io45" )
				)
				( pin "J8G1.46"
					( objectStatus "io46" )
				)
				( pin "J8G1.47"
					( objectStatus "io47" )
				)
				( pin "J8G1.48"
					( objectStatus "io48" )
				)
				( pin "J8G1.49"
					( objectStatus "io49" )
				)
				( pin "J8G1.50"
					( objectStatus "io50" )
				)
				( pin "J8G1.51"
					( objectStatus "io51" )
				)
				( pin "J8G1.52"
					( objectStatus "io52" )
				)
				( pin "J8G1.53"
					( objectStatus "io53" )
				)
				( pin "J8G1.54"
					( objectStatus "io54" )
				)
				( pin "J8G1.55"
					( objectStatus "io55" )
				)
				( pin "J8G1.56"
					( objectStatus "io56" )
				)
				( pin "J8G1.57"
					( objectStatus "io57" )
				)
				( pin "J8G1.58"
					( objectStatus "io58" )
				)
				( pin "J8G1.59"
					( objectStatus "io59" )
				)
				( pin "J8G1.60"
					( objectStatus "io60" )
				)
				( pin "J8G1.61"
					( objectStatus "io61" )
				)
				( pin "J8G1.62"
					( objectStatus "io62" )
				)
				( pin "J8G1.63"
					( objectStatus "io63" )
				)
				( pin "J8G1.64"
					( objectStatus "io64" )
				)
				( pin "J8G1.65"
					( objectStatus "io65" )
				)
				( pin "J8G1.66"
					( objectStatus "io66" )
				)
				( pin "J8G1.67"
					( objectStatus "io67" )
				)
				( pin "J8G1.68"
					( objectStatus "io68" )
				)
				( pin "J8G1.69"
					( objectStatus "io69" )
				)
				( pin "J8G1.70"
					( objectStatus "io70" )
				)
				( pin "J8G1.71"
					( objectStatus "io71" )
				)
				( pin "J8G1.72"
					( objectStatus "io72" )
				)
				( pin "J8G1.73"
					( objectStatus "io73" )
				)
				( pin "J8G1.74"
					( objectStatus "io74" )
				)
				( pin "J8G1.75"
					( objectStatus "io75" )
				)
				( pin "J8G1.76"
					( objectStatus "io76" )
				)
				( pin "J8G1.77"
					( objectStatus "io77" )
				)
				( pin "J8G1.78"
					( objectStatus "io78" )
				)
				( pin "J8G1.79"
					( objectStatus "io79" )
				)
				( pin "J8G1.80"
					( objectStatus "io80" )
				)
				( pin "J8G1.81"
					( objectStatus "io81" )
				)
				( pin "J8G1.82"
					( objectStatus "io82" )
				)
				( pin "J8G1.83"
					( objectStatus "io83" )
				)
				( pin "J8G1.84"
					( objectStatus "io84" )
				)
				( pin "J8G1.85"
					( objectStatus "io85" )
				)
				( pin "J8G1.86"
					( objectStatus "io86" )
				)
				( pin "J8G1.87"
					( objectStatus "io87" )
				)
				( pin "J8G1.88"
					( objectStatus "io88" )
				)
				( pin "J8G1.89"
					( objectStatus "io89" )
				)
				( pin "J8G1.90"
					( objectStatus "io90" )
				)
				( pin "J8G1.91"
					( objectStatus "io91" )
				)
				( pin "J8G1.92"
					( objectStatus "io92" )
				)
				( pin "J8G1.93"
					( objectStatus "io93" )
				)
				( pin "J8G1.94"
					( objectStatus "io94" )
				)
				( pin "J8G1.95"
					( objectStatus "io95" )
				)
				( pin "J8G1.96"
					( objectStatus "io96" )
				)
				( pin "J8G1.97"
					( objectStatus "io97" )
				)
				( pin "J8G1.98"
					( objectStatus "io98" )
				)
				( pin "J8G1.99"
					( objectStatus "io99" )
				)
				( pin "J8G1.100"
					( objectStatus "io100" )
				)
				( pin "J8G1.MH1"
					( objectStatus "mh1" )
				)
				( pin "J8G1.MH2"
					( objectStatus "mh2" )
				)
			)
			( gate "C2U23"
				( objectStatus "@baseboard_fab2_lib.baseboard_fab2(sch_1):page108_i315" )
				( pin "C2U23.1"
					( objectStatus "a" )
				)
				( pin "C2U23.2"
					( objectStatus "b" )
				)
			)
			( gate "C2U22"
				( objectStatus "@baseboard_fab2_lib.baseboard_fab2(sch_1):page108_i318" )
				( pin "C2U22.1"
					( objectStatus "a" )
				)
				( pin "C2U22.2"
					( objectStatus "b" )
				)
			)
			( gate "R2U35"
				( objectStatus "@baseboard_fab2_lib.baseboard_fab2(sch_1):page108_i320" )
				( pin "R2U35.1"
					( objectStatus "a" )
				)
				( pin "R2U35.2"
					( objectStatus "b" )
				)
			)
			( gate "R2U31"
				( objectStatus "@baseboard_fab2_lib.baseboard_fab2(sch_1):page108_i330" )
				( pin "R2U31.1"
					( objectStatus "a" )
				)
				( pin "R2U31.2"
					( objectStatus "b" )
				)
			)
			( gate "R2U32"
				( objectStatus "@baseboard_fab2_lib.baseboard_fab2(sch_1):page108_i339" )
				( pin "R2U32.1"
					( objectStatus "a" )
				)
				( pin "R2U32.2"
					( objectStatus "b" )
				)
			)
			( gate "R2U36"
				( objectStatus "@baseboard_fab2_lib.baseboard_fab2(sch_1):page108_i340" )
				( pin "R2U36.1"
					( objectStatus "a" )
				)
				( pin "R2U36.2"
					( objectStatus "b" )
				)
			)
			( gate "R139"
				( objectStatus "@baseboard_fab2_lib.baseboard_fab2(sch_1):page108_i341" )
				( pin "R139.1"
					( objectStatus "a" )
				)
				( pin "R139.2"
					( objectStatus "b" )
				)
			)
			( gate "R172"
				( objectStatus "@baseboard_fab2_lib.baseboard_fab2(sch_1):page108_i343" )
				( pin "R172.1"
					( objectStatus "a" )
				)
				( pin "R172.2"
					( objectStatus "b" )
				)
			)
			( gate "J8G1"
				( objectStatus "@baseboard_fab2_lib.baseboard_fab2(sch_1):page109_i243" )
				( pin "J8G1.101"
					( objectStatus "io101" )
				)
				( pin "J8G1.102"
					( objectStatus "io102" )
				)
				( pin "J8G1.103"
					( objectStatus "io103" )
				)
				( pin "J8G1.104"
					( objectStatus "io104" )
				)
				( pin "J8G1.105"
					( objectStatus "io105" )
				)
				( pin "J8G1.106"
					( objectStatus "io106" )
				)
				( pin "J8G1.107"
					( objectStatus "io107" )
				)
				( pin "J8G1.108"
					( objectStatus "io108" )
				)
				( pin "J8G1.109"
					( objectStatus "io109" )
				)
				( pin "J8G1.110"
					( objectStatus "io110" )
				)
				( pin "J8G1.111"
					( objectStatus "io111" )
				)
				( pin "J8G1.112"
					( objectStatus "io112" )
				)
				( pin "J8G1.113"
					( objectStatus "io113" )
				)
				( pin "J8G1.114"
					( objectStatus "io114" )
				)
				( pin "J8G1.115"
					( objectStatus "io115" )
				)
				( pin "J8G1.116"
					( objectStatus "io116" )
				)
				( pin "J8G1.117"
					( objectStatus "io117" )
				)
				( pin "J8G1.118"
					( objectStatus "io118" )
				)
				( pin "J8G1.119"
					( objectStatus "io119" )
				)
				( pin "J8G1.120"
					( objectStatus "io120" )
				)
				( pin "J8G1.121"
					( objectStatus "io121" )
				)
				( pin "J8G1.122"
					( objectStatus "io122" )
				)
				( pin "J8G1.123"
					( objectStatus "io123" )
				)
				( pin "J8G1.124"
					( objectStatus "io124" )
				)
				( pin "J8G1.125"
					( objectStatus "io125" )
				)
				( pin "J8G1.126"
					( objectStatus "io126" )
				)
				( pin "J8G1.127"
					( objectStatus "io127" )
				)
				( pin "J8G1.128"
					( objectStatus "io128" )
				)
				( pin "J8G1.129"
					( objectStatus "io129" )
				)
				( pin "J8G1.130"
					( objectStatus "io130" )
				)
				( pin "J8G1.131"
					( objectStatus "io131" )
				)
				( pin "J8G1.132"
					( objectStatus "io132" )
				)
				( pin "J8G1.133"
					( objectStatus "io133" )
				)
				( pin "J8G1.134"
					( objectStatus "io134" )
				)
				( pin "J8G1.135"
					( objectStatus "io135" )
				)
				( pin "J8G1.136"
					( objectStatus "io136" )
				)
				( pin "J8G1.137"
					( objectStatus "io137" )
				)
				( pin "J8G1.138"
					( objectStatus "io138" )
				)
				( pin "J8G1.139"
					( objectStatus "io139" )
				)
				( pin "J8G1.140"
					( objectStatus "io140" )
				)
				( pin "J8G1.141"
					( objectStatus "io141" )
				)
				( pin "J8G1.142"
					( objectStatus "io142" )
				)
				( pin "J8G1.143"
					( objectStatus "io143" )
				)
				( pin "J8G1.144"
					( objectStatus "io144" )
				)
				( pin "J8G1.145"
					( objectStatus "io145" )
				)
				( pin "J8G1.146"
					( objectStatus "io146" )
				)
				( pin "J8G1.147"
					( objectStatus "io147" )
				)
				( pin "J8G1.148"
					( objectStatus "io148" )
				)
				( pin "J8G1.149"
					( objectStatus "io149" )
				)
				( pin "J8G1.150"
					( objectStatus "io150" )
				)
				( pin "J8G1.151"
					( objectStatus "io151" )
				)
				( pin "J8G1.152"
					( objectStatus "io152" )
				)
				( pin "J8G1.153"
					( objectStatus "io153" )
				)
				( pin "J8G1.154"
					( objectStatus "io154" )
				)
				( pin "J8G1.155"
					( objectStatus "io155" )
				)
				( pin "J8G1.156"
					( objectStatus "io156" )
				)
				( pin "J8G1.157"
					( objectStatus "io157" )
				)
				( pin "J8G1.158"
					( objectStatus "io158" )
				)
				( pin "J8G1.159"
					( objectStatus "io159" )
				)
				( pin "J8G1.160"
					( objectStatus "io160" )
				)
				( pin "J8G1.161"
					( objectStatus "io161" )
				)
				( pin "J8G1.162"
					( objectStatus "io162" )
				)
				( pin "J8G1.163"
					( objectStatus "io163" )
				)
				( pin "J8G1.164"
					( objectStatus "io164" )
				)
				( pin "J8G1.165"
					( objectStatus "io165" )
				)
				( pin "J8G1.166"
					( objectStatus "io166" )
				)
				( pin "J8G1.167"
					( objectStatus "io167" )
				)
				( pin "J8G1.168"
					( objectStatus "io168" )
				)
				( pin "J8G1.169"
					( objectStatus "io169" )
				)
				( pin "J8G1.170"
					( objectStatus "io170" )
				)
				( pin "J8G1.171"
					( objectStatus "io171" )
				)
				( pin "J8G1.172"
					( objectStatus "io172" )
				)
				( pin "J8G1.173"
					( objectStatus "io173" )
				)
				( pin "J8G1.174"
					( objectStatus "io174" )
				)
				( pin "J8G1.175"
					( objectStatus "io175" )
				)
				( pin "J8G1.176"
					( objectStatus "io176" )
				)
				( pin "J8G1.177"
					( objectStatus "io177" )
				)
				( pin "J8G1.178"
					( objectStatus "io178" )
				)
				( pin "J8G1.179"
					( objectStatus "io179" )
				)
				( pin "J8G1.180"
					( objectStatus "io180" )
				)
				( pin "J8G1.181"
					( objectStatus "io181" )
				)
				( pin "J8G1.182"
					( objectStatus "io182" )
				)
				( pin "J8G1.183"
					( objectStatus "io183" )
				)
				( pin "J8G1.184"
					( objectStatus "io184" )
				)
				( pin "J8G1.185"
					( objectStatus "io185" )
				)
				( pin "J8G1.186"
					( objectStatus "io186" )
				)
				( pin "J8G1.187"
					( objectStatus "io187" )
				)
				( pin "J8G1.188"
					( objectStatus "io188" )
				)
				( pin "J8G1.189"
					( objectStatus "io189" )
				)
				( pin "J8G1.190"
					( objectStatus "io190" )
				)
				( pin "J8G1.191"
					( objectStatus "io191" )
				)
				( pin "J8G1.192"
					( objectStatus "io192" )
				)
				( pin "J8G1.193"
					( objectStatus "io193" )
				)
				( pin "J8G1.194"
					( objectStatus "io194" )
				)
				( pin "J8G1.195"
					( objectStatus "io195" )
				)
				( pin "J8G1.196"
					( objectStatus "io196" )
				)
				( pin "J8G1.197"
					( objectStatus "io197" )
				)
				( pin "J8G1.198"
					( objectStatus "io198" )
				)
				( pin "J8G1.199"
					( objectStatus "io199" )
				)
				( pin "J8G1.200"
					( objectStatus "io200" )
				)
			)
			( gate "TC9F1"
				( objectStatus "@baseboard_fab2_lib.baseboard_fab2(sch_1):page110_i1" )
				( pin "TC9F1.1"
					( objectStatus "gnd" )
				)
				( pin "TC9F1.2"
					( objectStatus "io1" )
				)
				( pin "TC9F1.3"
					( objectStatus "io2" )
				)
			)
			( gate "TC1G1"
				( objectStatus "@baseboard_fab2_lib.baseboard_fab2(sch_1):page110_i3" )
				( pin "TC1G1.1"
					( objectStatus "gnd" )
				)
				( pin "TC1G1.2"
					( objectStatus "io1" )
				)
				( pin "TC1G1.3"
					( objectStatus "io2" )
				)
			)
			( gate "TC1A1"
				( objectStatus "@baseboard_fab2_lib.baseboard_fab2(sch_1):page110_i7" )
				( pin "TC1A1.1"
					( objectStatus "gnd" )
				)
				( pin "TC1A1.2"
					( objectStatus "io1" )
				)
				( pin "TC1A1.3"
					( objectStatus "io2" )
				)
			)
			( gate "TC9A1"
				( objectStatus "@baseboard_fab2_lib.baseboard_fab2(sch_1):page110_i9" )
				( pin "TC9A1.1"
					( objectStatus "gnd" )
				)
				( pin "TC9A1.2"
					( objectStatus "io1" )
				)
				( pin "TC9A1.3"
					( objectStatus "io2" )
				)
			)
			( gate "LB2F1"
				( objectStatus "@baseboard_fab2_lib.baseboard_fab2(sch_1):page110_i11" )
			)
			( gate "LB5F1"
				( objectStatus "@baseboard_fab2_lib.baseboard_fab2(sch_1):page110_i12" )
			)
			( gate "LB2B1"
				( objectStatus "@baseboard_fab2_lib.baseboard_fab2(sch_1):page110_i13" )
			)
			( gate "LB5B1"
				( objectStatus "@baseboard_fab2_lib.baseboard_fab2(sch_1):page110_i14" )
			)
			( gate "LB6T1"
				( objectStatus "@baseboard_fab2_lib.baseboard_fab2(sch_1):page110_i15" )
			)
			( gate "TC7"
				( objectStatus "@baseboard_fab2_lib.baseboard_fab2(sch_1):page110_i16" )
				( pin "TC7.1"
					( objectStatus "io1" )
				)
				( pin "TC7.2"
					( objectStatus "io2" )
				)
				( pin "TC7.3"
					( objectStatus "io3" )
				)
			)
			( gate "TC8"
				( objectStatus "@baseboard_fab2_lib.baseboard_fab2(sch_1):page110_i18" )
				( pin "TC8.1"
					( objectStatus "io1" )
				)
				( pin "TC8.2"
					( objectStatus "io2" )
				)
				( pin "TC8.3"
					( objectStatus "io3" )
				)
			)
			( gate "TC10"
				( objectStatus "@baseboard_fab2_lib.baseboard_fab2(sch_1):page110_i22" )
				( pin "TC10.1"
					( objectStatus "io1" )
				)
				( pin "TC10.2"
					( objectStatus "io2" )
				)
				( pin "TC10.3"
					( objectStatus "io3" )
				)
			)
			( gate "TC11"
				( objectStatus "@baseboard_fab2_lib.baseboard_fab2(sch_1):page110_i24" )
				( pin "TC11.1"
					( objectStatus "io1" )
				)
				( pin "TC11.2"
					( objectStatus "io2" )
				)
				( pin "TC11.3"
					( objectStatus "io3" )
				)
			)
			( gate "TC19"
				( objectStatus "@baseboard_fab2_lib.baseboard_fab2(sch_1):page110_i53" )
				( pin "TC19.1"
					( objectStatus "io1" )
				)
				( pin "TC19.2"
					( objectStatus "io2" )
				)
				( pin "TC19.3"
					( objectStatus "io3" )
				)
			)
			( gate "TC1"
				( objectStatus "@baseboard_fab2_lib.baseboard_fab2(sch_1):page110_i54" )
				( pin "TC1.1"
					( objectStatus "io1" )
				)
				( pin "TC1.2"
					( objectStatus "io2" )
				)
				( pin "TC1.3"
					( objectStatus "io3" )
				)
			)
			( gate "TC3"
				( objectStatus "@baseboard_fab2_lib.baseboard_fab2(sch_1):page110_i58" )
				( pin "TC3.1"
					( objectStatus "io1" )
				)
				( pin "TC3.2"
					( objectStatus "io2" )
				)
				( pin "TC3.3"
					( objectStatus "io3" )
				)
			)
			( gate "TC4"
				( objectStatus "@baseboard_fab2_lib.baseboard_fab2(sch_1):page110_i62" )
				( pin "TC4.1"
					( objectStatus "io1" )
				)
				( pin "TC4.2"
					( objectStatus "io2" )
				)
				( pin "TC4.3"
					( objectStatus "io3" )
				)
			)
			( gate "TC20"
				( objectStatus "@baseboard_fab2_lib.baseboard_fab2(sch_1):page110_i66" )
				( pin "TC20.1"
					( objectStatus "io1" )
				)
				( pin "TC20.2"
					( objectStatus "io2" )
				)
				( pin "TC20.3"
					( objectStatus "io3" )
				)
			)
			( gate "R1L13"
				( objectStatus "@baseboard_fab2_lib.baseboard_fab2(sch_1):page111_i6" )
				( pin "R1L13.1"
					( objectStatus "a" )
				)
				( pin "R1L13.2"
					( objectStatus "b" )
				)
			)
			( gate "C9A2"
				( objectStatus "@baseboard_fab2_lib.baseboard_fab2(sch_1):page111_i10" )
				( pin "C9A2.1"
					( objectStatus "a" )
				)
				( pin "C9A2.2"
					( objectStatus "b" )
				)
			)
			( gate "R9A14"
				( objectStatus "@baseboard_fab2_lib.baseboard_fab2(sch_1):page111_i11" )
				( pin "R9A14.1"
					( objectStatus "a" )
				)
				( pin "R9A14.2"
					( objectStatus "b" )
				)
			)
			( gate "C9A5"
				( objectStatus "@baseboard_fab2_lib.baseboard_fab2(sch_1):page111_i12" )
				( pin "C9A5.1"
					( objectStatus "a" )
				)
				( pin "C9A5.2"
					( objectStatus "b" )
				)
			)
			( gate "R1L23"
				( objectStatus "@baseboard_fab2_lib.baseboard_fab2(sch_1):page111_i13" )
				( pin "R1L23.1"
					( objectStatus "a" )
				)
				( pin "R1L23.2"
					( objectStatus "b" )
				)
			)
			( gate "C1L8"
				( objectStatus "@baseboard_fab2_lib.baseboard_fab2(sch_1):page111_i14" )
				( pin "C1L8.1"
					( objectStatus "a" )
				)
				( pin "C1L8.2"
					( objectStatus "b" )
				)
			)
			( gate "C9A6"
				( objectStatus "@baseboard_fab2_lib.baseboard_fab2(sch_1):page111_i25" )
				( pin "C9A6.1"
					( objectStatus "a" )
				)
				( pin "C9A6.2"
					( objectStatus "b" )
				)
			)
			( gate "J9A3"
				( objectStatus "@baseboard_fab2_lib.baseboard_fab2(sch_1):page111_i26" )
				( pin "J9A3.1"
					( objectStatus "io1" )
				)
				( pin "J9A3.2"
					( objectStatus "io2" )
				)
				( pin "J9A3.3"
					( objectStatus "io3" )
				)
				( pin "J9A3.4"
					( objectStatus "io4" )
				)
				( pin "J9A3.5"
					( objectStatus "io5" )
				)
				( pin "J9A3.6"
					( objectStatus "io6" )
				)
				( pin "J9A3.7"
					( objectStatus "io7" )
				)
				( pin "J9A3.8"
					( objectStatus "io8" )
				)
				( pin "J9A3.9"
					( objectStatus "io9" )
				)
				( pin "J9A3.10"
					( objectStatus "io10" )
				)
				( pin "J9A3.11"
					( objectStatus "io11" )
				)
				( pin "J9A3.12"
					( objectStatus "io12" )
				)
				( pin "J9A3.13"
					( objectStatus "io13" )
				)
				( pin "J9A3.14"
					( objectStatus "io14" )
				)
				( pin "J9A3.15"
					( objectStatus "io15" )
				)
				( pin "J9A3.16"
					( objectStatus "io16" )
				)
				( pin "J9A3.17"
					( objectStatus "io17" )
				)
				( pin "J9A3.18"
					( objectStatus "io18" )
				)
				( pin "J9A3.19"
					( objectStatus "io19" )
				)
				( pin "J9A3.20"
					( objectStatus "io20" )
				)
				( pin "J9A3.21"
					( objectStatus "io21" )
				)
				( pin "J9A3.22"
					( objectStatus "io22" )
				)
				( pin "J9A3.23"
					( objectStatus "io23" )
				)
				( pin "J9A3.24"
					( objectStatus "io24" )
				)
				( pin "J9A3.25"
					( objectStatus "io25" )
				)
				( pin "J9A3.26"
					( objectStatus "io26" )
				)
				( pin "J9A3.27"
					( objectStatus "io27" )
				)
				( pin "J9A3.28"
					( objectStatus "io28" )
				)
				( pin "J9A3.29"
					( objectStatus "io29" )
				)
				( pin "J9A3.30"
					( objectStatus "io30" )
				)
				( pin "J9A3.31"
					( objectStatus "io31" )
				)
				( pin "J9A3.32"
					( objectStatus "io32" )
				)
				( pin "J9A3.33"
					( objectStatus "io33" )
				)
				( pin "J9A3.34"
					( objectStatus "io34" )
				)
				( pin "J9A3.35"
					( objectStatus "io35" )
				)
				( pin "J9A3.36"
					( objectStatus "io36" )
				)
				( pin "J9A3.37"
					( objectStatus "io37" )
				)
				( pin "J9A3.38"
					( objectStatus "io38" )
				)
				( pin "J9A3.39"
					( objectStatus "io39" )
				)
				( pin "J9A3.40"
					( objectStatus "io40" )
				)
				( pin "J9A3.41"
					( objectStatus "io41" )
				)
				( pin "J9A3.42"
					( objectStatus "io42" )
				)
				( pin "J9A3.43"
					( objectStatus "io43" )
				)
				( pin "J9A3.44"
					( objectStatus "io44" )
				)
				( pin "J9A3.45"
					( objectStatus "io45" )
				)
				( pin "J9A3.46"
					( objectStatus "io46" )
				)
				( pin "J9A3.47"
					( objectStatus "io47" )
				)
				( pin "J9A3.48"
					( objectStatus "io48" )
				)
				( pin "J9A3.49"
					( objectStatus "io49" )
				)
				( pin "J9A3.50"
					( objectStatus "io50" )
				)
				( pin "J9A3.51"
					( objectStatus "io51" )
				)
				( pin "J9A3.52"
					( objectStatus "io52" )
				)
				( pin "J9A3.53"
					( objectStatus "io53" )
				)
				( pin "J9A3.54"
					( objectStatus "io54" )
				)
				( pin "J9A3.55"
					( objectStatus "io55" )
				)
				( pin "J9A3.56"
					( objectStatus "io56" )
				)
				( pin "J9A3.57"
					( objectStatus "io57" )
				)
				( pin "J9A3.58"
					( objectStatus "io58" )
				)
				( pin "J9A3.59"
					( objectStatus "io59" )
				)
				( pin "J9A3.60"
					( objectStatus "io60" )
				)
			)
			( gate "C1L5"
				( objectStatus "@baseboard_fab2_lib.baseboard_fab2(sch_1):page111_i30" )
				( pin "C1L5.1"
					( objectStatus "a" )
				)
				( pin "C1L5.2"
					( objectStatus "b" )
				)
			)
			( gate "R2P2"
				( objectStatus "@baseboard_fab2_lib.baseboard_fab2(sch_1):page111_i37" )
				( pin "R2P2.1"
					( objectStatus "a" )
				)
				( pin "R2P2.2"
					( objectStatus "b" )
				)
			)
			( gate "R9A4"
				( objectStatus "@baseboard_fab2_lib.baseboard_fab2(sch_1):page111_i55" )
				( pin "R9A4.1"
					( objectStatus "a" )
				)
				( pin "R9A4.2"
					( objectStatus "b" )
				)
			)
			( gate "R1L17"
				( objectStatus "@baseboard_fab2_lib.baseboard_fab2(sch_1):page111_i56" )
				( pin "R1L17.1"
					( objectStatus "a" )
				)
				( pin "R1L17.2"
					( objectStatus "b" )
				)
			)
			( gate "R9A17"
				( objectStatus "@baseboard_fab2_lib.baseboard_fab2(sch_1):page111_i57" )
				( pin "R9A17.1"
					( objectStatus "a" )
				)
				( pin "R9A17.2"
					( objectStatus "b" )
				)
			)
			( gate "C9A4"
				( objectStatus "@baseboard_fab2_lib.baseboard_fab2(sch_1):page111_i59" )
				( pin "C9A4.1"
					( objectStatus "a" )
				)
				( pin "C9A4.2"
					( objectStatus "b" )
				)
			)
			( gate "R9A15"
				( objectStatus "@baseboard_fab2_lib.baseboard_fab2(sch_1):page111_i60" )
				( pin "R9A15.1"
					( objectStatus "a" )
				)
				( pin "R9A15.2"
					( objectStatus "b" )
				)
			)
			( gate "R1L28"
				( objectStatus "@baseboard_fab2_lib.baseboard_fab2(sch_1):page111_i66" )
				( pin "R1L28.1"
					( objectStatus "a" )
				)
				( pin "R1L28.2"
					( objectStatus "b" )
				)
			)
			( gate "R1L29"
				( objectStatus "@baseboard_fab2_lib.baseboard_fab2(sch_1):page111_i68" )
				( pin "R1L29.1"
					( objectStatus "a" )
				)
				( pin "R1L29.2"
					( objectStatus "b" )
				)
			)
			( gate "R9A3"
				( objectStatus "@baseboard_fab2_lib.baseboard_fab2(sch_1):page111_i74" )
				( pin "R9A3.1"
					( objectStatus "a" )
				)
				( pin "R9A3.2"
					( objectStatus "b" )
				)
			)
			( gate "R9A2"
				( objectStatus "@baseboard_fab2_lib.baseboard_fab2(sch_1):page111_i83" )
				( pin "R9A2.1"
					( objectStatus "a" )
				)
				( pin "R9A2.2"
					( objectStatus "b" )
				)
			)
			( gate "U1L4"
				( objectStatus "@baseboard_fab2_lib.baseboard_fab2(sch_1):page111_i85" )
				( pin "U1L4.2"
					( objectStatus "a" )
				)
				( pin "U1L4.4"
					( objectStatus "y" )
				)
			)
			( gate "C1L11"
				( objectStatus "@baseboard_fab2_lib.baseboard_fab2(sch_1):page111_i87" )
				( pin "C1L11.1"
					( objectStatus "a" )
				)
				( pin "C1L11.2"
					( objectStatus "b" )
				)
			)
			( gate "R8E2"
				( objectStatus "@baseboard_fab2_lib.baseboard_fab2(sch_1):page111_i89" )
				( pin "R8E2.1"
					( objectStatus "a" )
				)
				( pin "R8E2.2"
					( objectStatus "b" )
				)
			)
			( gate "Q9A1"
				( objectStatus "@baseboard_fab2_lib.baseboard_fab2(sch_1):page111_i93" )
				( pin "Q9A1.2"
					( objectStatus "b(0)" )
				)
				( pin "Q9A1.6"
					( objectStatus "c(0)" )
				)
				( pin "Q9A1.1"
					( objectStatus "e(0)" )
				)
			)
			( gate "Q9A1"
				( objectStatus "@baseboard_fab2_lib.baseboard_fab2(sch_1):page111_i94" )
				( pin "Q9A1.5"
					( objectStatus "b(0)" )
				)
				( pin "Q9A1.3"
					( objectStatus "c(0)" )
				)
				( pin "Q9A1.4"
					( objectStatus "e(0)" )
				)
			)
			( gate "R9A1"
				( objectStatus "@baseboard_fab2_lib.baseboard_fab2(sch_1):page111_i95" )
				( pin "R9A1.1"
					( objectStatus "a" )
				)
				( pin "R9A1.2"
					( objectStatus "b" )
				)
			)
			( gate "U9B3"
				( objectStatus "@baseboard_fab2_lib.baseboard_fab2(sch_1):page112_i40" )
				( pin "U9B3.4"
					( objectStatus "a" )
				)
				( pin "U9B3.3"
					( objectStatus "b0" )
				)
				( pin "U9B3.1"
					( objectStatus "b1" )
				)
				( pin "U9B3.2"
					( objectStatus "gnd" )
				)
				( pin "U9B3.6"
					( objectStatus "s" )
				)
				( pin "U9B3.5"
					( objectStatus "vcc" )
				)
			)
			( gate "C9B6"
				( objectStatus "@baseboard_fab2_lib.baseboard_fab2(sch_1):page112_i42" )
				( pin "C9B6.1"
					( objectStatus "a" )
				)
				( pin "C9B6.2"
					( objectStatus "b" )
				)
			)
			( gate "C9B3"
				( objectStatus "@baseboard_fab2_lib.baseboard_fab2(sch_1):page112_i47" )
				( pin "C9B3.1"
					( objectStatus "a" )
				)
				( pin "C9B3.2"
					( objectStatus "b" )
				)
			)
			( gate "R6P46"
				( objectStatus "@baseboard_fab2_lib.baseboard_fab2(sch_1):page112_i49" )
				( pin "R6P46.1"
					( objectStatus "a" )
				)
				( pin "R6P46.2"
					( objectStatus "b" )
				)
			)
			( gate "R7P30"
				( objectStatus "@baseboard_fab2_lib.baseboard_fab2(sch_1):page112_i50" )
				( pin "R7P30.1"
					( objectStatus "a" )
				)
				( pin "R7P30.2"
					( objectStatus "b" )
				)
			)
			( gate "R1M3"
				( objectStatus "@baseboard_fab2_lib.baseboard_fab2(sch_1):page112_i51" )
				( pin "R1M3.1"
					( objectStatus "a" )
				)
				( pin "R1M3.2"
					( objectStatus "b" )
				)
			)
			( gate "R4P15"
				( objectStatus "@baseboard_fab2_lib.baseboard_fab2(sch_1):page112_i53" )
				( pin "R4P15.1"
					( objectStatus "a" )
				)
				( pin "R4P15.2"
					( objectStatus "b" )
				)
			)
			( gate "R1M4"
				( objectStatus "@baseboard_fab2_lib.baseboard_fab2(sch_1):page112_i54" )
				( pin "R1M4.1"
					( objectStatus "a" )
				)
				( pin "R1M4.2"
					( objectStatus "b" )
				)
			)
			( gate "R6T7"
				( objectStatus "@baseboard_fab2_lib.baseboard_fab2(sch_1):page112_i55" )
				( pin "R6T7.1"
					( objectStatus "a" )
				)
				( pin "R6T7.2"
					( objectStatus "b" )
				)
			)
			( gate "R6T6"
				( objectStatus "@baseboard_fab2_lib.baseboard_fab2(sch_1):page112_i56" )
				( pin "R6T6.1"
					( objectStatus "a" )
				)
				( pin "R6T6.2"
					( objectStatus "b" )
				)
			)
			( gate "R4P12"
				( objectStatus "@baseboard_fab2_lib.baseboard_fab2(sch_1):page112_i57" )
				( pin "R4P12.1"
					( objectStatus "a" )
				)
				( pin "R4P12.2"
					( objectStatus "b" )
				)
			)
			( gate "R4P23"
				( objectStatus "@baseboard_fab2_lib.baseboard_fab2(sch_1):page112_i58" )
				( pin "R4P23.1"
					( objectStatus "a" )
				)
				( pin "R4P23.2"
					( objectStatus "b" )
				)
			)
			( gate "R4P24"
				( objectStatus "@baseboard_fab2_lib.baseboard_fab2(sch_1):page112_i59" )
				( pin "R4P24.1"
					( objectStatus "a" )
				)
				( pin "R4P24.2"
					( objectStatus "b" )
				)
			)
			( gate "R1L15"
				( objectStatus "@baseboard_fab2_lib.baseboard_fab2(sch_1):page112_i60" )
				( pin "R1L15.1"
					( objectStatus "a" )
				)
				( pin "R1L15.2"
					( objectStatus "b" )
				)
			)
			( gate "R7P29"
				( objectStatus "@baseboard_fab2_lib.baseboard_fab2(sch_1):page112_i61" )
				( pin "R7P29.1"
					( objectStatus "a" )
				)
				( pin "R7P29.2"
					( objectStatus "b" )
				)
			)
			( gate "R6T5"
				( objectStatus "@baseboard_fab2_lib.baseboard_fab2(sch_1):page112_i62" )
				( pin "R6T5.1"
					( objectStatus "a" )
				)
				( pin "R6T5.2"
					( objectStatus "b" )
				)
			)
			( gate "R1L39"
				( objectStatus "@baseboard_fab2_lib.baseboard_fab2(sch_1):page112_i76" )
				( pin "R1L39.1"
					( objectStatus "a" )
				)
				( pin "R1L39.2"
					( objectStatus "b" )
				)
			)
			( gate "R1L41"
				( objectStatus "@baseboard_fab2_lib.baseboard_fab2(sch_1):page112_i77" )
				( pin "R1L41.1"
					( objectStatus "a" )
				)
				( pin "R1L41.2"
					( objectStatus "b" )
				)
			)
			( gate "R9A11"
				( objectStatus "@baseboard_fab2_lib.baseboard_fab2(sch_1):page112_i78" )
				( pin "R9A11.1"
					( objectStatus "a" )
				)
				( pin "R9A11.2"
					( objectStatus "b" )
				)
			)
			( gate "R8A13"
				( objectStatus "@baseboard_fab2_lib.baseboard_fab2(sch_1):page112_i79" )
				( pin "R8A13.1"
					( objectStatus "a" )
				)
				( pin "R8A13.2"
					( objectStatus "b" )
				)
			)
			( gate "R8A14"
				( objectStatus "@baseboard_fab2_lib.baseboard_fab2(sch_1):page112_i80" )
				( pin "R8A14.1"
					( objectStatus "a" )
				)
				( pin "R8A14.2"
					( objectStatus "b" )
				)
			)
			( gate "R3M10"
				( objectStatus "@baseboard_fab2_lib.baseboard_fab2(sch_1):page112_i85" )
				( pin "R3M10.1"
					( objectStatus "a" )
				)
				( pin "R3M10.2"
					( objectStatus "b" )
				)
			)
			( gate "R8B2"
				( objectStatus "@baseboard_fab2_lib.baseboard_fab2(sch_1):page112_i94" )
				( pin "R8B2.1"
					( objectStatus "a" )
				)
				( pin "R8B2.2"
					( objectStatus "b" )
				)
			)
			( gate "R8B1"
				( objectStatus "@baseboard_fab2_lib.baseboard_fab2(sch_1):page112_i95" )
				( pin "R8B1.1"
					( objectStatus "a" )
				)
				( pin "R8B1.2"
					( objectStatus "b" )
				)
			)
			( gate "U1L1"
				( objectStatus "@baseboard_fab2_lib.baseboard_fab2(sch_1):page112_i108" )
			)
			( gate "U1L5"
				( objectStatus "@baseboard_fab2_lib.baseboard_fab2(sch_1):page112_i109" )
			)
			( gate "R6T9"
				( objectStatus "@baseboard_fab2_lib.baseboard_fab2(sch_1):page112_i120" )
				( pin "R6T9.1"
					( objectStatus "a" )
				)
				( pin "R6T9.2"
					( objectStatus "b" )
				)
			)
			( gate "R6T8"
				( objectStatus "@baseboard_fab2_lib.baseboard_fab2(sch_1):page112_i121" )
				( pin "R6T8.1"
					( objectStatus "a" )
				)
				( pin "R6T8.2"
					( objectStatus "b" )
				)
			)
			( gate "U9B2"
				( objectStatus "@baseboard_fab2_lib.baseboard_fab2(sch_1):page112_i127" )
				( pin "U9B2.2"
					( objectStatus "a" )
				)
				( pin "U9B2.4"
					( objectStatus "b" )
				)
				( pin "U9B2.1"
					( objectStatus "oe_n" )
				)
			)
			( gate "C9B4"
				( objectStatus "@baseboard_fab2_lib.baseboard_fab2(sch_1):page112_i131" )
				( pin "C9B4.1"
					( objectStatus "a" )
				)
				( pin "C9B4.2"
					( objectStatus "b" )
				)
			)
			( gate "C1L1"
				( objectStatus "@baseboard_fab2_lib.baseboard_fab2(sch_1):page112_i136" )
				( pin "C1L1.1"
					( objectStatus "a" )
				)
				( pin "C1L1.2"
					( objectStatus "b" )
				)
			)
			( gate "C1L19"
				( objectStatus "@baseboard_fab2_lib.baseboard_fab2(sch_1):page112_i140" )
				( pin "C1L19.1"
					( objectStatus "a" )
				)
				( pin "C1L19.2"
					( objectStatus "b" )
				)
			)
			( gate "U2N1"
				( objectStatus "@baseboard_fab2_lib.baseboard_fab2(sch_1):page113_i107" )
				( pin "U2N1.4"
					( objectStatus "a" )
				)
				( pin "U2N1.3"
					( objectStatus "b0" )
				)
				( pin "U2N1.1"
					( objectStatus "b1" )
				)
				( pin "U2N1.2"
					( objectStatus "gnd" )
				)
				( pin "U2N1.6"
					( objectStatus "s" )
				)
				( pin "U2N1.5"
					( objectStatus "vcc" )
				)
			)
			( gate "C2N28"
				( objectStatus "@baseboard_fab2_lib.baseboard_fab2(sch_1):page113_i116" )
				( pin "C2N28.1"
					( objectStatus "a" )
				)
				( pin "C2N28.2"
					( objectStatus "b" )
				)
			)
			( gate "C2N30"
				( objectStatus "@baseboard_fab2_lib.baseboard_fab2(sch_1):page113_i117" )
				( pin "C2N30.1"
					( objectStatus "a" )
				)
				( pin "C2N30.2"
					( objectStatus "b" )
				)
			)
			( gate "C2N29"
				( objectStatus "@baseboard_fab2_lib.baseboard_fab2(sch_1):page113_i119" )
				( pin "C2N29.1"
					( objectStatus "a" )
				)
				( pin "C2N29.2"
					( objectStatus "b" )
				)
			)
			( gate "U2N2"
				( objectStatus "@baseboard_fab2_lib.baseboard_fab2(sch_1):page113_i127" )
				( pin "U2N2.2"
					( objectStatus "a" )
				)
				( pin "U2N2.4"
					( objectStatus "b" )
				)
				( pin "U2N2.1"
					( objectStatus "oe_n" )
				)
			)
			( gate "R4P9"
				( objectStatus "@baseboard_fab2_lib.baseboard_fab2(sch_1):page113_i134" )
				( pin "R4P9.1"
					( objectStatus "a" )
				)
				( pin "R4P9.2"
					( objectStatus "b" )
				)
			)
			( gate "C2N27"
				( objectStatus "@baseboard_fab2_lib.baseboard_fab2(sch_1):page113_i147" )
				( pin "C2N27.1"
					( objectStatus "a" )
				)
				( pin "C2N27.2"
					( objectStatus "b" )
				)
			)
			( gate "R8C19"
				( objectStatus "@baseboard_fab2_lib.baseboard_fab2(sch_1):page113_i168" )
				( pin "R8C19.1"
					( objectStatus "a" )
				)
				( pin "R8C19.2"
					( objectStatus "b" )
				)
			)
			( gate "J8C3"
				( objectStatus "@baseboard_fab2_lib.baseboard_fab2(sch_1):page113_i175" )
				( pin "J8C3.1"
					( objectStatus "io1" )
				)
				( pin "J8C3.2"
					( objectStatus "io2" )
				)
				( pin "J8C3.3"
					( objectStatus "io3" )
				)
				( pin "J8C3.4"
					( objectStatus "io4" )
				)
				( pin "J8C3.5"
					( objectStatus "io5" )
				)
				( pin "J8C3.6"
					( objectStatus "io6" )
				)
				( pin "J8C3.7"
					( objectStatus "io7" )
				)
				( pin "J8C3.8"
					( objectStatus "io8" )
				)
				( pin "J8C3.9"
					( objectStatus "io9" )
				)
				( pin "J8C3.10"
					( objectStatus "io10" )
				)
			)
			( gate "R135"
				( objectStatus "@baseboard_fab2_lib.baseboard_fab2(sch_1):page113_i179" )
				( pin "R135.1"
					( objectStatus "a" )
				)
				( pin "R135.2"
					( objectStatus "b" )
				)
			)
			( gate "R6M5"
				( objectStatus "@baseboard_fab2_lib.baseboard_fab2(sch_1):page113_i180" )
				( pin "R6M5.1"
					( objectStatus "a" )
				)
				( pin "R6M5.2"
					( objectStatus "b" )
				)
			)
			( gate "U9"
				( objectStatus "@baseboard_fab2_lib.baseboard_fab2(sch_1):page113_i185" )
				( pin "U9.2"
					( objectStatus "a" )
				)
				( pin "U9.4"
					( objectStatus "b" )
				)
				( pin "U9.1"
					( objectStatus "oe_n" )
				)
			)
			( gate "R6M8"
				( objectStatus "@baseboard_fab2_lib.baseboard_fab2(sch_1):page113_i188" )
				( pin "R6M8.1"
					( objectStatus "a" )
				)
				( pin "R6M8.2"
					( objectStatus "b" )
				)
			)
			( gate "U7"
				( objectStatus "@baseboard_fab2_lib.baseboard_fab2(sch_1):page113_i190" )
				( pin "U7.2"
					( objectStatus "a" )
				)
				( pin "U7.4"
					( objectStatus "b" )
				)
				( pin "U7.1"
					( objectStatus "oe_n" )
				)
			)
			( gate "R6M6"
				( objectStatus "@baseboard_fab2_lib.baseboard_fab2(sch_1):page113_i195" )
				( pin "R6M6.1"
					( objectStatus "a" )
				)
				( pin "R6M6.2"
					( objectStatus "b" )
				)
			)
			( gate "U8"
				( objectStatus "@baseboard_fab2_lib.baseboard_fab2(sch_1):page113_i196" )
				( pin "U8.2"
					( objectStatus "a" )
				)
				( pin "U8.4"
					( objectStatus "b" )
				)
				( pin "U8.1"
					( objectStatus "oe_n" )
				)
			)
			( gate "R132"
				( objectStatus "@baseboard_fab2_lib.baseboard_fab2(sch_1):page113_i199" )
				( pin "R132.1"
					( objectStatus "a" )
				)
				( pin "R132.2"
					( objectStatus "b" )
				)
			)
			( gate "R131"
				( objectStatus "@baseboard_fab2_lib.baseboard_fab2(sch_1):page113_i202" )
				( pin "R131.1"
					( objectStatus "a" )
				)
				( pin "R131.2"
					( objectStatus "b" )
				)
			)
			( gate "R133"
				( objectStatus "@baseboard_fab2_lib.baseboard_fab2(sch_1):page113_i203" )
				( pin "R133.1"
					( objectStatus "a" )
				)
				( pin "R133.2"
					( objectStatus "b" )
				)
			)
			( gate "R130"
				( objectStatus "@baseboard_fab2_lib.baseboard_fab2(sch_1):page113_i204" )
				( pin "R130.1"
					( objectStatus "a" )
				)
				( pin "R130.2"
					( objectStatus "b" )
				)
			)
			( gate "R134"
				( objectStatus "@baseboard_fab2_lib.baseboard_fab2(sch_1):page113_i205" )
				( pin "R134.1"
					( objectStatus "a" )
				)
				( pin "R134.2"
					( objectStatus "b" )
				)
			)
			( gate "U6"
				( objectStatus "@baseboard_fab2_lib.baseboard_fab2(sch_1):page113_i206" )
				( pin "U6.2"
					( objectStatus "a" )
				)
				( pin "U6.4"
					( objectStatus "b" )
				)
				( pin "U6.1"
					( objectStatus "oe_n" )
				)
			)
			( gate "R157"
				( objectStatus "@baseboard_fab2_lib.baseboard_fab2(sch_1):page113_i239" )
				( pin "R157.1"
					( objectStatus "a" )
				)
				( pin "R157.2"
					( objectStatus "b" )
				)
			)
			( gate "R158"
				( objectStatus "@baseboard_fab2_lib.baseboard_fab2(sch_1):page113_i240" )
				( pin "R158.1"
					( objectStatus "a" )
				)
				( pin "R158.2"
					( objectStatus "b" )
				)
			)
			( gate "C34"
				( objectStatus "@baseboard_fab2_lib.baseboard_fab2(sch_1):page113_i246" )
				( pin "C34.1"
					( objectStatus "a" )
				)
				( pin "C34.2"
					( objectStatus "b" )
				)
			)
			( gate "C32"
				( objectStatus "@baseboard_fab2_lib.baseboard_fab2(sch_1):page113_i248" )
				( pin "C32.1"
					( objectStatus "a" )
				)
				( pin "C32.2"
					( objectStatus "b" )
				)
			)
			( gate "C33"
				( objectStatus "@baseboard_fab2_lib.baseboard_fab2(sch_1):page113_i250" )
				( pin "C33.1"
					( objectStatus "a" )
				)
				( pin "C33.2"
					( objectStatus "b" )
				)
			)
			( gate "U10"
				( objectStatus "@baseboard_fab2_lib.baseboard_fab2(sch_1):page113_i255" )
				( pin "U10.4"
					( objectStatus "a" )
				)
				( pin "U10.3"
					( objectStatus "b0" )
				)
				( pin "U10.1"
					( objectStatus "b1" )
				)
				( pin "U10.2"
					( objectStatus "gnd" )
				)
				( pin "U10.6"
					( objectStatus "s" )
				)
				( pin "U10.5"
					( objectStatus "vcc" )
				)
			)
			( gate "C36"
				( objectStatus "@baseboard_fab2_lib.baseboard_fab2(sch_1):page113_i265" )
				( pin "C36.1"
					( objectStatus "a" )
				)
				( pin "C36.2"
					( objectStatus "b" )
				)
			)
			( gate "C35"
				( objectStatus "@baseboard_fab2_lib.baseboard_fab2(sch_1):page113_i266" )
				( pin "C35.1"
					( objectStatus "a" )
				)
				( pin "C35.2"
					( objectStatus "b" )
				)
			)
			( gate "C40"
				( objectStatus "@baseboard_fab2_lib.baseboard_fab2(sch_1):page113_i267" )
				( pin "C40.1"
					( objectStatus "a" )
				)
				( pin "C40.2"
					( objectStatus "b" )
				)
			)
			( gate "U7C1"
				( objectStatus "@baseboard_fab2_lib.baseboard_fab2(sch_1):page114_i40" )
				( pin "U7C1.A39"
					( objectStatus "clkout_itpxdpn" )
				)
				( pin "U7C1.C39"
					( objectStatus "clkout_itpxdpp" )
				)
				( pin "U7C1.A32"
					( objectStatus "clkout_nssccap0n" )
				)
				( pin "U7C1.C32"
					( objectStatus "clkout_nssccap0p" )
				)
				( pin "U7C1.B38"
					( objectStatus "clkout_nssccap1n" )
				)
				( pin "U7C1.D38"
					( objectStatus "clkout_nssccap1p" )
				)
				( pin "U7C1.B29"
					( objectStatus "clkout_plat0n" )
				)
				( pin "U7C1.D29"
					( objectStatus "clkout_plat0p" )
				)
				( pin "U7C1.B40"
					( objectStatus "clkout_plat1n" )
				)
				( pin "U7C1.D40"
					( objectStatus "clkout_plat1p" )
				)
				( pin "U7C1.K38"
					( objectStatus "clkout_srcn(0)" )
				)
				( pin "U7C1.K35"
					( objectStatus "clkout_srcn(1)" )
				)
				( pin "U7C1.J33"
					( objectStatus "clkout_srcn(2)" )
				)
				( pin "U7C1.K42"
					( objectStatus "clkout_srcn(3)" )
				)
				( pin "U7C1.A28"
					( objectStatus "clkout_srcn(4)" )
				)
				( pin "U7C1.J40"
					( objectStatus "clkout_srcn(5)" )
				)
				( pin "U7C1.D33"
					( objectStatus "clkout_srcn(6)" )
				)
				( pin "U7C1.H31"
					( objectStatus "clkout_srcn(7)" )
				)
				( pin "U7C1.D31"
					( objectStatus "clkout_srcn(8)" )
				)
				( pin "U7C1.J26"
					( objectStatus "clkout_srcn(9)" )
				)
				( pin "U7C1.B23"
					( objectStatus "clkout_srcn(10)" )
				)
				( pin "U7C1.B21"
					( objectStatus "clkout_srcn(11)" )
				)
				( pin "U7C1.K24"
					( objectStatus "clkout_srcn(12)" )
				)
				( pin "U7C1.C24"
					( objectStatus "clkout_srcn(13)" )
				)
				( pin "U7C1.C20"
					( objectStatus "clkout_srcn(14)" )
				)
				( pin "U7C1.K27"
					( objectStatus "clkout_srcn(15)" )
				)
				( pin "U7C1.H38"
					( objectStatus "clkout_srcp(0)" )
				)
				( pin "U7C1.H35"
					( objectStatus "clkout_srcp(1)" )
				)
				( pin "U7C1.G33"
					( objectStatus "clkout_srcp(2)" )
				)
				( pin "U7C1.H42"
					( objectStatus "clkout_srcp(3)" )
				)
				( pin "U7C1.C28"
					( objectStatus "clkout_srcp(4)" )
				)
				( pin "U7C1.G40"
					( objectStatus "clkout_srcp(5)" )
				)
				( pin "U7C1.B33"
					( objectStatus "clkout_srcp(6)" )
				)
				( pin "U7C1.K31"
					( objectStatus "clkout_srcp(7)" )
				)
				( pin "U7C1.B31"
					( objectStatus "clkout_srcp(8)" )
				)
				( pin "U7C1.G26"
					( objectStatus "clkout_srcp(9)" )
				)
				( pin "U7C1.D23"
					( objectStatus "clkout_srcp(10)" )
				)
				( pin "U7C1.D21"
					( objectStatus "clkout_srcp(11)" )
				)
				( pin "U7C1.H24"
					( objectStatus "clkout_srcp(12)" )
				)
				( pin "U7C1.A24"
					( objectStatus "clkout_srcp(13)" )
				)
				( pin "U7C1.A20"
					( objectStatus "clkout_srcp(14)" )
				)
				( pin "U7C1.H27"
					( objectStatus "clkout_srcp(15)" )
				)
				( pin "U7C1.BW50"
					( objectStatus "clockse_bmcclk" )
				)
				( pin "U7C1.BY51"
					( objectStatus "clockse_pmsyncclk1" )
				)
				( pin "U7C1.BV51"
					( objectStatus "clockse_pmsyncclk2" )
				)
				( pin "U7C1.C26"
					( objectStatus "rsvd(64)" )
				)
				( pin "U7C1.A26"
					( objectStatus "rsvd(65)" )
				)
				( pin "U7C1.K17"
					( objectStatus "rtcx1" )
				)
				( pin "U7C1.H17"
					( objectStatus "rtcx2" )
				)
				( pin "U7C1.G44"
					( objectStatus "xclk_biasref" )
				)
				( pin "U7C1.B35"
					( objectStatus "xtal_in" )
				)
				( pin "U7C1.D35"
					( objectStatus "xtal_out" )
				)
			)
			( gate "C7C15"
				( objectStatus "@baseboard_fab2_lib.baseboard_fab2(sch_1):page114_i46" )
				( pin "C7C15.1"
					( objectStatus "a" )
				)
				( pin "C7C15.2"
					( objectStatus "b" )
				)
			)
			( gate "C7C5"
				( objectStatus "@baseboard_fab2_lib.baseboard_fab2(sch_1):page114_i47" )
				( pin "C7C5.1"
					( objectStatus "a" )
				)
				( pin "C7C5.2"
					( objectStatus "b" )
				)
			)
			( gate "R7C1"
				( objectStatus "@baseboard_fab2_lib.baseboard_fab2(sch_1):page114_i48" )
				( pin "R7C1.1"
					( objectStatus "a" )
				)
				( pin "R7C1.2"
					( objectStatus "b" )
				)
			)
			( gate "Y7C1"
				( objectStatus "@baseboard_fab2_lib.baseboard_fab2(sch_1):page114_i49" )
				( pin "Y7C1.1"
					( objectStatus "a" )
				)
				( pin "Y7C1.3"
					( objectStatus "b" )
				)
			)
			( gate "C7C4"
				( objectStatus "@baseboard_fab2_lib.baseboard_fab2(sch_1):page114_i50" )
				( pin "C7C4.1"
					( objectStatus "a" )
				)
				( pin "C7C4.2"
					( objectStatus "b" )
				)
			)
			( gate "R7C6"
				( objectStatus "@baseboard_fab2_lib.baseboard_fab2(sch_1):page114_i54" )
				( pin "R7C6.1"
					( objectStatus "a" )
				)
				( pin "R7C6.2"
					( objectStatus "b" )
				)
			)
			( gate "Y7C2"
				( objectStatus "@baseboard_fab2_lib.baseboard_fab2(sch_1):page114_i55" )
				( pin "Y7C2.1"
					( objectStatus "a" )
				)
				( pin "Y7C2.2"
					( objectStatus "b" )
				)
			)
			( gate "C7C13"
				( objectStatus "@baseboard_fab2_lib.baseboard_fab2(sch_1):page114_i56" )
				( pin "C7C13.1"
					( objectStatus "a" )
				)
				( pin "C7C13.2"
					( objectStatus "b" )
				)
			)
			( gate "R8B20"
				( objectStatus "@baseboard_fab2_lib.baseboard_fab2(sch_1):page114_i110" )
				( pin "R8B20.1"
					( objectStatus "a" )
				)
				( pin "R8B20.2"
					( objectStatus "b" )
				)
			)
			( gate "R8B21"
				( objectStatus "@baseboard_fab2_lib.baseboard_fab2(sch_1):page114_i124" )
				( pin "R8B21.1"
					( objectStatus "a" )
				)
				( pin "R8B21.2"
					( objectStatus "b" )
				)
			)
			( gate "R7C2"
				( objectStatus "@baseboard_fab2_lib.baseboard_fab2(sch_1):page114_i141" )
				( pin "R7C2.1"
					( objectStatus "a" )
				)
				( pin "R7C2.2"
					( objectStatus "b" )
				)
			)
			( gate "R7C4"
				( objectStatus "@baseboard_fab2_lib.baseboard_fab2(sch_1):page114_i142" )
				( pin "R7C4.1"
					( objectStatus "a" )
				)
				( pin "R7C4.2"
					( objectStatus "b" )
				)
			)
			( gate "R3N1"
				( objectStatus "@baseboard_fab2_lib.baseboard_fab2(sch_1):page114_i149" )
				( pin "R3N1.1"
					( objectStatus "a" )
				)
				( pin "R3N1.2"
					( objectStatus "b" )
				)
			)
			( gate "U7C1"
				( objectStatus "@baseboard_fab2_lib.baseboard_fab2(sch_1):page115_i74" )
				( pin "U7C1.BN68"
					( objectStatus "rsvd(55)" )
				)
				( pin "U7C1.BN70"
					( objectStatus "usb2_comp" )
				)
				( pin "U7C1.BR67"
					( objectStatus "usb2_vbus" )
				)
				( pin "U7C1.BY60"
					( objectStatus "usb2n_1" )
				)
				( pin "U7C1.CA61"
					( objectStatus "usb2n_2" )
				)
				( pin "U7C1.CA59"
					( objectStatus "usb2n_3" )
				)
				( pin "U7C1.BY62"
					( objectStatus "usb2n_4" )
				)
				( pin "U7C1.BY58"
					( objectStatus "usb2n_5" )
				)
				( pin "U7C1.CA63"
					( objectStatus "usb2n_6" )
				)
				( pin "U7C1.CA57"
					( objectStatus "usb2n_7" )
				)
				( pin "U7C1.BY64"
					( objectStatus "usb2n_8" )
				)
				( pin "U7C1.BY55"
					( objectStatus "usb2n_9" )
				)
				( pin "U7C1.BW65"
					( objectStatus "usb2n_10" )
				)
				( pin "U7C1.CA54"
					( objectStatus "usb2n_11" )
				)
				( pin "U7C1.BW67"
					( objectStatus "usb2n_12" )
				)
				( pin "U7C1.BY53"
					( objectStatus "usb2n_13" )
				)
				( pin "U7C1.BW68"
					( objectStatus "usb2n_14" )
				)
				( pin "U7C1.BV60"
					( objectStatus "usb2p_1" )
				)
				( pin "U7C1.BW61"
					( objectStatus "usb2p_2" )
				)
				( pin "U7C1.BW59"
					( objectStatus "usb2p_3" )
				)
				( pin "U7C1.BV62"
					( objectStatus "usb2p_4" )
				)
				( pin "U7C1.BV58"
					( objectStatus "usb2p_5" )
				)
				( pin "U7C1.BW63"
					( objectStatus "usb2p_6" )
				)
				( pin "U7C1.BW57"
					( objectStatus "usb2p_7" )
				)
				( pin "U7C1.BV64"
					( objectStatus "usb2p_8" )
				)
				( pin "U7C1.BV55"
					( objectStatus "usb2p_9" )
				)
				( pin "U7C1.BU65"
					( objectStatus "usb2p_10" )
				)
				( pin "U7C1.BW54"
					( objectStatus "usb2p_11" )
				)
				( pin "U7C1.BV66"
					( objectStatus "usb2p_12" )
				)
				( pin "U7C1.BV53"
					( objectStatus "usb2p_13" )
				)
				( pin "U7C1.BU67"
					( objectStatus "usb2p_14" )
				)
				( pin "U7C1.BK71"
					( objectStatus "usb3_1_rxn" )
				)
				( pin "U7C1.BK69"
					( objectStatus "usb3_1_rxp" )
				)
				( pin "U7C1.BL52"
					( objectStatus "usb3_1_txn" )
				)
				( pin "U7C1.BK54"
					( objectStatus "usb3_1_txp" )
				)
				( pin "U7C1.BJ72"
					( objectStatus "usb3_2_rxn" )
				)
				( pin "U7C1.BJ70"
					( objectStatus "usb3_2_rxp" )
				)
				( pin "U7C1.BL56"
					( objectStatus "usb3_2_txn" )
				)
				( pin "U7C1.BJ56"
					( objectStatus "usb3_2_txp" )
				)
				( pin "U7C1.BH71"
					( objectStatus "usb3_3_rxn" )
				)
				( pin "U7C1.BH69"
					( objectStatus "usb3_3_rxp" )
				)
				( pin "U7C1.BM54"
					( objectStatus "usb3_3_txn" )
				)
				( pin "U7C1.BN56"
					( objectStatus "usb3_3_txp" )
				)
				( pin "U7C1.BF72"
					( objectStatus "usb3_4_rxn" )
				)
				( pin "U7C1.BF70"
					( objectStatus "usb3_4_rxp" )
				)
				( pin "U7C1.BH58"
					( objectStatus "usb3_4_txn" )
				)
				( pin "U7C1.BG56"
					( objectStatus "usb3_4_txp" )
				)
				( pin "U7C1.BE71"
					( objectStatus "usb3_5_rxn" )
				)
				( pin "U7C1.BE69"
					( objectStatus "usb3_5_rxp" )
				)
				( pin "U7C1.BK58"
					( objectStatus "usb3_5_txn" )
				)
				( pin "U7C1.BJ59"
					( objectStatus "usb3_5_txp" )
				)
				( pin "U7C1.BD72"
					( objectStatus "usb3_6_rxn" )
				)
				( pin "U7C1.BD70"
					( objectStatus "usb3_6_rxp" )
				)
				( pin "U7C1.BL59"
					( objectStatus "usb3_6_txn" )
				)
				( pin "U7C1.BM61"
					( objectStatus "usb3_6_txp" )
				)
			)
			( gate "R8B9"
				( objectStatus "@baseboard_fab2_lib.baseboard_fab2(sch_1):page115_i90" )
				( pin "R8B9.1"
					( objectStatus "a" )
				)
				( pin "R8B9.2"
					( objectStatus "b" )
				)
			)
			( gate "R22"
				( objectStatus "@baseboard_fab2_lib.baseboard_fab2(sch_1):page115_i114" )
				( pin "R22.1"
					( objectStatus "a" )
				)
				( pin "R22.2"
					( objectStatus "b" )
				)
			)
			( gate "R3M11"
				( objectStatus "@baseboard_fab2_lib.baseboard_fab2(sch_1):page116_i108" )
				( pin "R3M11.1"
					( objectStatus "a" )
				)
				( pin "R3M11.2"
					( objectStatus "b" )
				)
			)
			( gate "R3M12"
				( objectStatus "@baseboard_fab2_lib.baseboard_fab2(sch_1):page116_i181" )
				( pin "R3M12.1"
					( objectStatus "a" )
				)
				( pin "R3M12.2"
					( objectStatus "b" )
				)
			)
			( gate "C2M4"
				( objectStatus "@baseboard_fab2_lib.baseboard_fab2(sch_1):page116_i182" )
				( pin "C2M4.1"
					( objectStatus "a" )
				)
				( pin "C2M4.2"
					( objectStatus "b" )
				)
			)
			( gate "C2M3"
				( objectStatus "@baseboard_fab2_lib.baseboard_fab2(sch_1):page116_i183" )
				( pin "C2M3.1"
					( objectStatus "a" )
				)
				( pin "C2M3.2"
					( objectStatus "b" )
				)
			)
			( gate "U7C1"
				( objectStatus "@baseboard_fab2_lib.baseboard_fab2(sch_1):page116_i220" )
				( pin "U7C1.D66"
					( objectStatus "extclkn" )
				)
				( pin "U7C1.E67"
					( objectStatus "extclkp" )
				)
				( pin "U7C1.AN70"
					( objectStatus "pcie4_gbe_rxn" )
				)
				( pin "U7C1.AN72"
					( objectStatus "pcie4_gbe_rxp" )
				)
				( pin "U7C1.BG66"
					( objectStatus "pcie4_gbe_txn" )
				)
				( pin "U7C1.BJ66"
					( objectStatus "pcie4_gbe_txp" )
				)
				( pin "U7C1.AM69"
					( objectStatus "pcie5_gbe_rxn" )
				)
				( pin "U7C1.AM71"
					( objectStatus "pcie5_gbe_rxp" )
				)
				( pin "U7C1.BH65"
					( objectStatus "pcie5_gbe_txn" )
				)
				( pin "U7C1.BJ63"
					( objectStatus "pcie5_gbe_txp" )
				)
				( pin "U7C1.BB63"
					( objectStatus "pcie6_ssata0_rxn" )
				)
				( pin "U7C1.BD61"
					( objectStatus "pcie6_ssata0_rxp" )
				)
				( pin "U7C1.AJ70"
					( objectStatus "pcie6_ssata0_txn" )
				)
				( pin "U7C1.AJ72"
					( objectStatus "pcie6_ssata0_txp" )
				)
				( pin "U7C1.AY59"
					( objectStatus "pcie7_ssata1_rxn" )
				)
				( pin "U7C1.BA61"
					( objectStatus "pcie7_ssata1_rxp" )
				)
				( pin "U7C1.AH69"
					( objectStatus "pcie7_ssata1_txn" )
				)
				( pin "U7C1.AH71"
					( objectStatus "pcie7_ssata1_txp" )
				)
				( pin "U7C1.BA65"
					( objectStatus "pcie8_ssata2_gbe_rxn" )
				)
				( pin "U7C1.BD65"
					( objectStatus "pcie8_ssata2_gbe_rxp" )
				)
				( pin "U7C1.AF70"
					( objectStatus "pcie8_ssata2_gbe_txn" )
				)
				( pin "U7C1.AF72"
					( objectStatus "pcie8_ssata2_gbe_txp" )
				)
				( pin "U7C1.AW65"
					( objectStatus "pcie9_ssata3_rxn" )
				)
				( pin "U7C1.AY66"
					( objectStatus "pcie9_ssata3_rxp" )
				)
				( pin "U7C1.AE69"
					( objectStatus "pcie9_ssata3_txn" )
				)
				( pin "U7C1.AE71"
					( objectStatus "pcie9_ssata3_txp" )
				)
				( pin "U7C1.AV63"
					( objectStatus "pcie10_ssata4_rxn" )
				)
				( pin "U7C1.AU65"
					( objectStatus "pcie10_ssata4_rxp" )
				)
				( pin "U7C1.AD70"
					( objectStatus "pcie10_ssata4_txn" )
				)
				( pin "U7C1.AD72"
					( objectStatus "pcie10_ssata4_txp" )
				)
				( pin "U7C1.AT66"
					( objectStatus "pcie11_ssata5_gbe_rxn" )
				)
				( pin "U7C1.AV66"
					( objectStatus "pcie11_ssata5_gbe_rxp" )
				)
				( pin "U7C1.AC69"
					( objectStatus "pcie11_ssata5_gbe_txn" )
				)
				( pin "U7C1.AC71"
					( objectStatus "pcie11_ssata5_gbe_txp" )
				)
				( pin "U7C1.AR61"
					( objectStatus "pcie12_up0_sata0_rxn" )
				)
				( pin "U7C1.AT63"
					( objectStatus "pcie12_up0_sata0_rxp" )
				)
				( pin "U7C1.W69"
					( objectStatus "pcie12_up0_sata0_txn" )
				)
				( pin "U7C1.W71"
					( objectStatus "pcie12_up0_sata0_txp" )
				)
				( pin "U7C1.AL66"
					( objectStatus "pcie13_up1_sata1_rxn" )
				)
				( pin "U7C1.AN65"
					( objectStatus "pcie13_up1_sata1_rxp" )
				)
				( pin "U7C1.V70"
					( objectStatus "pcie13_up1_sata1_txn" )
				)
				( pin "U7C1.V72"
					( objectStatus "pcie13_up1_sata1_txp" )
				)
				( pin "U7C1.AK65"
					( objectStatus "pcie14_up2_sata2_rxn" )
				)
				( pin "U7C1.AJ63"
					( objectStatus "pcie14_up2_sata2_rxp" )
				)
				( pin "U7C1.T69"
					( objectStatus "pcie14_up2_sata2_txn" )
				)
				( pin "U7C1.T71"
					( objectStatus "pcie14_up2_sata2_txp" )
				)
				( pin "U7C1.AP63"
					( objectStatus "pcie15_up3_sata3_rxn" )
				)
				( pin "U7C1.AL63"
					( objectStatus "pcie15_up3_sata3_rxp" )
				)
				( pin "U7C1.R70"
					( objectStatus "pcie15_up3_sata3_txn" )
				)
				( pin "U7C1.R72"
					( objectStatus "pcie15_up3_sata3_txp" )
				)
				( pin "U7C1.AF65"
					( objectStatus "pcie16_up4_sata4_rxn" )
				)
				( pin "U7C1.AH65"
					( objectStatus "pcie16_up4_sata4_rxp" )
				)
				( pin "U7C1.P69"
					( objectStatus "pcie16_up4_sata4_txn" )
				)
				( pin "U7C1.P71"
					( objectStatus "pcie16_up4_sata4_txp" )
				)
				( pin "U7C1.AH61"
					( objectStatus "pcie17_up5_sata5_rxn" )
				)
				( pin "U7C1.AG63"
					( objectStatus "pcie17_up5_sata5_rxp" )
				)
				( pin "U7C1.N70"
					( objectStatus "pcie17_up5_sata5_txn" )
				)
				( pin "U7C1.N72"
					( objectStatus "pcie17_up5_sata5_txp" )
				)
				( pin "U7C1.AP59"
					( objectStatus "pcie18_up6_sata6_rxn" )
				)
				( pin "U7C1.AN61"
					( objectStatus "pcie18_up6_sata6_rxp" )
				)
				( pin "U7C1.M69"
					( objectStatus "pcie18_up6_sata6_txn" )
				)
				( pin "U7C1.M71"
					( objectStatus "pcie18_up6_sata6_txp" )
				)
				( pin "U7C1.AA61"
					( objectStatus "pcie19_up7_sata7_rxn" )
				)
				( pin "U7C1.AD61"
					( objectStatus "pcie19_up7_sata7_rxp" )
				)
				( pin "U7C1.L70"
					( objectStatus "pcie19_up7_sata7_txn" )
				)
				( pin "U7C1.L72"
					( objectStatus "pcie19_up7_sata7_txp" )
				)
				( pin "U7C1.BD58"
					( objectStatus "pcie_rcompn" )
				)
				( pin "U7C1.BB56"
					( objectStatus "pcie_rcompp" )
				)
				( pin "U7C1.AF58"
					( objectStatus "pcieup_rcompn" )
				)
				( pin "U7C1.AH58"
					( objectStatus "pcieup_rcompp" )
				)
				( pin "U7C1.AP69"
					( objectStatus "rsvd(47)" )
				)
				( pin "U7C1.AP71"
					( objectStatus "rsvd(48)" )
				)
				( pin "U7C1.G67"
					( objectStatus "rsvd(49)" )
				)
				( pin "U7C1.H69"
					( objectStatus "rsvd(50)" )
				)
				( pin "U7C1.AA69"
					( objectStatus "rsvd(51)" )
				)
				( pin "U7C1.AA71"
					( objectStatus "rsvd(52)" )
				)
				( pin "U7C1.BA71"
					( objectStatus "usb3_7_pcie0_rxn" )
				)
				( pin "U7C1.BA69"
					( objectStatus "usb3_7_pcie0_rxp" )
				)
				( pin "U7C1.BR61"
					( objectStatus "usb3_7_pcie0_txn" )
				)
				( pin "U7C1.BN63"
					( objectStatus "usb3_7_pcie0_txp" )
				)
				( pin "U7C1.AY72"
					( objectStatus "usb3_8_pcie1_rxn" )
				)
				( pin "U7C1.AY70"
					( objectStatus "usb3_8_pcie1_rxp" )
				)
				( pin "U7C1.BM65"
					( objectStatus "usb3_8_pcie1_txn" )
				)
				( pin "U7C1.BR65"
					( objectStatus "usb3_8_pcie1_txp" )
				)
				( pin "U7C1.AW71"
					( objectStatus "usb3_9_pcie2_rxn" )
				)
				( pin "U7C1.AW69"
					( objectStatus "usb3_9_pcie2_rxp" )
				)
				( pin "U7C1.BK65"
					( objectStatus "usb3_9_pcie2_txn" )
				)
				( pin "U7C1.BL66"
					( objectStatus "usb3_9_pcie2_txp" )
				)
				( pin "U7C1.AV72"
					( objectStatus "usb3_10_pcie3_gbe_rxn" )
				)
				( pin "U7C1.AV70"
					( objectStatus "usb3_10_pcie3_gbe_rxp" )
				)
				( pin "U7C1.BH61"
					( objectStatus "usb3_10_pcie3_gbe_txn" )
				)
				( pin "U7C1.BK61"
					( objectStatus "usb3_10_pcie3_gbe_txp" )
				)
			)
			( gate "R7B8"
				( objectStatus "@baseboard_fab2_lib.baseboard_fab2(sch_1):page116_i229" )
				( pin "R7B8.1"
					( objectStatus "a" )
				)
				( pin "R7B8.2"
					( objectStatus "b" )
				)
			)
			( gate "R7B7"
				( objectStatus "@baseboard_fab2_lib.baseboard_fab2(sch_1):page116_i230" )
				( pin "R7B7.1"
					( objectStatus "a" )
				)
				( pin "R7B7.2"
					( objectStatus "b" )
				)
			)
			( gate "R3M9"
				( objectStatus "@baseboard_fab2_lib.baseboard_fab2(sch_1):page116_i234" )
				( pin "R3M9.1"
					( objectStatus "a" )
				)
				( pin "R3M9.2"
					( objectStatus "b" )
				)
			)
			( gate "R3M8"
				( objectStatus "@baseboard_fab2_lib.baseboard_fab2(sch_1):page116_i235" )
				( pin "R3M8.1"
					( objectStatus "a" )
				)
				( pin "R3M8.2"
					( objectStatus "b" )
				)
			)
			( gate "U7C1"
				( objectStatus "@baseboard_fab2_lib.baseboard_fab2(sch_1):page117_i9" )
				( pin "U7C1.D42"
					( objectStatus "dmi_rxn(0)" )
				)
				( pin "U7C1.C43"
					( objectStatus "dmi_rxn(1)" )
				)
				( pin "U7C1.D44"
					( objectStatus "dmi_rxn(2)" )
				)
				( pin "U7C1.C45"
					( objectStatus "dmi_rxn(3)" )
				)
				( pin "U7C1.B42"
					( objectStatus "dmi_rxp(0)" )
				)
				( pin "U7C1.A43"
					( objectStatus "dmi_rxp(1)" )
				)
				( pin "U7C1.B44"
					( objectStatus "dmi_rxp(2)" )
				)
				( pin "U7C1.A45"
					( objectStatus "dmi_rxp(3)" )
				)
				( pin "U7C1.H46"
					( objectStatus "dmi_txn(0)" )
				)
				( pin "U7C1.J48"
					( objectStatus "dmi_txn(1)" )
				)
				( pin "U7C1.K50"
					( objectStatus "dmi_txn(2)" )
				)
				( pin "U7C1.P52"
					( objectStatus "dmi_txn(3)" )
				)
				( pin "U7C1.K46"
					( objectStatus "dmi_txp(0)" )
				)
				( pin "U7C1.H50"
					( objectStatus "dmi_txp(1)" )
				)
				( pin "U7C1.M52"
					( objectStatus "dmi_txp(2)" )
				)
				( pin "U7C1.N54"
					( objectStatus "dmi_txp(3)" )
				)
				( pin "U7C1.C48"
					( objectStatus "pcieup_0_rxn" )
				)
				( pin "U7C1.A48"
					( objectStatus "pcieup_0_rxp" )
				)
				( pin "U7C1.J52"
					( objectStatus "pcieup_0_txn" )
				)
				( pin "U7C1.G52"
					( objectStatus "pcieup_0_txp" )
				)
				( pin "U7C1.D49"
					( objectStatus "pcieup_1_rxn" )
				)
				( pin "U7C1.B49"
					( objectStatus "pcieup_1_rxp" )
				)
				( pin "U7C1.P56"
					( objectStatus "pcieup_1_txn" )
				)
				( pin "U7C1.M56"
					( objectStatus "pcieup_1_txp" )
				)
				( pin "U7C1.C50"
					( objectStatus "pcieup_2_rxn" )
				)
				( pin "U7C1.A50"
					( objectStatus "pcieup_2_rxp" )
				)
				( pin "U7C1.H54"
					( objectStatus "pcieup_2_txn" )
				)
				( pin "U7C1.G56"
					( objectStatus "pcieup_2_txp" )
				)
				( pin "U7C1.D51"
					( objectStatus "pcieup_3_rxn" )
				)
				( pin "U7C1.B51"
					( objectStatus "pcieup_3_rxp" )
				)
				( pin "U7C1.J56"
					( objectStatus "pcieup_3_txn" )
				)
				( pin "U7C1.K58"
					( objectStatus "pcieup_3_txp" )
				)
				( pin "U7C1.C52"
					( objectStatus "pcieup_4_rxn" )
				)
				( pin "U7C1.A52"
					( objectStatus "pcieup_4_rxp" )
				)
				( pin "U7C1.N58"
					( objectStatus "pcieup_4_txn" )
				)
				( pin "U7C1.M59"
					( objectStatus "pcieup_4_txp" )
				)
				( pin "U7C1.D53"
					( objectStatus "pcieup_5_rxn" )
				)
				( pin "U7C1.B53"
					( objectStatus "pcieup_5_rxp" )
				)
				( pin "U7C1.N61"
					( objectStatus "pcieup_5_txn" )
				)
				( pin "U7C1.K61"
					( objectStatus "pcieup_5_txp" )
				)
				( pin "U7C1.C54"
					( objectStatus "pcieup_6_rxn" )
				)
				( pin "U7C1.A54"
					( objectStatus "pcieup_6_rxp" )
				)
				( pin "U7C1.H61"
					( objectStatus "pcieup_6_txn" )
				)
				( pin "U7C1.J63"
					( objectStatus "pcieup_6_txp" )
				)
				( pin "U7C1.D55"
					( objectStatus "pcieup_7_rxn" )
				)
				( pin "U7C1.B55"
					( objectStatus "pcieup_7_rxp" )
				)
				( pin "U7C1.P59"
					( objectStatus "pcieup_7_txn" )
				)
				( pin "U7C1.R61"
					( objectStatus "pcieup_7_txp" )
				)
				( pin "U7C1.C57"
					( objectStatus "pcieup_8_rxn" )
				)
				( pin "U7C1.A57"
					( objectStatus "pcieup_8_rxp" )
				)
				( pin "U7C1.K65"
					( objectStatus "pcieup_8_txn" )
				)
				( pin "U7C1.M63"
					( objectStatus "pcieup_8_txp" )
				)
				( pin "U7C1.D58"
					( objectStatus "pcieup_9_rxn" )
				)
				( pin "U7C1.B58"
					( objectStatus "pcieup_9_rxp" )
				)
				( pin "U7C1.J66"
					( objectStatus "pcieup_9_txn" )
				)
				( pin "U7C1.M66"
					( objectStatus "pcieup_9_txp" )
				)
				( pin "U7C1.C59"
					( objectStatus "pcieup_10_rxn" )
				)
				( pin "U7C1.A59"
					( objectStatus "pcieup_10_rxp" )
				)
				( pin "U7C1.N65"
					( objectStatus "pcieup_10_txn" )
				)
				( pin "U7C1.P66"
					( objectStatus "pcieup_10_txp" )
				)
				( pin "U7C1.D60"
					( objectStatus "pcieup_11_rxn" )
				)
				( pin "U7C1.B60"
					( objectStatus "pcieup_11_rxp" )
				)
				( pin "U7C1.T59"
					( objectStatus "pcieup_11_txn" )
				)
				( pin "U7C1.V59"
					( objectStatus "pcieup_11_txp" )
				)
				( pin "U7C1.C61"
					( objectStatus "pcieup_12_rxn" )
				)
				( pin "U7C1.A61"
					( objectStatus "pcieup_12_rxp" )
				)
				( pin "U7C1.R65"
					( objectStatus "pcieup_12_txn" )
				)
				( pin "U7C1.U65"
					( objectStatus "pcieup_12_txp" )
				)
				( pin "U7C1.D62"
					( objectStatus "pcieup_13_rxn" )
				)
				( pin "U7C1.B62"
					( objectStatus "pcieup_13_rxp" )
				)
				( pin "U7C1.T63"
					( objectStatus "pcieup_13_txn" )
				)
				( pin "U7C1.U61"
					( objectStatus "pcieup_13_txp" )
				)
				( pin "U7C1.C63"
					( objectStatus "pcieup_14_rxn" )
				)
				( pin "U7C1.A63"
					( objectStatus "pcieup_14_rxp" )
				)
				( pin "U7C1.W65"
					( objectStatus "pcieup_14_txn" )
				)
				( pin "U7C1.V63"
					( objectStatus "pcieup_14_txp" )
				)
				( pin "U7C1.D64"
					( objectStatus "pcieup_15_rxn" )
				)
				( pin "U7C1.B64"
					( objectStatus "pcieup_15_rxp" )
				)
				( pin "U7C1.Y66"
					( objectStatus "pcieup_15_txn" )
				)
				( pin "U7C1.AA65"
					( objectStatus "pcieup_15_txp" )
				)
			)
			( gate "R3N9"
				( objectStatus "@baseboard_fab2_lib.baseboard_fab2(sch_1):page118_i66" )
				( pin "R3N9.1"
					( objectStatus "a" )
				)
				( pin "R3N9.2"
					( objectStatus "b" )
				)
			)
			( gate "R3N14"
				( objectStatus "@baseboard_fab2_lib.baseboard_fab2(sch_1):page118_i67" )
				( pin "R3N14.1"
					( objectStatus "a" )
				)
				( pin "R3N14.2"
					( objectStatus "b" )
				)
			)
			( gate "R3N13"
				( objectStatus "@baseboard_fab2_lib.baseboard_fab2(sch_1):page118_i71" )
				( pin "R3N13.1"
					( objectStatus "a" )
				)
				( pin "R3N13.2"
					( objectStatus "b" )
				)
			)
			( gate "U7C1"
				( objectStatus "@baseboard_fab2_lib.baseboard_fab2(sch_1):page118_i73" )
				( pin "U7C1.AT56"
					( objectStatus "cpu_trst_n" )
				)
				( pin "U7C1.K13"
					( objectStatus "dsw_pwrok" )
				)
				( pin "U7C1.G15"
					( objectStatus "gpd0" )
				)
				( pin "U7C1.H13"
					( objectStatus "gpd1_acpresent" )
				)
				( pin "U7C1.M11"
					( objectStatus "gpd2_gbe_wake_n" )
				)
				( pin "U7C1.C15"
					( objectStatus "gpd3_pwrbtn_n" )
				)
				( pin "U7C1.D14"
					( objectStatus "gpd4_slp_s3_n" )
				)
				( pin "U7C1.B16"
					( objectStatus "gpd5_slp_s4_n" )
				)
				( pin "U7C1.G11"
					( objectStatus "gpd6_slp_a_n" )
				)
				( pin "U7C1.H9"
					( objectStatus "gpd7" )
				)
				( pin "U7C1.C13"
					( objectStatus "gpd8_susclk" )
				)
				( pin "U7C1.A15"
					( objectStatus "gpd9" )
				)
				( pin "U7C1.B14"
					( objectStatus "gpd10_slp_s5_n" )
				)
				( pin "U7C1.A13"
					( objectStatus "gpd11_gbephy" )
				)
				( pin "U7C1.AR54"
					( objectStatus "itp_pmode" )
				)
				( pin "U7C1.AL56"
					( objectStatus "jtag_tck" )
				)
				( pin "U7C1.AN54"
					( objectStatus "jtag_tdi" )
				)
				( pin "U7C1.AP56"
					( objectStatus "jtag_tdo" )
				)
				( pin "U7C1.AH54"
					( objectStatus "jtag_tms" )
				)
				( pin "U7C1.AF54"
					( objectStatus "jtagx" )
				)
				( pin "U7C1.BB29"
					( objectStatus "lan_rbias_0" )
				)
				( pin "U7C1.BD42"
					( objectStatus "lan_rbias_1" )
				)
				( pin "U7C1.BH31"
					( objectStatus "lan_rx_p0n" )
				)
				( pin "U7C1.BF31"
					( objectStatus "lan_rx_p0p" )
				)
				( pin "U7C1.BG29"
					( objectStatus "lan_rx_p1n" )
				)
				( pin "U7C1.BJ29"
					( objectStatus "lan_rx_p1p" )
				)
				( pin "U7C1.BJ37"
					( objectStatus "lan_rx_p2n" )
				)
				( pin "U7C1.BG37"
					( objectStatus "lan_rx_p2p" )
				)
				( pin "U7C1.BF35"
					( objectStatus "lan_rx_p3n" )
				)
				( pin "U7C1.BH35"
					( objectStatus "lan_rx_p3p" )
				)
				( pin "U7C1.BM27"
					( objectStatus "lan_tx_p0n" )
				)
				( pin "U7C1.BR27"
					( objectStatus "lan_tx_p0p" )
				)
				( pin "U7C1.BM24"
					( objectStatus "lan_tx_p1n" )
				)
				( pin "U7C1.BR24"
					( objectStatus "lan_tx_p1p" )
				)
				( pin "U7C1.BM35"
					( objectStatus "lan_tx_p2n" )
				)
				( pin "U7C1.BR35"
					( objectStatus "lan_tx_p2p" )
				)
				( pin "U7C1.BR31"
					( objectStatus "lan_tx_p3n" )
				)
				( pin "U7C1.BM31"
					( objectStatus "lan_tx_p3p" )
				)
				( pin "U7C1.BV16"
					( objectStatus "lan_xtal_in" )
				)
				( pin "U7C1.BY16"
					( objectStatus "lan_xtal_out" )
				)
				( pin "U7C1.R17"
					( objectStatus "pch_pwrok" )
				)
				( pin "U7C1.U9"
					( objectStatus "peci" )
				)
				( pin "U7C1.U17"
					( objectStatus "pltrst_cpu_n" )
				)
				( pin "U7C1.U13"
					( objectStatus "pm_sync" )
				)
				( pin "U7C1.V7"
					( objectStatus "pm_sync2" )
				)
				( pin "U7C1.AD54"
					( objectStatus "prdy_n" )
				)
				( pin "U7C1.U54"
					( objectStatus "preq_n" )
				)
				( pin "U7C1.R9"
					( objectStatus "proc_pwrgd" )
				)
				( pin "U7C1.P15"
					( objectStatus "rsmrst_n" )
				)
				( pin "U7C1.AA54"
					( objectStatus "rsvd(32)" )
				)
				( pin "U7C1.V56"
					( objectStatus "rsvd(33)" )
				)
				( pin "U7C1.Y56"
					( objectStatus "rsvd(34)" )
				)
				( pin "U7C1.W54"
					( objectStatus "rsvd(35)" )
				)
				( pin "U7C1.AK54"
					( objectStatus "rsvd(36)" )
				)
				( pin "U7C1.BN29"
					( objectStatus "rsvd(37)" )
				)
				( pin "U7C1.BL29"
					( objectStatus "rsvd(38)" )
				)
				( pin "U7C1.BL26"
					( objectStatus "rsvd(39)" )
				)
				( pin "U7C1.BN26"
					( objectStatus "rsvd(40)" )
				)
				( pin "U7C1.BJ40"
					( objectStatus "rsvd(41)" )
				)
				( pin "U7C1.BG40"
					( objectStatus "rsvd(42)" )
				)
				( pin "U7C1.BL33"
					( objectStatus "rsvd(43)" )
				)
				( pin "U7C1.BN33"
					( objectStatus "rsvd(44)" )
				)
				( pin "U7C1.P22"
					( objectStatus "rsvd(45)" )
				)
				( pin "U7C1.P26"
					( objectStatus "rsvd(53)" )
				)
				( pin "U7C1.R24"
					( objectStatus "rsvd(54)" )
				)
				( pin "U7C1.M15"
					( objectStatus "slp_gbe_n" )
				)
				( pin "U7C1.P7"
					( objectStatus "slp_sus_n" )
				)
				( pin "U7C1.BY19"
					( objectStatus "sys_pwrok" )
				)
				( pin "U7C1.BV19"
					( objectStatus "sys_reset_n" )
				)
				( pin "U7C1.V15"
					( objectStatus "thrmtrip_n" )
				)
				( pin "U7C1.M7"
					( objectStatus "trigger_in" )
				)
				( pin "U7C1.R13"
					( objectStatus "trigger_out" )
				)
				( pin "U7C1.K9"
					( objectStatus "wake_n" )
				)
			)
			( gate "Y8C1"
				( objectStatus "@baseboard_fab2_lib.baseboard_fab2(sch_1):page118_i76" )
				( pin "Y8C1.1"
					( objectStatus "a" )
				)
				( pin "Y8C1.3"
					( objectStatus "b" )
				)
			)
			( gate "C8C2"
				( objectStatus "@baseboard_fab2_lib.baseboard_fab2(sch_1):page118_i77" )
				( pin "C8C2.1"
					( objectStatus "a" )
				)
				( pin "C8C2.2"
					( objectStatus "b" )
				)
			)
			( gate "C8C1"
				( objectStatus "@baseboard_fab2_lib.baseboard_fab2(sch_1):page118_i79" )
				( pin "C8C1.1"
					( objectStatus "a" )
				)
				( pin "C8C1.2"
					( objectStatus "b" )
				)
			)
			( gate "R2N4"
				( objectStatus "@baseboard_fab2_lib.baseboard_fab2(sch_1):page118_i96" )
				( pin "R2N4.1"
					( objectStatus "a" )
				)
				( pin "R2N4.2"
					( objectStatus "b" )
				)
			)
			( gate "R2M6"
				( objectStatus "@baseboard_fab2_lib.baseboard_fab2(sch_1):page118_i99" )
				( pin "R2M6.1"
					( objectStatus "a" )
				)
				( pin "R2M6.2"
					( objectStatus "b" )
				)
			)
			( gate "R8C24"
				( objectStatus "@baseboard_fab2_lib.baseboard_fab2(sch_1):page118_i120" )
				( pin "R8C24.1"
					( objectStatus "a" )
				)
				( pin "R8C24.2"
					( objectStatus "b" )
				)
			)
			( gate "R8C23"
				( objectStatus "@baseboard_fab2_lib.baseboard_fab2(sch_1):page118_i125" )
				( pin "R8C23.1"
					( objectStatus "a" )
				)
				( pin "R8C23.2"
					( objectStatus "b" )
				)
			)
			( gate "R2N6"
				( objectStatus "@baseboard_fab2_lib.baseboard_fab2(sch_1):page118_i128" )
				( pin "R2N6.1"
					( objectStatus "a" )
				)
				( pin "R2N6.2"
					( objectStatus "b" )
				)
			)
			( gate "R7D23"
				( objectStatus "@baseboard_fab2_lib.baseboard_fab2(sch_1):page118_i131" )
				( pin "R7D23.1"
					( objectStatus "a" )
				)
				( pin "R7D23.2"
					( objectStatus "b" )
				)
			)
			( gate "C7D1"
				( objectStatus "@baseboard_fab2_lib.baseboard_fab2(sch_1):page118_i136" )
				( pin "C7D1.1"
					( objectStatus "a" )
				)
				( pin "C7D1.2"
					( objectStatus "b" )
				)
			)
			( gate "U7D1"
				( objectStatus "@baseboard_fab2_lib.baseboard_fab2(sch_1):page118_i142" )
				( pin "U7D1.2"
					( objectStatus "a" )
				)
				( pin "U7D1.4"
					( objectStatus "b" )
				)
				( pin "U7D1.1"
					( objectStatus "oe_n" )
				)
			)
			( gate "R7C23"
				( objectStatus "@baseboard_fab2_lib.baseboard_fab2(sch_1):page118_i144" )
				( pin "R7C23.1"
					( objectStatus "a" )
				)
				( pin "R7C23.2"
					( objectStatus "b" )
				)
			)
			( gate "U7C1"
				( objectStatus "@baseboard_fab2_lib.baseboard_fab2(sch_1):page119_i115" )
				( pin "U7C1.N3"
					( objectStatus "gpp_a0_rcin_n_espi_alert1_n" )
				)
				( pin "U7C1.Y3"
					( objectStatus "gpp_a1_lad0_espi_io0" )
				)
				( pin "U7C1.N1"
					( objectStatus "gpp_a2_lad1_espi_io1" )
				)
				( pin "U7C1.W2"
					( objectStatus "gpp_a3_lad2_espi_io2" )
				)
				( pin "U7C1.Y1"
					( objectStatus "gpp_a4_lad3_espi_io3" )
				)
				( pin "U7C1.P4"
					( objectStatus "gpp_a5_lframe_n_espi_cs0_n" )
				)
				( pin "U7C1.P2"
					( objectStatus "gpp_a6_serirq_espi_cs1_n" )
				)
				( pin "U7C1.AA2"
					( objectStatus "gpp_a7_pirqa_n_espi_alert0_n" )
				)
				( pin "U7C1.AB1"
					( objectStatus "gpp_a8_clkrun_n" )
				)
				( pin "U7C1.R3"
					( objectStatus "gpp_a9_clkout_lpc0_espi_clk" )
				)
				( pin "U7C1.AA4"
					( objectStatus "gpp_a10_clkout_lpc1" )
				)
				( pin "U7C1.AC2"
					( objectStatus "gpp_a11_pme_n" )
				)
				( pin "U7C1.R1"
					( objectStatus "gpp_a12_bmbusy_n_sxexithldoff_n" )
				)
				( pin "U7C1.T4"
					( objectStatus "gpp_a13_suswarn_n_suspwrdnack" )
				)
				( pin "U7C1.AB3"
					( objectStatus "gpp_a14_espi_reset_n" )
				)
				( pin "U7C1.AC4"
					( objectStatus "gpp_a15_susack_n" )
				)
				( pin "U7C1.T2"
					( objectStatus "gpp_a16_clkout_lpc2" )
				)
				( pin "U7C1.AD1"
					( objectStatus "gpp_a17" )
				)
				( pin "U7C1.AD3"
					( objectStatus "gpp_a18" )
				)
				( pin "U7C1.V3"
					( objectStatus "gpp_a19" )
				)
				( pin "U7C1.W4"
					( objectStatus "gpp_a20" )
				)
				( pin "U7C1.AE2"
					( objectStatus "gpp_a21" )
				)
				( pin "U7C1.AE4"
					( objectStatus "gpp_a22" )
				)
				( pin "U7C1.V1"
					( objectStatus "gpp_a23" )
				)
				( pin "U7C1.BL7"
					( objectStatus "gpp_b0_core_vid0" )
				)
				( pin "U7C1.BH9"
					( objectStatus "gpp_b1_core_vid1" )
				)
				( pin "U7C1.BN15"
					( objectStatus "gpp_b2" )
				)
				( pin "U7C1.BR9"
					( objectStatus "gpp_b3_cpu_gp2" )
				)
				( pin "U7C1.BN7"
					( objectStatus "gpp_b4_cpu_gp3" )
				)
				( pin "U7C1.BK17"
					( objectStatus "gpp_b5_srcclkreq0_n" )
				)
				( pin "U7C1.BG18"
					( objectStatus "gpp_b6_srcclkreq1_n" )
				)
				( pin "U7C1.BR13"
					( objectStatus "gpp_b7_srcclkreq2_n" )
				)
				( pin "U7C1.BN11"
					( objectStatus "gpp_b8_srcclkreq3_n" )
				)
				( pin "U7C1.BH20"
					( objectStatus "gpp_b9_srcclkreq4_n" )
				)
				( pin "U7C1.BL11"
					( objectStatus "gpp_b10_srcclkreq5_n" )
				)
				( pin "U7C1.BK9"
					( objectStatus "gpp_b11" )
				)
				( pin "U7C1.BL18"
					( objectStatus "gpp_b12_glb_rst_warn_n" )
				)
				( pin "U7C1.BN18"
					( objectStatus "gpp_b13_pltrst_n" )
				)
				( pin "U7C1.BH13"
					( objectStatus "gpp_b14_spkr" )
				)
				( pin "U7C1.BK13"
					( objectStatus "gpp_b15" )
				)
				( pin "U7C1.BG22"
					( objectStatus "gpp_b16" )
				)
				( pin "U7C1.BG15"
					( objectStatus "gpp_b17" )
				)
				( pin "U7C1.BL15"
					( objectStatus "gpp_b18" )
				)
				( pin "U7C1.BK20"
					( objectStatus "gpp_b19" )
				)
				( pin "U7C1.BJ22"
					( objectStatus "gpp_b20" )
				)
				( pin "U7C1.BH17"
					( objectStatus "gpp_b21" )
				)
				( pin "U7C1.BR17"
					( objectStatus "gpp_b22" )
				)
				( pin "U7C1.BM20"
					( objectStatus "gpp_b23_meie_sml1alrt_n_phot_n" )
				)
				( pin "U7C1.BW28"
					( objectStatus "gpp_c0_smbclk" )
				)
				( pin "U7C1.BV27"
					( objectStatus "gpp_c1_smbdata" )
				)
				( pin "U7C1.BY27"
					( objectStatus "gpp_c2_smbalert_n" )
				)
				( pin "U7C1.BV29"
					( objectStatus "gpp_c3_sml0clk_ie" )
				)
				( pin "U7C1.BW30"
					( objectStatus "gpp_c4_sml0data_ie" )
				)
				( pin "U7C1.BW34"
					( objectStatus "gpp_c5_sml0alert_ie_n" )
				)
				( pin "U7C1.CA28"
					( objectStatus "gpp_c6_sml1clk_ie" )
				)
				( pin "U7C1.BV35"
					( objectStatus "gpp_c7_sml1data_ie" )
				)
				( pin "U7C1.BW32"
					( objectStatus "gpp_c8" )
				)
				( pin "U7C1.BY29"
					( objectStatus "gpp_c9" )
				)
				( pin "U7C1.BV31"
					( objectStatus "gpp_c10" )
				)
				( pin "U7C1.BV33"
					( objectStatus "gpp_c11" )
				)
				( pin "U7C1.CA30"
					( objectStatus "gpp_c12" )
				)
				( pin "U7C1.BV38"
					( objectStatus "gpp_c13" )
				)
				( pin "U7C1.BY38"
					( objectStatus "gpp_c14" )
				)
				( pin "U7C1.CA32"
					( objectStatus "gpp_c15" )
				)
				( pin "U7C1.BW37"
					( objectStatus "gpp_c16" )
				)
				( pin "U7C1.BY31"
					( objectStatus "gpp_c17" )
				)
				( pin "U7C1.BY35"
					( objectStatus "gpp_c18" )
				)
				( pin "U7C1.BW39"
					( objectStatus "gpp_c19" )
				)
				( pin "U7C1.CA39"
					( objectStatus "gpp_c20" )
				)
				( pin "U7C1.BY33"
					( objectStatus "gpp_c21" )
				)
				( pin "U7C1.CA34"
					( objectStatus "gpp_c22" )
				)
				( pin "U7C1.CA37"
					( objectStatus "gpp_c23" )
				)
				( pin "U7C1.BR42"
					( objectStatus "gpp_d0" )
				)
				( pin "U7C1.BK46"
					( objectStatus "gpp_d1" )
				)
				( pin "U7C1.BJ44"
					( objectStatus "gpp_d2" )
				)
				( pin "U7C1.BW45"
					( objectStatus "gpp_d3" )
				)
				( pin "U7C1.BM42"
					( objectStatus "gpp_d4" )
				)
				( pin "U7C1.BM38"
					( objectStatus "gpp_d5" )
				)
				( pin "U7C1.BW41"
					( objectStatus "gpp_d6" )
				)
				( pin "U7C1.CA45"
					( objectStatus "gpp_d7" )
				)
				( pin "U7C1.BR38"
					( objectStatus "gpp_d8" )
				)
				( pin "U7C1.BY42"
					( objectStatus "gpp_d9_ssata_devslp3" )
				)
				( pin "U7C1.BV47"
					( objectStatus "gpp_d10_ssata_devslp4" )
				)
				( pin "U7C1.BY47"
					( objectStatus "gpp_d11_ssata_devslp5" )
				)
				( pin "U7C1.BN40"
					( objectStatus "gpp_d12_ssata_sdataout1" )
				)
				( pin "U7C1.BY44"
					( objectStatus "gpp_d13_sml0bclk_ie" )
				)
				( pin "U7C1.BL44"
					( objectStatus "gpp_d14_sml0bdata_ie" )
				)
				( pin "U7C1.BW43"
					( objectStatus "gpp_d15_ssata_sdataout0" )
				)
				( pin "U7C1.BV42"
					( objectStatus "gpp_d16_sml0balert_ie_n" )
				)
				( pin "U7C1.BW48"
					( objectStatus "gpp_d17" )
				)
				( pin "U7C1.CA41"
					( objectStatus "gpp_d18" )
				)
				( pin "U7C1.CA43"
					( objectStatus "gpp_d19" )
				)
				( pin "U7C1.CA48"
					( objectStatus "gpp_d20" )
				)
				( pin "U7C1.BV44"
					( objectStatus "gpp_d21_ie_uart_rx" )
				)
				( pin "U7C1.BR46"
					( objectStatus "gpp_d22_ie_uart_tx" )
				)
				( pin "U7C1.BN44"
					( objectStatus "gpp_d23" )
				)
			)
			( gate "R2M3"
				( objectStatus "@baseboard_fab2_lib.baseboard_fab2(sch_1):page119_i172" )
				( pin "R2M3.1"
					( objectStatus "a" )
				)
				( pin "R2M3.2"
					( objectStatus "b" )
				)
			)
			( gate "R2N1"
				( objectStatus "@baseboard_fab2_lib.baseboard_fab2(sch_1):page119_i173" )
				( pin "R2N1.1"
					( objectStatus "a" )
				)
				( pin "R2N1.2"
					( objectStatus "b" )
				)
			)
			( gate "R2M7"
				( objectStatus "@baseboard_fab2_lib.baseboard_fab2(sch_1):page119_i174" )
				( pin "R2M7.1"
					( objectStatus "a" )
				)
				( pin "R2M7.2"
					( objectStatus "b" )
				)
			)
			( gate "Q9A2"
				( objectStatus "@baseboard_fab2_lib.baseboard_fab2(sch_1):page119_i175" )
				( pin "Q9A2.6"
					( objectStatus "drain(0)" )
				)
				( pin "Q9A2.2"
					( objectStatus "gate(0)" )
				)
				( pin "Q9A2.1"
					( objectStatus "source(0)" )
				)
			)
			( gate "R9A20"
				( objectStatus "@baseboard_fab2_lib.baseboard_fab2(sch_1):page119_i178" )
				( pin "R9A20.1"
					( objectStatus "a" )
				)
				( pin "R9A20.2"
					( objectStatus "b" )
				)
			)
			( gate "DS9A5"
				( objectStatus "@baseboard_fab2_lib.baseboard_fab2(sch_1):page119_i179" )
				( pin "DS9A5.1"
					( objectStatus "a" )
				)
				( pin "DS9A5.2"
					( objectStatus "c" )
				)
			)
			( gate "Q9A2"
				( objectStatus "@baseboard_fab2_lib.baseboard_fab2(sch_1):page119_i180" )
				( pin "Q9A2.3"
					( objectStatus "drain(0)" )
				)
				( pin "Q9A2.5"
					( objectStatus "gate(0)" )
				)
				( pin "Q9A2.4"
					( objectStatus "source(0)" )
				)
			)
			( gate "R9A18"
				( objectStatus "@baseboard_fab2_lib.baseboard_fab2(sch_1):page119_i183" )
				( pin "R9A18.1"
					( objectStatus "a" )
				)
				( pin "R9A18.2"
					( objectStatus "b" )
				)
			)
			( gate "R9A21"
				( objectStatus "@baseboard_fab2_lib.baseboard_fab2(sch_1):page119_i186" )
				( pin "R9A21.1"
					( objectStatus "a" )
				)
				( pin "R9A21.2"
					( objectStatus "b" )
				)
			)
			( gate "R2T14"
				( objectStatus "@baseboard_fab2_lib.baseboard_fab2(sch_1):page119_i189" )
				( pin "R2T14.1"
					( objectStatus "a" )
				)
				( pin "R2T14.2"
					( objectStatus "b" )
				)
			)
			( gate "R173"
				( objectStatus "@baseboard_fab2_lib.baseboard_fab2(sch_1):page119_i213" )
				( pin "R173.1"
					( objectStatus "a" )
				)
				( pin "R173.2"
					( objectStatus "b" )
				)
			)
			( gate "R174"
				( objectStatus "@baseboard_fab2_lib.baseboard_fab2(sch_1):page119_i215" )
				( pin "R174.1"
					( objectStatus "a" )
				)
				( pin "R174.2"
					( objectStatus "b" )
				)
			)
			( gate "U7C1"
				( objectStatus "@baseboard_fab2_lib.baseboard_fab2(sch_1):page120_i147" )
				( pin "U7C1.BY25"
					( objectStatus "gpio_rcomp_3p3" )
				)
				( pin "U7C1.BH50"
					( objectStatus "gpp_e0_sataxpcie0_satagp0" )
				)
				( pin "U7C1.AY52"
					( objectStatus "gpp_e1_sataxpcie1_satagp1" )
				)
				( pin "U7C1.BG52"
					( objectStatus "gpp_e2_sataxpcie2_satagp2" )
				)
				( pin "U7C1.BE52"
					( objectStatus "gpp_e3_cpu_gp0" )
				)
				( pin "U7C1.AV52"
					( objectStatus "gpp_e4_sata_devslp0" )
				)
				( pin "U7C1.AT52"
					( objectStatus "gpp_e5_sata_devslp1" )
				)
				( pin "U7C1.BB52"
					( objectStatus "gpp_e6_sata_devslp2" )
				)
				( pin "U7C1.BJ48"
					( objectStatus "gpp_e7_cpu_gp1" )
				)
				( pin "U7C1.AV56"
					( objectStatus "gpp_e8_sata_led_n" )
				)
				( pin "U7C1.BL48"
					( objectStatus "gpp_e9_usb2_oc0_n" )
				)
				( pin "U7C1.BN48"
					( objectStatus "gpp_e10_usb2_oc1_n" )
				)
				( pin "U7C1.AW54"
					( objectStatus "gpp_e11_usb2_oc2_n" )
				)
				( pin "U7C1.AU58"
					( objectStatus "gpp_e12_usb2_oc3_n" )
				)
				( pin "U7C1.AG7"
					( objectStatus "gpp_f0_sataxpcie3_satagp3" )
				)
				( pin "U7C1.AK9"
					( objectStatus "gpp_f1_sataxpcie4_satagp4" )
				)
				( pin "U7C1.AK20"
					( objectStatus "gpp_f2_sataxpcie5_satagp5" )
				)
				( pin "U7C1.AK13"
					( objectStatus "gpp_f3_sataxpcie6_satagp6" )
				)
				( pin "U7C1.AH13"
					( objectStatus "gpp_f4_sataxpcie7_satagp7" )
				)
				( pin "U7C1.AH17"
					( objectStatus "gpp_f5_sata_devslp3" )
				)
				( pin "U7C1.AL18"
					( objectStatus "gpp_f6_sata_devslp4" )
				)
				( pin "U7C1.AK17"
					( objectStatus "gpp_f7_sata_devslp5" )
				)
				( pin "U7C1.AH9"
					( objectStatus "gpp_f8_sata_devslp6" )
				)
				( pin "U7C1.AR20"
					( objectStatus "gpp_f9_sata_devslp7" )
				)
				( pin "U7C1.AL7"
					( objectStatus "gpp_f10_sata_sclock" )
				)
				( pin "U7C1.AR9"
					( objectStatus "gpp_f11_sata_sload" )
				)
				( pin "U7C1.AP7"
					( objectStatus "gpp_f12_sata_sdataout1" )
				)
				( pin "U7C1.AP11"
					( objectStatus "gpp_f13_sata_sdataout0" )
				)
				( pin "U7C1.AL11"
					( objectStatus "gpp_f14_ssata_led_n" )
				)
				( pin "U7C1.AR13"
					( objectStatus "gpp_f15_usb2_oc4_n" )
				)
				( pin "U7C1.AU13"
					( objectStatus "gpp_f16_usb2_oc5_n" )
				)
				( pin "U7C1.AP15"
					( objectStatus "gpp_f17_usb2_oc6_n" )
				)
				( pin "U7C1.AL15"
					( objectStatus "gpp_f18_usb2_oc7_n" )
				)
				( pin "U7C1.AU9"
					( objectStatus "gpp_f19_lan_smbclk" )
				)
				( pin "U7C1.AU20"
					( objectStatus "gpp_f20_lan_smbdata" )
				)
				( pin "U7C1.AR17"
					( objectStatus "gpp_f21_lan_smbalrt_n" )
				)
				( pin "U7C1.AP18"
					( objectStatus "gpp_f22_ssata_sclock" )
				)
				( pin "U7C1.AU17"
					( objectStatus "gpp_f23_ssata_sload" )
				)
				( pin "U7C1.AY11"
					( objectStatus "gpp_g0_fantach0_fantach0ie" )
				)
				( pin "U7C1.AV15"
					( objectStatus "gpp_g1_fantach1_fantach1ie" )
				)
				( pin "U7C1.BE22"
					( objectStatus "gpp_g2_fantach2_fantach2ie" )
				)
				( pin "U7C1.AY7"
					( objectStatus "gpp_g3_fantach3_fantach3ie" )
				)
				( pin "U7C1.BA9"
					( objectStatus "gpp_g4_fantach4_fantach4ie" )
				)
				( pin "U7C1.AW20"
					( objectStatus "gpp_g5_fantach5_fantach5ie" )
				)
				( pin "U7C1.AV18"
					( objectStatus "gpp_g6_fantach6_fantach6ie" )
				)
				( pin "U7C1.AY15"
					( objectStatus "gpp_g7_fantach7_fantach7ie" )
				)
				( pin "U7C1.BG11"
					( objectStatus "gpp_g8_fanpwm0_fanpwm0ie" )
				)
				( pin "U7C1.AV11"
					( objectStatus "gpp_g9_fanpwm1_fampwm1ie" )
				)
				( pin "U7C1.BE11"
					( objectStatus "gpp_g10_fanpwm2_fanpwm2ie" )
				)
				( pin "U7C1.BA20"
					( objectStatus "gpp_g11_fanpwm3_fanpmw3ie" )
				)
				( pin "U7C1.BD13"
					( objectStatus "gpp_g12" )
				)
				( pin "U7C1.AY18"
					( objectStatus "gpp_g13" )
				)
				( pin "U7C1.AV7"
					( objectStatus "gpp_g14" )
				)
				( pin "U7C1.BE18"
					( objectStatus "gpp_g15" )
				)
				( pin "U7C1.BD17"
					( objectStatus "gpp_g16" )
				)
				( pin "U7C1.BD9"
					( objectStatus "gpp_g17_adr_complete" )
				)
				( pin "U7C1.BE7"
					( objectStatus "gpp_g18_nmi_n" )
				)
				( pin "U7C1.BE15"
					( objectStatus "gpp_g19_smi_n" )
				)
				( pin "U7C1.BA17"
					( objectStatus "gpp_g20_ssata_devslp0" )
				)
				( pin "U7C1.BG7"
					( objectStatus "gpp_g21_ssata_devslp1" )
				)
				( pin "U7C1.BD20"
					( objectStatus "gpp_g22_ssata_devslp2" )
				)
				( pin "U7C1.BA13"
					( objectStatus "gpp_g23_ssataxpcie0_ssatagp0" )
				)
				( pin "U7C1.AT4"
					( objectStatus "gpp_h0_srcclkreq6_n" )
				)
				( pin "U7C1.AW4"
					( objectStatus "gpp_h1_srcclkreq7_n" )
				)
				( pin "U7C1.AV3"
					( objectStatus "gpp_h2_srcclkreq8_n" )
				)
				( pin "U7C1.AR1"
					( objectStatus "gpp_h3_srcclkreq9_n" )
				)
				( pin "U7C1.AT2"
					( objectStatus "gpp_h4_srcclkreq10_n" )
				)
				( pin "U7C1.AY3"
					( objectStatus "gpp_h5_srcclkreq11_n" )
				)
				( pin "U7C1.AW2"
					( objectStatus "gpp_h6_srcclkreq12_n" )
				)
				( pin "U7C1.AV1"
					( objectStatus "gpp_h7_srcclkreq13_n" )
				)
				( pin "U7C1.AR3"
					( objectStatus "gpp_h8_srcclkreq14_n" )
				)
				( pin "U7C1.BE2"
					( objectStatus "gpp_h9_srcclkreq15_n" )
				)
				( pin "U7C1.BA4"
					( objectStatus "gpp_h10_sml2clk_ie" )
				)
				( pin "U7C1.BD1"
					( objectStatus "gpp_h11_sml2data_ie" )
				)
				( pin "U7C1.BB1"
					( objectStatus "gpp_h12_sml2alert_n_ie_n" )
				)
				( pin "U7C1.AY1"
					( objectStatus "gpp_h13_sml3clk_ie" )
				)
				( pin "U7C1.BC2"
					( objectStatus "gpp_h14_sml3data_ie" )
				)
				( pin "U7C1.BB3"
					( objectStatus "gpp_h15_sml3alert_n_ie_n" )
				)
				( pin "U7C1.BF1"
					( objectStatus "gpp_h16_sml4clk_ie" )
				)
				( pin "U7C1.BE4"
					( objectStatus "gpp_h17_sml4data_ie" )
				)
				( pin "U7C1.BC4"
					( objectStatus "gpp_h18_sml4alert_n_ie_n" )
				)
				( pin "U7C1.BD3"
					( objectStatus "gpp_h19_ssataxpcie1_ssatagp1" )
				)
				( pin "U7C1.BF3"
					( objectStatus "gpp_h20_ssataxpcie2_ssatagp2" )
				)
				( pin "U7C1.BA2"
					( objectStatus "gpp_h21_ssataxpcie3_ssatagp3" )
				)
				( pin "U7C1.BH2"
					( objectStatus "gpp_h22_ssataxpcie4_ssatagp4" )
				)
				( pin "U7C1.BH4"
					( objectStatus "gpp_h23_ssataxpcie5_ssatagp5" )
				)
				( pin "U7C1.CA20"
					( objectStatus "gpp_i0_lan_tdo" )
				)
				( pin "U7C1.BV21"
					( objectStatus "gpp_i1_lan_tck" )
				)
				( pin "U7C1.CA22"
					( objectStatus "gpp_i2_lan_tms" )
				)
				( pin "U7C1.BY23"
					( objectStatus "gpp_i3_lan_tdi" )
				)
				( pin "U7C1.BW20"
					( objectStatus "gpp_i4_do_reset_in_n" )
				)
				( pin "U7C1.BW24"
					( objectStatus "gpp_i5_do_reset_out_n" )
				)
				( pin "U7C1.BV23"
					( objectStatus "gpp_i6_reset_done" )
				)
				( pin "U7C1.CA24"
					( objectStatus "gpp_i7_lan_trst_n" )
				)
				( pin "U7C1.BW22"
					( objectStatus "gpp_i8_pci_dis_n" )
				)
				( pin "U7C1.BY21"
					( objectStatus "gpp_i9_lan_dis_n" )
				)
				( pin "U7C1.BV25"
					( objectStatus "gpp_i10" )
				)
				( pin "U7C1.BL1"
					( objectStatus "gpp_j0_lan_led_p0_0" )
				)
				( pin "U7C1.BK4"
					( objectStatus "gpp_j1_lan_led_p0_1" )
				)
				( pin "U7C1.BP4"
					( objectStatus "gpp_j2_lan_led_p1_0" )
				)
				( pin "U7C1.BK2"
					( objectStatus "gpp_j3_lan_led_p1_1" )
				)
				( pin "U7C1.BL3"
					( objectStatus "gpp_j4_lan_led_p2_0" )
				)
				( pin "U7C1.BU6"
					( objectStatus "gpp_j5_lan_led_p2_1" )
				)
				( pin "U7C1.CA13"
					( objectStatus "gpp_j6_lan_led_p3_0" )
				)
				( pin "U7C1.BM2"
					( objectStatus "gpp_j7_lan_led_p3_1" )
				)
				( pin "U7C1.BM4"
					( objectStatus "gpp_j8_lan_i2c_scl_mdc_p0" )
				)
				( pin "U7C1.BN3"
					( objectStatus "gpp_j9_lan_i2c_sda_mdio_p0" )
				)
				( pin "U7C1.BW5"
					( objectStatus "gpp_j10_lan_i2c_scl_mdc_p1" )
				)
				( pin "U7C1.BV8"
					( objectStatus "gpp_j11_lan_i2c_sda_mdio_p1" )
				)
				( pin "U7C1.BT5"
					( objectStatus "gpp_j12_lan_i2c_scl_mdc_p2" )
				)
				( pin "U7C1.BW11"
					( objectStatus "gpp_j13_lan_i2c_sda_mdio_p2" )
				)
				( pin "U7C1.BW6"
					( objectStatus "gpp_j14_lan_i2c_scl_mdc_p3" )
				)
				( pin "U7C1.BW9"
					( objectStatus "gpp_j15_lan_i2c_sda_mdio_p3" )
				)
				( pin "U7C1.BV10"
					( objectStatus "gpp_j16_lan_sdp_p0_0" )
				)
				( pin "U7C1.CA11"
					( objectStatus "gpp_j17_lan_sdp_p0_1" )
				)
				( pin "U7C1.BY10"
					( objectStatus "gpp_j18_lan_sdp_p1_0" )
				)
				( pin "U7C1.BY14"
					( objectStatus "gpp_j19_lan_sdp_p1_1" )
				)
				( pin "U7C1.BW13"
					( objectStatus "gpp_j20_lan_sdp_p2_0" )
				)
				( pin "U7C1.BV12"
					( objectStatus "gpp_j21_lan_sdp_p2_1" )
				)
				( pin "U7C1.BY12"
					( objectStatus "gpp_j22_lan_sdp_p3_0" )
				)
				( pin "U7C1.BV14"
					( objectStatus "gpp_j23_lan_sdp_p3_1" )
				)
			)
			( gate "R8C21"
				( objectStatus "@baseboard_fab2_lib.baseboard_fab2(sch_1):page120_i148" )
				( pin "R8C21.1"
					( objectStatus "a" )
				)
				( pin "R8C21.2"
					( objectStatus "b" )
				)
			)
			( gate "R2M1"
				( objectStatus "@baseboard_fab2_lib.baseboard_fab2(sch_1):page120_i218" )
				( pin "R2M1.1"
					( objectStatus "a" )
				)
				( pin "R2M1.2"
					( objectStatus "b" )
				)
			)
			( gate "R2N26"
				( objectStatus "@baseboard_fab2_lib.baseboard_fab2(sch_1):page120_i219" )
				( pin "R2N26.1"
					( objectStatus "a" )
				)
				( pin "R2N26.2"
					( objectStatus "b" )
				)
			)
			( gate "R7C15"
				( objectStatus "@baseboard_fab2_lib.baseboard_fab2(sch_1):page121_i31" )
				( pin "R7C15.1"
					( objectStatus "a" )
				)
				( pin "R7C15.2"
					( objectStatus "b" )
				)
			)
			( gate "R7C16"
				( objectStatus "@baseboard_fab2_lib.baseboard_fab2(sch_1):page121_i33" )
				( pin "R7C16.1"
					( objectStatus "a" )
				)
				( pin "R7C16.2"
					( objectStatus "b" )
				)
			)
			( gate "U7C1"
				( objectStatus "@baseboard_fab2_lib.baseboard_fab2(sch_1):page121_i34" )
				( pin "U7C1.C70"
					( objectStatus "cgc_dut_detect_n" )
				)
				( pin "U7C1.AM4"
					( objectStatus "gpio_rcomp_1p8_3p3" )
				)
				( pin "U7C1.AJ1"
					( objectStatus "gpp_k0_lan_ncsi_clk_in" )
				)
				( pin "U7C1.AM2"
					( objectStatus "gpp_k1_lan_ncsi_txd0" )
				)
				( pin "U7C1.AK2"
					( objectStatus "gpp_k2_lan_ncsi_txd1" )
				)
				( pin "U7C1.AL3"
					( objectStatus "gpp_k3_lan_ncsi_tx_en" )
				)
				( pin "U7C1.AN3"
					( objectStatus "gpp_k4_lan_ncsi_crs_dv" )
				)
				( pin "U7C1.AL1"
					( objectStatus "gpp_k5_lan_ncsi_rxd0" )
				)
				( pin "U7C1.AN1"
					( objectStatus "gpp_k6_lan_ncsi_rxd1" )
				)
				( pin "U7C1.AH2"
					( objectStatus "gpp_k7" )
				)
				( pin "U7C1.AJ3"
					( objectStatus "gpp_k8_lan_ncsi_arb_in" )
				)
				( pin "U7C1.AK4"
					( objectStatus "gpp_k9_lan_ncsi_arb_out" )
				)
				( pin "U7C1.AH4"
					( objectStatus "gpp_k10_pe_rst_n" )
				)
				( pin "U7C1.AE18"
					( objectStatus "gpp_l2_testch0_d0" )
				)
				( pin "U7C1.AE15"
					( objectStatus "gpp_l3_testch0_d1" )
				)
				( pin "U7C1.AE11"
					( objectStatus "gpp_l4_testch0_d2" )
				)
				( pin "U7C1.Y18"
					( objectStatus "gpp_l5_testch0_d3" )
				)
				( pin "U7C1.AA20"
					( objectStatus "gpp_l6_testch0_d4" )
				)
				( pin "U7C1.AA17"
					( objectStatus "gpp_l7_testch0_d5" )
				)
				( pin "U7C1.AD9"
					( objectStatus "gpp_l8_testch0_d6" )
				)
				( pin "U7C1.AD17"
					( objectStatus "gpp_l9_testch0_d7" )
				)
				( pin "U7C1.AF20"
					( objectStatus "gpp_l10_testch0_clk" )
				)
				( pin "U7C1.AD20"
					( objectStatus "gpp_l11_testch1_d0" )
				)
				( pin "U7C1.Y15"
					( objectStatus "gpp_l12_testch1_d1" )
				)
				( pin "U7C1.AD13"
					( objectStatus "gpp_l13_testch1_d2" )
				)
				( pin "U7C1.AA13"
					( objectStatus "gpp_l14_testch1_d3" )
				)
				( pin "U7C1.Y11"
					( objectStatus "gpp_l15_testch1_d4" )
				)
				( pin "U7C1.Y7"
					( objectStatus "gpp_l16_testch1_d5" )
				)
				( pin "U7C1.AA9"
					( objectStatus "gpp_l17_testch1_d6" )
				)
				( pin "U7C1.AE7"
					( objectStatus "gpp_l18_testch1_d7" )
				)
				( pin "U7C1.AG11"
					( objectStatus "gpp_l19_testch1_clk" )
				)
				( pin "U7C1.P18"
					( objectStatus "hda_bclk" )
				)
				( pin "U7C1.M18"
					( objectStatus "hda_rst_n" )
				)
				( pin "U7C1.K20"
					( objectStatus "hda_sdi_0" )
				)
				( pin "U7C1.V18"
					( objectStatus "hda_sdi_1" )
				)
				( pin "U7C1.U24"
					( objectStatus "hda_sdo" )
				)
				( pin "U7C1.H20"
					( objectStatus "hda_sync" )
				)
				( pin "U7C1.AG18"
					( objectStatus "intruder_n" )
				)
				( pin "U7C1.AF61"
					( objectStatus "rsvd(0)" )
				)
				( pin "U7C1.AC56"
					( objectStatus "rsvd(1)" )
				)
				( pin "U7C1.AA58"
					( objectStatus "rsvd(2)" )
				)
				( pin "U7C1.V11"
					( objectStatus "rsvd(3)" )
				)
				( pin "U7C1.P37"
					( objectStatus "rsvd(4)" )
				)
				( pin "U7C1.AG15"
					( objectStatus "rsvd(5)" )
				)
				( pin "U7C1.AT69"
					( objectStatus "rsvd(6)" )
				)
				( pin "U7C1.F8"
					( objectStatus "rsvd(7)" )
				)
				( pin "U7C1.F69"
					( objectStatus "rsvd(8)" )
				)
				( pin "U7C1.F66"
					( objectStatus "rsvd(9)" )
				)
				( pin "U7C1.D8"
					( objectStatus "rsvd(10)" )
				)
				( pin "U7C1.C18"
					( objectStatus "rsvd(11)" )
				)
				( pin "U7C1.C68"
					( objectStatus "rsvd(12)" )
				)
				( pin "U7C1.C67"
					( objectStatus "rsvd(13)" )
				)
				( pin "U7C1.E18"
					( objectStatus "rsvd(14)" )
				)
				( pin "U7C1.C6"
					( objectStatus "rsvd(15)" )
				)
				( pin "U7C1.C5"
					( objectStatus "rsvd(16)" )
				)
				( pin "U7C1.B10"
					( objectStatus "rsvd(17)" )
				)
				( pin "U7C1.C11"
					( objectStatus "rsvd(18)" )
				)
				( pin "U7C1.C9"
					( objectStatus "rsvd(19)" )
				)
				( pin "U7C1.D10"
					( objectStatus "rsvd(20)" )
				)
				( pin "U7C1.A11"
					( objectStatus "rsvd(21)" )
				)
				( pin "U7C1.AT71"
					( objectStatus "rsvd(22)" )
				)
				( pin "U7C1.P40"
					( objectStatus "rsvd(23)" )
				)
				( pin "U7C1.P44"
					( objectStatus "rsvd(24)" )
				)
				( pin "U7C1.P48"
					( objectStatus "rsvd(25)" )
				)
				( pin "U7C1.BH24"
					( objectStatus "rsvd(26)" )
				)
				( pin "U7C1.BG26"
					( objectStatus "rsvd(27)" )
				)
				( pin "U7C1.BW3"
					( objectStatus "rsvd(46)" )
				)
				( pin "U7C1.U20"
					( objectStatus "rsvd(66)" )
				)
				( pin "U7C1.R20"
					( objectStatus "rsvd(67)" )
				)
				( pin "U7C1.V22"
					( objectStatus "rsvd(68)" )
				)
				( pin "U7C1.P11"
					( objectStatus "rtcrst_n" )
				)
				( pin "U7C1.K2"
					( objectStatus "spi0_clk" )
				)
				( pin "U7C1.J3"
					( objectStatus "spi0_flash_cs0_n" )
				)
				( pin "U7C1.G7"
					( objectStatus "spi0_flash_cs1_n" )
				)
				( pin "U7C1.F5"
					( objectStatus "spi0_io2" )
				)
				( pin "U7C1.L1"
					( objectStatus "spi0_io3" )
				)
				( pin "U7C1.L3"
					( objectStatus "spi0_miso_io1" )
				)
				( pin "U7C1.H4"
					( objectStatus "spi0_mosi_io0" )
				)
				( pin "U7C1.K4"
					( objectStatus "spi0_tpm_cs_n" )
				)
				( pin "U7C1.G18"
					( objectStatus "srtcrst_n" )
				)
			)
			( gate "R8D10"
				( objectStatus "@baseboard_fab2_lib.baseboard_fab2(sch_1):page121_i35" )
				( pin "R8D10.1"
					( objectStatus "a" )
				)
				( pin "R8D10.2"
					( objectStatus "b" )
				)
			)
			( gate "R3N10"
				( objectStatus "@baseboard_fab2_lib.baseboard_fab2(sch_1):page121_i37" )
				( pin "R3N10.1"
					( objectStatus "a" )
				)
				( pin "R3N10.2"
					( objectStatus "b" )
				)
			)
			( gate "R3P3"
				( objectStatus "@baseboard_fab2_lib.baseboard_fab2(sch_1):page121_i65" )
				( pin "R3P3.1"
					( objectStatus "a" )
				)
				( pin "R3P3.2"
					( objectStatus "b" )
				)
			)
			( gate "R2P1"
				( objectStatus "@baseboard_fab2_lib.baseboard_fab2(sch_1):page121_i66" )
				( pin "R2P1.1"
					( objectStatus "a" )
				)
				( pin "R2P1.2"
					( objectStatus "b" )
				)
			)
			( gate "R3P2"
				( objectStatus "@baseboard_fab2_lib.baseboard_fab2(sch_1):page121_i67" )
				( pin "R3P2.1"
					( objectStatus "a" )
				)
				( pin "R3P2.2"
					( objectStatus "b" )
				)
			)
			( gate "R8D11"
				( objectStatus "@baseboard_fab2_lib.baseboard_fab2(sch_1):page121_i68" )
				( pin "R8D11.1"
					( objectStatus "a" )
				)
				( pin "R8D11.2"
					( objectStatus "b" )
				)
			)
			( gate "R7C14"
				( objectStatus "@baseboard_fab2_lib.baseboard_fab2(sch_1):page121_i69" )
				( pin "R7C14.1"
					( objectStatus "a" )
				)
				( pin "R7C14.2"
					( objectStatus "b" )
				)
			)
			( gate "R7C20"
				( objectStatus "@baseboard_fab2_lib.baseboard_fab2(sch_1):page121_i73" )
				( pin "R7C20.1"
					( objectStatus "a" )
				)
				( pin "R7C20.2"
					( objectStatus "b" )
				)
			)
			( gate "U7C1"
				( objectStatus "@baseboard_fab2_lib.baseboard_fab2(sch_1):page122_i63" )
				( pin "U7C1.R35"
					( objectStatus "rsvd(28)" )
				)
				( pin "U7C1.P33"
					( objectStatus "rsvd(29)" )
				)
				( pin "U7C1.R31"
					( objectStatus "rsvd(30)" )
				)
				( pin "U7C1.P29"
					( objectStatus "rsvd(31)" )
				)
				( pin "U7C1.AP27"
					( objectStatus "rsvd(58)" )
				)
				( pin "U7C1.AT27"
					( objectStatus "rsvd(59)" )
				)
				( pin "U7C1.W50"
					( objectStatus "vcca_clkfilt_1p05(0)" )
				)
				( pin "U7C1.AG45"
					( objectStatus "vcca_clkfilt_1p05(1)" )
				)
				( pin "U7C1.AJ46"
					( objectStatus "vcca_clkfilt_1p05(2)" )
				)
				( pin "U7C1.AJ48"
					( objectStatus "vcca_clkfilt_1p05(3)" )
				)
				( pin "U7C1.AE46"
					( objectStatus "vcca_clkfilt_1p05(4)" )
				)
				( pin "U7C1.AE45"
					( objectStatus "vcca_clkpll_1p05(0)" )
				)
				( pin "U7C1.AG48"
					( objectStatus "vcca_clkpll_1p05(1)" )
				)
				( pin "U7C1.AH50"
					( objectStatus "vcca_clkunf_1p05(0)" )
				)
				( pin "U7C1.U50"
					( objectStatus "vcca_clkunf_1p05(1)" )
				)
				( pin "U7C1.AD50"
					( objectStatus "vcca_clkxtal_1p05" )
				)
				( pin "U7C1.AW45"
					( objectStatus "vccmphy_1p05(0)" )
				)
				( pin "U7C1.AW43"
					( objectStatus "vccmphy_1p05(1)" )
				)
				( pin "U7C1.AJ43"
					( objectStatus "vccmphy_1p05(2)" )
				)
				( pin "U7C1.AU45"
					( objectStatus "vccmphy_1p05(3)" )
				)
				( pin "U7C1.AU43"
					( objectStatus "vccmphy_1p05(4)" )
				)
				( pin "U7C1.AT45"
					( objectStatus "vccmphy_1p05(5)" )
				)
				( pin "U7C1.AT43"
					( objectStatus "vccmphy_1p05(6)" )
				)
				( pin "U7C1.AP45"
					( objectStatus "vccmphy_1p05(7)" )
				)
				( pin "U7C1.AP43"
					( objectStatus "vccmphy_1p05(8)" )
				)
				( pin "U7C1.AM45"
					( objectStatus "vccmphy_1p05(9)" )
				)
				( pin "U7C1.AM43"
					( objectStatus "vccmphy_1p05(10)" )
				)
				( pin "U7C1.AK45"
					( objectStatus "vccmphy_1p05(11)" )
				)
				( pin "U7C1.AK43"
					( objectStatus "vccmphy_1p05(12)" )
				)
				( pin "U7C1.BA29"
					( objectStatus "vccp10gbe_hv_1p8(0)" )
				)
				( pin "U7C1.BA27"
					( objectStatus "vccp10gbe_hv_1p8(1)" )
				)
				( pin "U7C1.BB37"
					( objectStatus "vccp10gbe_lv_1p05(0)" )
				)
				( pin "U7C1.BB33"
					( objectStatus "vccp10gbe_lv_1p05(1)" )
				)
				( pin "U7C1.BA37"
					( objectStatus "vccp10gbe_lv_1p05(2)" )
				)
				( pin "U7C1.BA36"
					( objectStatus "vccp10gbe_lv_1p05(3)" )
				)
				( pin "U7C1.BA34"
					( objectStatus "vccp10gbe_lv_1p05(4)" )
				)
				( pin "U7C1.BA32"
					( objectStatus "vccp10gbe_lv_1p05(5)" )
				)
				( pin "U7C1.BA30"
					( objectStatus "vccp10gbe_lv_1p05(6)" )
				)
				( pin "U7C1.BD38"
					( objectStatus "vccp10gbepll_1p05(0)" )
				)
				( pin "U7C1.BB40"
					( objectStatus "vccp10gbepll_1p05(1)" )
				)
				( pin "U7C1.BA41"
					( objectStatus "vccp10gbepll_1p05(2)" )
				)
				( pin "U7C1.BA39"
					( objectStatus "vccp10gbepll_1p05(3)" )
				)
				( pin "U7C1.BD46"
					( objectStatus "vccp_1p8(0)" )
				)
				( pin "U7C1.AE26"
					( objectStatus "vccp_1p8(1)" )
				)
				( pin "U7C1.BA46"
					( objectStatus "vccp_3p3(0)" )
				)
				( pin "U7C1.BA45"
					( objectStatus "vccp_3p3(1)" )
				)
				( pin "U7C1.AD24"
					( objectStatus "vccp_3p3(2)" )
				)
				( pin "U7C1.AN24"
					( objectStatus "vccp_3p3(5)" )
				)
				( pin "U7C1.AW48"
					( objectStatus "vccp_hsiopll_1p05(0)" )
				)
				( pin "U7C1.AU48"
					( objectStatus "vccp_hsiopll_1p05(2)" )
				)
				( pin "U7C1.AP48"
					( objectStatus "vccp_hsiopll_1p05(3)" )
				)
				( pin "U7C1.AT48"
					( objectStatus "vccp_hsiopllunf_1p05" )
				)
				( pin "U7C1.AN50"
					( objectStatus "vccp_uppll_1p05(0)" )
				)
				( pin "U7C1.AK50"
					( objectStatus "vccp_uppll_1p05(2)" )
				)
				( pin "U7C1.AM48"
					( objectStatus "vccp_uppllunf_1p05" )
				)
				( pin "U7C1.AH24"
					( objectStatus "vccpdsw_3p3" )
				)
				( pin "U7C1.AU29"
					( objectStatus "vccpgpp_1p8(0)" )
				)
				( pin "U7C1.AW29"
					( objectStatus "vccpgpp_1p8(1)" )
				)
				( pin "U7C1.AT29"
					( objectStatus "vccpgpp_1p8(2)" )
				)
				( pin "U7C1.AM29"
					( objectStatus "vccpgpp_1p8(3)" )
				)
				( pin "U7C1.AP29"
					( objectStatus "vccpgpp_1p8(4)" )
				)
				( pin "U7C1.AW27"
					( objectStatus "vccpgpp_1p8(5)" )
				)
				( pin "U7C1.AK24"
					( objectStatus "vccpgpp_1p8(6)" )
				)
				( pin "U7C1.AW24"
					( objectStatus "vccpgppa" )
				)
				( pin "U7C1.BE26"
					( objectStatus "vccpgppb" )
				)
				( pin "U7C1.BE40"
					( objectStatus "vccpgppc" )
				)
				( pin "U7C1.BA43"
					( objectStatus "vccpgppd" )
				)
				( pin "U7C1.BE44"
					( objectStatus "vccpgppe" )
				)
				( pin "U7C1.AU27"
					( objectStatus "vccpgppf" )
				)
				( pin "U7C1.BA26"
					( objectStatus "vccpgppg" )
				)
				( pin "U7C1.BA24"
					( objectStatus "vccpgpph" )
				)
				( pin "U7C1.BB26"
					( objectStatus "vccpgppj" )
				)
				( pin "U7C1.AU24"
					( objectStatus "vccpgppk" )
				)
				( pin "U7C1.AG27"
					( objectStatus "vccphda_1p8" )
				)
				( pin "U7C1.BF46"
					( objectStatus "vccprim_1p05(0)" )
				)
				( pin "U7C1.BE48"
					( objectStatus "vccprim_1p05(1)" )
				)
				( pin "U7C1.AU39"
					( objectStatus "vccprim_1p05(2)" )
				)
				( pin "U7C1.AU37"
					( objectStatus "vccprim_1p05(3)" )
				)
				( pin "U7C1.AT39"
					( objectStatus "vccprim_1p05(4)" )
				)
				( pin "U7C1.AM27"
					( objectStatus "vccprim_1p05(5)" )
				)
				( pin "U7C1.AJ29"
					( objectStatus "vccprim_1p05(6)" )
				)
				( pin "U7C1.AC26"
					( objectStatus "vccprim_1p05(7)" )
				)
				( pin "U7C1.AA46"
					( objectStatus "vccprim_1p05(8)" )
				)
				( pin "U7C1.AA45"
					( objectStatus "vccprim_1p05(9)" )
				)
				( pin "U7C1.Y46"
					( objectStatus "vccprim_1p05(10)" )
				)
				( pin "U7C1.Y45"
					( objectStatus "vccprim_1p05(11)" )
				)
				( pin "U7C1.V44"
					( objectStatus "vccprim_1p05(12)" )
				)
				( pin "U7C1.U46"
					( objectStatus "vccprim_1p05(13)" )
				)
				( pin "U7C1.T44"
					( objectStatus "vccprim_1p05(14)" )
				)
				( pin "U7C1.R46"
					( objectStatus "vccprim_1p05(15)" )
				)
				( pin "U7C1.R42"
					( objectStatus "vccprim_1p05(16)" )
				)
				( pin "U7C1.AK27"
					( objectStatus "vccprim_1p05(17)" )
				)
				( pin "U7C1.AA24"
					( objectStatus "vccprim_1p05(18)" )
				)
				( pin "U7C1.Y26"
					( objectStatus "vccprim_1p05(19)" )
				)
				( pin "U7C1.AJ27"
					( objectStatus "vccprtc" )
				)
				( pin "U7C1.AG29"
					( objectStatus "vccprtcprim_3p3" )
				)
				( pin "U7C1.AR24"
					( objectStatus "vccpspi" )
				)
				( pin "U7C1.AK29"
					( objectStatus "vccpspi_1p8" )
				)
				( pin "U7C1.BA48"
					( objectStatus "vccpusbdsw_3p3" )
				)
				( pin "U7C1.AG22"
					( objectStatus "vccrtcext" )
				)
			)
			( gate "U7C1"
				( objectStatus "@baseboard_fab2_lib.baseboard_fab2(sch_1):page123_i13" )
				( pin "U7C1.N31"
					( objectStatus "vss(355)" )
				)
				( pin "U7C1.N27"
					( objectStatus "vss(356)" )
				)
				( pin "U7C1.N24"
					( objectStatus "vss(357)" )
				)
				( pin "U7C1.N20"
					( objectStatus "vss(358)" )
				)
				( pin "U7C1.N17"
					( objectStatus "vss(359)" )
				)
				( pin "U7C1.N13"
					( objectStatus "vss(360)" )
				)
				( pin "U7C1.M48"
					( objectStatus "vss(361)" )
				)
				( pin "U7C1.M44"
					( objectStatus "vss(362)" )
				)
				( pin "U7C1.N50"
					( objectStatus "vss(363)" )
				)
				( pin "U7C1.N42"
					( objectStatus "vss(364)" )
				)
				( pin "U7C1.M40"
					( objectStatus "vss(365)" )
				)
				( pin "U7C1.M4"
					( objectStatus "vss(366)" )
				)
				( pin "U7C1.M37"
					( objectStatus "vss(367)" )
				)
				( pin "U7C1.M33"
					( objectStatus "vss(368)" )
				)
				( pin "U7C1.M29"
					( objectStatus "vss(369)" )
				)
				( pin "U7C1.M26"
					( objectStatus "vss(370)" )
				)
				( pin "U7C1.M22"
					( objectStatus "vss(371)" )
				)
				( pin "U7C1.M2"
					( objectStatus "vss(372)" )
				)
				( pin "U7C1.L68"
					( objectStatus "vss(373)" )
				)
				( pin "U7C1.L5"
					( objectStatus "vss(374)" )
				)
				( pin "U7C1.K71"
					( objectStatus "vss(375)" )
				)
				( pin "U7C1.K69"
					( objectStatus "vss(376)" )
				)
				( pin "U7C1.K54"
					( objectStatus "vss(377)" )
				)
				( pin "U7C1.J70"
					( objectStatus "vss(378)" )
				)
				( pin "U7C1.J68"
					( objectStatus "vss(379)" )
				)
				( pin "U7C1.J59"
					( objectStatus "vss(380)" )
				)
				( pin "U7C1.J44"
					( objectStatus "vss(381)" )
				)
				( pin "U7C1.J37"
					( objectStatus "vss(382)" )
				)
				( pin "U7C1.J22"
					( objectStatus "vss(383)" )
				)
				( pin "U7C1.J15"
					( objectStatus "vss(384)" )
				)
				( pin "U7C1.J11"
					( objectStatus "vss(385)" )
				)
				( pin "U7C1.H65"
					( objectStatus "vss(386)" )
				)
				( pin "U7C1.J7"
					( objectStatus "vss(387)" )
				)
				( pin "U7C1.J5"
					( objectStatus "vss(388)" )
				)
				( pin "U7C1.J29"
					( objectStatus "vss(389)" )
				)
				( pin "U7C1.H58"
					( objectStatus "vss(390)" )
				)
				( pin "U7C1.G66"
					( objectStatus "vss(391)" )
				)
				( pin "U7C1.G63"
					( objectStatus "vss(392)" )
				)
				( pin "U7C1.G6"
					( objectStatus "vss(393)" )
				)
				( pin "U7C1.G48"
					( objectStatus "vss(394)" )
				)
				( pin "U7C1.G37"
					( objectStatus "vss(395)" )
				)
				( pin "U7C1.G29"
					( objectStatus "vss(396)" )
				)
				( pin "U7C1.G22"
					( objectStatus "vss(397)" )
				)
				( pin "U7C1.E9"
					( objectStatus "vss(398)" )
				)
				( pin "U7C1.G59"
					( objectStatus "vss(399)" )
				)
				( pin "U7C1.E63"
					( objectStatus "vss(400)" )
				)
				( pin "U7C1.E61"
					( objectStatus "vss(401)" )
				)
				( pin "U7C1.E6"
					( objectStatus "vss(402)" )
				)
				( pin "U7C1.E57"
					( objectStatus "vss(403)" )
				)
				( pin "U7C1.E54"
					( objectStatus "vss(404)" )
				)
				( pin "U7C1.E52"
					( objectStatus "vss(405)" )
				)
				( pin "U7C1.E50"
					( objectStatus "vss(406)" )
				)
				( pin "U7C1.E48"
					( objectStatus "vss(407)" )
				)
				( pin "U7C1.E45"
					( objectStatus "vss(408)" )
				)
				( pin "U7C1.E43"
					( objectStatus "vss(409)" )
				)
				( pin "U7C1.E41"
					( objectStatus "vss(410)" )
				)
				( pin "U7C1.E39"
					( objectStatus "vss(411)" )
				)
				( pin "U7C1.E37"
					( objectStatus "vss(412)" )
				)
				( pin "U7C1.E34"
					( objectStatus "vss(413)" )
				)
				( pin "U7C1.E32"
					( objectStatus "vss(414)" )
				)
				( pin "U7C1.E30"
					( objectStatus "vss(415)" )
				)
				( pin "U7C1.E28"
					( objectStatus "vss(416)" )
				)
				( pin "U7C1.E26"
					( objectStatus "vss(417)" )
				)
				( pin "U7C1.E24"
					( objectStatus "vss(418)" )
				)
				( pin "U7C1.E22"
					( objectStatus "vss(419)" )
				)
				( pin "U7C1.E20"
					( objectStatus "vss(420)" )
				)
				( pin "U7C1.E15"
					( objectStatus "vss(421)" )
				)
				( pin "U7C1.E13"
					( objectStatus "vss(422)" )
				)
				( pin "U7C1.E11"
					( objectStatus "vss(423)" )
				)
				( pin "U7C1.D47"
					( objectStatus "vss(424)" )
				)
				( pin "U7C1.E65"
					( objectStatus "vss(425)" )
				)
				( pin "U7C1.E59"
					( objectStatus "vss(426)" )
				)
				( pin "U7C1.D27"
					( objectStatus "vss(427)" )
				)
				( pin "U7C1.D25"
					( objectStatus "vss(428)" )
				)
				( pin "U7C1.D19"
					( objectStatus "vss(429)" )
				)
				( pin "U7C1.D16"
					( objectStatus "vss(430)" )
				)
				( pin "U7C1.D12"
					( objectStatus "vss(431)" )
				)
				( pin "U7C1.C65"
					( objectStatus "vss(432)" )
				)
				( pin "U7C1.C41"
					( objectStatus "vss(433)" )
				)
				( pin "U7C1.C37"
					( objectStatus "vss(434)" )
				)
				( pin "U7C1.C34"
					( objectStatus "vss(435)" )
				)
				( pin "U7C1.C30"
					( objectStatus "vss(436)" )
				)
				( pin "U7C1.C22"
					( objectStatus "vss(437)" )
				)
				( pin "U7C1.B47"
					( objectStatus "vss(438)" )
				)
				( pin "U7C1.B27"
					( objectStatus "vss(439)" )
				)
				( pin "U7C1.B25"
					( objectStatus "vss(440)" )
				)
				( pin "U7C1.B19"
					( objectStatus "vss(441)" )
				)
				( pin "U7C1.B12"
					( objectStatus "vss(442)" )
				)
				( pin "U7C1.A41"
					( objectStatus "vss(443)" )
				)
				( pin "U7C1.A37"
					( objectStatus "vss(444)" )
				)
				( pin "U7C1.A34"
					( objectStatus "vss(445)" )
				)
				( pin "U7C1.A30"
					( objectStatus "vss(446)" )
				)
				( pin "U7C1.A22"
					( objectStatus "vss(447)" )
				)
				( pin "U7C1.A18"
					( objectStatus "vss(448)" )
				)
				( pin "U7C1.Y70"
					( objectStatus "vss(449)" )
				)
				( pin "U7C1.Y72"
					( objectStatus "vss(450)" )
				)
				( pin "U7C1.AT37"
					( objectStatus "vss(451)" )
				)
				( pin "U7C1.BB48"
					( objectStatus "vss(452)" )
				)
				( pin "U7C1.CA70"
					( objectStatus "vss(453)" )
				)
				( pin "U7C1.BW72"
					( objectStatus "vss(454)" )
				)
				( pin "U7C1.BW70"
					( objectStatus "vss(455)" )
				)
				( pin "U7C1.BU72"
					( objectStatus "vss(456)" )
				)
				( pin "U7C1.BR72"
					( objectStatus "vss(457)" )
				)
				( pin "U7C1.G72"
					( objectStatus "vss(458)" )
				)
				( pin "U7C1.G1"
					( objectStatus "vss(459)" )
				)
				( pin "U7C1.E72"
					( objectStatus "vss(460)" )
				)
				( pin "U7C1.E1"
					( objectStatus "vss(461)" )
				)
				( pin "U7C1.C72"
					( objectStatus "vss(462)" )
				)
				( pin "U7C1.C3"
					( objectStatus "vss(463)" )
				)
				( pin "U7C1.BR1"
					( objectStatus "vss(464)" )
				)
				( pin "U7C1.BU1"
					( objectStatus "vss(465)" )
				)
				( pin "U7C1.BW1"
					( objectStatus "vss(466)" )
				)
				( pin "U7C1.CA3"
					( objectStatus "vss(467)" )
				)
				( pin "U7C1.A70"
					( objectStatus "vss(468)" )
				)
				( pin "U7C1.CA5"
					( objectStatus "vss(469)" )
				)
				( pin "U7C1.CA7"
					( objectStatus "vss(470)" )
				)
				( pin "U7C1.CA9"
					( objectStatus "vss(471)" )
				)
				( pin "U7C1.CA65"
					( objectStatus "vss(472)" )
				)
				( pin "U7C1.CA66"
					( objectStatus "vss(473)" )
				)
				( pin "U7C1.CA68"
					( objectStatus "vss(474)" )
				)
				( pin "U7C1.BN72"
					( objectStatus "vss(475)" )
				)
				( pin "U7C1.BN1"
					( objectStatus "vss(476)" )
				)
				( pin "U7C1.J72"
					( objectStatus "vss(477)" )
				)
				( pin "U7C1.J1"
					( objectStatus "vss(478)" )
				)
				( pin "U7C1.A68"
					( objectStatus "vss(479)" )
				)
				( pin "U7C1.A66"
					( objectStatus "vss(480)" )
				)
				( pin "U7C1.A65"
					( objectStatus "vss(481)" )
				)
				( pin "U7C1.A9"
					( objectStatus "vss(482)" )
				)
				( pin "U7C1.A7"
					( objectStatus "vss(483)" )
				)
				( pin "U7C1.A5"
					( objectStatus "vss(484)" )
				)
				( pin "U7C1.E3"
					( objectStatus "vss(485)" )
				)
				( pin "U7C1.F3"
					( objectStatus "vss(486)" )
				)
				( pin "U7C1.BR3"
					( objectStatus "vss(487)" )
				)
				( pin "U7C1.BU3"
					( objectStatus "vss(488)" )
				)
				( pin "U7C1.E70"
					( objectStatus "vss(489)" )
				)
				( pin "U7C1.F70"
					( objectStatus "vss(490)" )
				)
				( pin "U7C1.BR70"
					( objectStatus "vss(491)" )
				)
				( pin "U7C1.BU70"
					( objectStatus "vss(492)" )
				)
				( pin "U7C1.BT69"
					( objectStatus "vss(493)" )
				)
				( pin "U7C1.BP69"
					( objectStatus "vss(494)" )
				)
			)
			( gate "U7C1"
				( objectStatus "@baseboard_fab2_lib.baseboard_fab2(sch_1):page123_i21" )
				( pin "U7C1.AE27"
					( objectStatus "vccmphy_1p05(13)" )
				)
				( pin "U7C1.AU36"
					( objectStatus "vccprim_avid(0)" )
				)
				( pin "U7C1.AU34"
					( objectStatus "vccprim_avid(1)" )
				)
				( pin "U7C1.AU32"
					( objectStatus "vccprim_avid(2)" )
				)
				( pin "U7C1.AT36"
					( objectStatus "vccprim_avid(3)" )
				)
				( pin "U7C1.AT34"
					( objectStatus "vccprim_avid(4)" )
				)
				( pin "U7C1.AT32"
					( objectStatus "vccprim_avid(5)" )
				)
				( pin "U7C1.AP39"
					( objectStatus "vccprim_avid(6)" )
				)
				( pin "U7C1.AP37"
					( objectStatus "vccprim_avid(7)" )
				)
				( pin "U7C1.AP36"
					( objectStatus "vccprim_avid(8)" )
				)
				( pin "U7C1.AP34"
					( objectStatus "vccprim_avid(9)" )
				)
				( pin "U7C1.AP32"
					( objectStatus "vccprim_avid(10)" )
				)
				( pin "U7C1.AM39"
					( objectStatus "vccprim_avid(11)" )
				)
				( pin "U7C1.AM37"
					( objectStatus "vccprim_avid(12)" )
				)
				( pin "U7C1.AM36"
					( objectStatus "vccprim_avid(13)" )
				)
				( pin "U7C1.AM34"
					( objectStatus "vccprim_avid(14)" )
				)
				( pin "U7C1.AM32"
					( objectStatus "vccprim_avid(15)" )
				)
				( pin "U7C1.AK39"
					( objectStatus "vccprim_avid(16)" )
				)
				( pin "U7C1.AK37"
					( objectStatus "vccprim_avid(17)" )
				)
				( pin "U7C1.AK34"
					( objectStatus "vccprim_avid(18)" )
				)
				( pin "U7C1.AG39"
					( objectStatus "vccprim_avid(19)" )
				)
				( pin "U7C1.AG37"
					( objectStatus "vccprim_avid(20)" )
				)
				( pin "U7C1.AG36"
					( objectStatus "vccprim_avid(21)" )
				)
				( pin "U7C1.AG34"
					( objectStatus "vccprim_avid(22)" )
				)
				( pin "U7C1.AG32"
					( objectStatus "vccprim_avid(23)" )
				)
				( pin "U7C1.AE41"
					( objectStatus "vccprim_avid(24)" )
				)
				( pin "U7C1.AE39"
					( objectStatus "vccprim_avid(25)" )
				)
				( pin "U7C1.AE37"
					( objectStatus "vccprim_avid(26)" )
				)
				( pin "U7C1.AE36"
					( objectStatus "vccprim_avid(27)" )
				)
				( pin "U7C1.AE34"
					( objectStatus "vccprim_avid(28)" )
				)
				( pin "U7C1.AE32"
					( objectStatus "vccprim_avid(29)" )
				)
				( pin "U7C1.AE30"
					( objectStatus "vccprim_avid(30)" )
				)
				( pin "U7C1.U27"
					( objectStatus "vccprim_avid(31)" )
				)
				( pin "U7C1.AC41"
					( objectStatus "vccprim_avid(32)" )
				)
				( pin "U7C1.AC39"
					( objectStatus "vccprim_avid(33)" )
				)
				( pin "U7C1.AC37"
					( objectStatus "vccprim_avid(34)" )
				)
				( pin "U7C1.AC36"
					( objectStatus "vccprim_avid(35)" )
				)
				( pin "U7C1.AC34"
					( objectStatus "vccprim_avid(36)" )
				)
				( pin "U7C1.AC32"
					( objectStatus "vccprim_avid(37)" )
				)
				( pin "U7C1.AC30"
					( objectStatus "vccprim_avid(38)" )
				)
				( pin "U7C1.AC29"
					( objectStatus "vccprim_avid(39)" )
				)
				( pin "U7C1.AA41"
					( objectStatus "vccprim_avid(40)" )
				)
				( pin "U7C1.AA39"
					( objectStatus "vccprim_avid(41)" )
				)
				( pin "U7C1.AA37"
					( objectStatus "vccprim_avid(42)" )
				)
				( pin "U7C1.AA36"
					( objectStatus "vccprim_avid(43)" )
				)
				( pin "U7C1.AA34"
					( objectStatus "vccprim_avid(44)" )
				)
				( pin "U7C1.AA32"
					( objectStatus "vccprim_avid(45)" )
				)
				( pin "U7C1.AA30"
					( objectStatus "vccprim_avid(46)" )
				)
				( pin "U7C1.AA29"
					( objectStatus "vccprim_avid(47)" )
				)
				( pin "U7C1.Y41"
					( objectStatus "vccprim_avid(48)" )
				)
				( pin "U7C1.Y39"
					( objectStatus "vccprim_avid(49)" )
				)
				( pin "U7C1.Y37"
					( objectStatus "vccprim_avid(50)" )
				)
				( pin "U7C1.Y36"
					( objectStatus "vccprim_avid(51)" )
				)
				( pin "U7C1.Y34"
					( objectStatus "vccprim_avid(52)" )
				)
				( pin "U7C1.Y32"
					( objectStatus "vccprim_avid(53)" )
				)
				( pin "U7C1.Y30"
					( objectStatus "vccprim_avid(54)" )
				)
				( pin "U7C1.Y29"
					( objectStatus "vccprim_avid(55)" )
				)
				( pin "U7C1.V40"
					( objectStatus "vccprim_avid(56)" )
				)
				( pin "U7C1.V33"
					( objectStatus "vccprim_avid(57)" )
				)
				( pin "U7C1.V29"
					( objectStatus "vccprim_avid(58)" )
				)
				( pin "U7C1.U38"
					( objectStatus "vccprim_avid(59)" )
				)
				( pin "U7C1.U35"
					( objectStatus "vccprim_avid(60)" )
				)
				( pin "U7C1.U31"
					( objectStatus "vccprim_avid(61)" )
				)
				( pin "U7C1.AK32"
					( objectStatus "vccprim_avid(62)" )
				)
				( pin "U7C1.V37"
					( objectStatus "vccprim_avid_qat_sense" )
				)
				( pin "U7C1.AK36"
					( objectStatus "vccprim_avid_sense" )
				)
			)
			( gate "U7C1"
				( objectStatus "@baseboard_fab2_lib.baseboard_fab2(sch_1):page124_i15" )
				( pin "U7C1.CA52"
					( objectStatus "vss(0)" )
				)
				( pin "U7C1.CA50"
					( objectStatus "vss(1)" )
				)
				( pin "U7C1.CA26"
					( objectStatus "vss(2)" )
				)
				( pin "U7C1.CA18"
					( objectStatus "vss(3)" )
				)
				( pin "U7C1.CA15"
					( objectStatus "vss(4)" )
				)
				( pin "U7C1.BY49"
					( objectStatus "vss(5)" )
				)
				( pin "U7C1.BY40"
					( objectStatus "vss(6)" )
				)
				( pin "U7C1.BW52"
					( objectStatus "vss(7)" )
				)
				( pin "U7C1.BW26"
					( objectStatus "vss(8)" )
				)
				( pin "U7C1.BW18"
					( objectStatus "vss(9)" )
				)
				( pin "U7C1.BW15"
					( objectStatus "vss(10)" )
				)
				( pin "U7C1.BV40"
					( objectStatus "vss(11)" )
				)
				( pin "U7C1.BU9"
					( objectStatus "vss(12)" )
				)
				( pin "U7C1.BU63"
					( objectStatus "vss(13)" )
				)
				( pin "U7C1.BU61"
					( objectStatus "vss(14)" )
				)
				( pin "U7C1.BU59"
					( objectStatus "vss(15)" )
				)
				( pin "U7C1.BU57"
					( objectStatus "vss(16)" )
				)
				( pin "U7C1.BU54"
					( objectStatus "vss(17)" )
				)
				( pin "U7C1.BU52"
					( objectStatus "vss(18)" )
				)
				( pin "U7C1.BU50"
					( objectStatus "vss(19)" )
				)
				( pin "U7C1.BU48"
					( objectStatus "vss(20)" )
				)
				( pin "U7C1.BU45"
					( objectStatus "vss(21)" )
				)
				( pin "U7C1.BU43"
					( objectStatus "vss(22)" )
				)
				( pin "U7C1.BU41"
					( objectStatus "vss(23)" )
				)
				( pin "U7C1.BU39"
					( objectStatus "vss(24)" )
				)
				( pin "U7C1.BU37"
					( objectStatus "vss(25)" )
				)
				( pin "U7C1.BU34"
					( objectStatus "vss(26)" )
				)
				( pin "U7C1.BU32"
					( objectStatus "vss(27)" )
				)
				( pin "U7C1.BU30"
					( objectStatus "vss(28)" )
				)
				( pin "U7C1.BU28"
					( objectStatus "vss(29)" )
				)
				( pin "U7C1.BU26"
					( objectStatus "vss(30)" )
				)
				( pin "U7C1.BU24"
					( objectStatus "vss(31)" )
				)
				( pin "U7C1.BU22"
					( objectStatus "vss(32)" )
				)
				( pin "U7C1.BU20"
					( objectStatus "vss(33)" )
				)
				( pin "U7C1.BU18"
					( objectStatus "vss(34)" )
				)
				( pin "U7C1.BU15"
					( objectStatus "vss(35)" )
				)
				( pin "U7C1.BV49"
					( objectStatus "vss(36)" )
				)
				( pin "U7C1.BU11"
					( objectStatus "vss(37)" )
				)
				( pin "U7C1.BU13"
					( objectStatus "vss(38)" )
				)
				( pin "U7C1.BT66"
					( objectStatus "vss(39)" )
				)
				( pin "U7C1.BR6"
					( objectStatus "vss(40)" )
				)
				( pin "U7C1.BR58"
					( objectStatus "vss(41)" )
				)
				( pin "U7C1.BR54"
					( objectStatus "vss(42)" )
				)
				( pin "U7C1.BT8"
					( objectStatus "vss(43)" )
				)
				( pin "U7C1.BR50"
					( objectStatus "vss(44)" )
				)
				( pin "U7C1.BR20"
					( objectStatus "vss(45)" )
				)
				( pin "U7C1.BN66"
					( objectStatus "vss(46)" )
				)
				( pin "U7C1.BN52"
					( objectStatus "vss(47)" )
				)
				( pin "U7C1.BN5"
					( objectStatus "vss(48)" )
				)
				( pin "U7C1.BN59"
					( objectStatus "vss(49)" )
				)
				( pin "U7C1.BN22"
					( objectStatus "vss(50)" )
				)
				( pin "U7C1.BM9"
					( objectStatus "vss(51)" )
				)
				( pin "U7C1.BM71"
					( objectStatus "vss(52)" )
				)
				( pin "U7C1.BM69"
					( objectStatus "vss(53)" )
				)
				( pin "U7C1.BM58"
					( objectStatus "vss(54)" )
				)
				( pin "U7C1.BM50"
					( objectStatus "vss(55)" )
				)
				( pin "U7C1.BM46"
					( objectStatus "vss(56)" )
				)
				( pin "U7C1.BN37"
					( objectStatus "vss(57)" )
				)
				( pin "U7C1.BM17"
					( objectStatus "vss(58)" )
				)
				( pin "U7C1.BM13"
					( objectStatus "vss(59)" )
				)
				( pin "U7C1.BL72"
					( objectStatus "vss(60)" )
				)
				( pin "U7C1.BL70"
					( objectStatus "vss(61)" )
				)
				( pin "U7C1.BL63"
					( objectStatus "vss(62)" )
				)
				( pin "U7C1.BL5"
					( objectStatus "vss(63)" )
				)
				( pin "U7C1.BL37"
					( objectStatus "vss(64)" )
				)
				( pin "U7C1.BL68"
					( objectStatus "vss(65)" )
				)
				( pin "U7C1.BL40"
					( objectStatus "vss(66)" )
				)
				( pin "U7C1.BL22"
					( objectStatus "vss(67)" )
				)
				( pin "U7C1.BK50"
					( objectStatus "vss(68)" )
				)
				( pin "U7C1.BK42"
					( objectStatus "vss(69)" )
				)
				( pin "U7C1.BK38"
					( objectStatus "vss(70)" )
				)
				( pin "U7C1.BK35"
					( objectStatus "vss(71)" )
				)
				( pin "U7C1.BK31"
					( objectStatus "vss(72)" )
				)
				( pin "U7C1.BK27"
					( objectStatus "vss(73)" )
				)
				( pin "U7C1.BK24"
					( objectStatus "vss(74)" )
				)
			)
			( gate "U7C1"
				( objectStatus "@baseboard_fab2_lib.baseboard_fab2(sch_1):page124_i16" )
				( pin "U7C1.BJ68"
					( objectStatus "vss(75)" )
				)
				( pin "U7C1.BJ52"
					( objectStatus "vss(76)" )
				)
				( pin "U7C1.BJ33"
					( objectStatus "vss(77)" )
				)
				( pin "U7C1.BJ3"
					( objectStatus "vss(78)" )
				)
				( pin "U7C1.BJ26"
					( objectStatus "vss(79)" )
				)
				( pin "U7C1.BJ18"
					( objectStatus "vss(80)" )
				)
				( pin "U7C1.BJ15"
					( objectStatus "vss(81)" )
				)
				( pin "U7C1.BJ7"
					( objectStatus "vss(82)" )
				)
				( pin "U7C1.BJ5"
					( objectStatus "vss(83)" )
				)
				( pin "U7C1.BJ11"
					( objectStatus "vss(84)" )
				)
				( pin "U7C1.BJ1"
					( objectStatus "vss(85)" )
				)
				( pin "U7C1.BH54"
					( objectStatus "vss(86)" )
				)
				( pin "U7C1.BH46"
					( objectStatus "vss(87)" )
				)
				( pin "U7C1.BH42"
					( objectStatus "vss(88)" )
				)
				( pin "U7C1.BH38"
					( objectStatus "vss(89)" )
				)
				( pin "U7C1.BH27"
					( objectStatus "vss(90)" )
				)
				( pin "U7C1.BG63"
					( objectStatus "vss(91)" )
				)
				( pin "U7C1.BG59"
					( objectStatus "vss(92)" )
				)
				( pin "U7C1.BG48"
					( objectStatus "vss(93)" )
				)
				( pin "U7C1.BG33"
					( objectStatus "vss(94)" )
				)
				( pin "U7C1.BF9"
					( objectStatus "vss(95)" )
				)
				( pin "U7C1.BF68"
					( objectStatus "vss(96)" )
				)
				( pin "U7C1.BF65"
					( objectStatus "vss(97)" )
				)
				( pin "U7C1.BF61"
					( objectStatus "vss(98)" )
				)
				( pin "U7C1.BF58"
					( objectStatus "vss(99)" )
				)
				( pin "U7C1.BF50"
					( objectStatus "vss(100)" )
				)
				( pin "U7C1.BF5"
					( objectStatus "vss(101)" )
				)
				( pin "U7C1.BF42"
					( objectStatus "vss(102)" )
				)
				( pin "U7C1.BF38"
					( objectStatus "vss(103)" )
				)
				( pin "U7C1.BF27"
					( objectStatus "vss(104)" )
				)
				( pin "U7C1.BF24"
					( objectStatus "vss(105)" )
				)
				( pin "U7C1.BF20"
					( objectStatus "vss(106)" )
				)
				( pin "U7C1.BG44"
					( objectStatus "vss(107)" )
				)
				( pin "U7C1.BF54"
					( objectStatus "vss(108)" )
				)
				( pin "U7C1.BF17"
					( objectStatus "vss(109)" )
				)
				( pin "U7C1.BF13"
					( objectStatus "vss(110)" )
				)
				( pin "U7C1.BE66"
					( objectStatus "vss(111)" )
				)
				( pin "U7C1.BE63"
					( objectStatus "vss(112)" )
				)
				( pin "U7C1.BE59"
					( objectStatus "vss(113)" )
				)
				( pin "U7C1.BE56"
					( objectStatus "vss(114)" )
				)
				( pin "U7C1.BE37"
					( objectStatus "vss(115)" )
				)
				( pin "U7C1.BE33"
					( objectStatus "vss(116)" )
				)
				( pin "U7C1.BE29"
					( objectStatus "vss(117)" )
				)
				( pin "U7C1.BD68"
					( objectStatus "vss(118)" )
				)
				( pin "U7C1.BD54"
					( objectStatus "vss(119)" )
				)
				( pin "U7C1.BD50"
					( objectStatus "vss(120)" )
				)
				( pin "U7C1.BD5"
					( objectStatus "vss(121)" )
				)
				( pin "U7C1.BD35"
					( objectStatus "vss(122)" )
				)
				( pin "U7C1.BD31"
					( objectStatus "vss(123)" )
				)
				( pin "U7C1.BD27"
					( objectStatus "vss(124)" )
				)
				( pin "U7C1.BD24"
					( objectStatus "vss(125)" )
				)
				( pin "U7C1.BC71"
					( objectStatus "vss(126)" )
				)
				( pin "U7C1.BC69"
					( objectStatus "vss(127)" )
				)
				( pin "U7C1.BB72"
					( objectStatus "vss(128)" )
				)
				( pin "U7C1.BB70"
					( objectStatus "vss(129)" )
				)
				( pin "U7C1.BB68"
					( objectStatus "vss(130)" )
				)
				( pin "U7C1.BB66"
					( objectStatus "vss(131)" )
				)
				( pin "U7C1.BB59"
					( objectStatus "vss(132)" )
				)
				( pin "U7C1.BB44"
					( objectStatus "vss(133)" )
				)
				( pin "U7C1.BB22"
					( objectStatus "vss(134)" )
				)
				( pin "U7C1.BB18"
					( objectStatus "vss(135)" )
				)
				( pin "U7C1.BB15"
					( objectStatus "vss(136)" )
				)
				( pin "U7C1.BB11"
					( objectStatus "vss(137)" )
				)
				( pin "U7C1.BB7"
					( objectStatus "vss(138)" )
				)
				( pin "U7C1.BB5"
					( objectStatus "vss(139)" )
				)
				( pin "U7C1.BA58"
					( objectStatus "vss(140)" )
				)
				( pin "U7C1.BA54"
					( objectStatus "vss(141)" )
				)
				( pin "U7C1.BA50"
					( objectStatus "vss(142)" )
				)
				( pin "U7C1.AY68"
					( objectStatus "vss(143)" )
				)
				( pin "U7C1.AY63"
					( objectStatus "vss(144)" )
				)
				( pin "U7C1.AY56"
					( objectStatus "vss(145)" )
				)
				( pin "U7C1.AY22"
					( objectStatus "vss(146)" )
				)
				( pin "U7C1.AY5"
					( objectStatus "vss(147)" )
				)
				( pin "U7C1.AW61"
					( objectStatus "vss(148)" )
				)
				( pin "U7C1.AW58"
					( objectStatus "vss(149)" )
				)
				( pin "U7C1.AW50"
					( objectStatus "vss(150)" )
				)
				( pin "U7C1.AW46"
					( objectStatus "vss(151)" )
				)
				( pin "U7C1.AW41"
					( objectStatus "vss(152)" )
				)
				( pin "U7C1.AW39"
					( objectStatus "vss(153)" )
				)
				( pin "U7C1.AW37"
					( objectStatus "vss(154)" )
				)
				( pin "U7C1.AW36"
					( objectStatus "vss(155)" )
				)
				( pin "U7C1.AW34"
					( objectStatus "vss(156)" )
				)
				( pin "U7C1.AW32"
					( objectStatus "vss(157)" )
				)
				( pin "U7C1.AW30"
					( objectStatus "vss(158)" )
				)
				( pin "U7C1.AW26"
					( objectStatus "vss(159)" )
				)
				( pin "U7C1.AW17"
					( objectStatus "vss(160)" )
				)
				( pin "U7C1.AW13"
					( objectStatus "vss(161)" )
				)
				( pin "U7C1.AW9"
					( objectStatus "vss(162)" )
				)
				( pin "U7C1.AV68"
					( objectStatus "vss(163)" )
				)
				( pin "U7C1.AV59"
					( objectStatus "vss(164)" )
				)
				( pin "U7C1.AV22"
					( objectStatus "vss(165)" )
				)
				( pin "U7C1.AV5"
					( objectStatus "vss(166)" )
				)
				( pin "U7C1.AU61"
					( objectStatus "vss(167)" )
				)
				( pin "U7C1.AU54"
					( objectStatus "vss(168)" )
				)
				( pin "U7C1.AU50"
					( objectStatus "vss(169)" )
				)
				( pin "U7C1.AU46"
					( objectStatus "vss(170)" )
				)
				( pin "U7C1.AU41"
					( objectStatus "vss(171)" )
				)
				( pin "U7C1.AE22"
					( objectStatus "vss(172)" )
				)
				( pin "U7C1.AU30"
					( objectStatus "vss(173)" )
				)
				( pin "U7C1.AU26"
					( objectStatus "vss(174)" )
				)
				( pin "U7C1.AT59"
					( objectStatus "vss(175)" )
				)
				( pin "U7C1.AT46"
					( objectStatus "vss(176)" )
				)
				( pin "U7C1.AT41"
					( objectStatus "vss(177)" )
				)
				( pin "U7C1.AT30"
					( objectStatus "vss(178)" )
				)
				( pin "U7C1.AT26"
					( objectStatus "vss(179)" )
				)
				( pin "U7C1.AT22"
					( objectStatus "vss(180)" )
				)
				( pin "U7C1.AT18"
					( objectStatus "vss(181)" )
				)
				( pin "U7C1.AT15"
					( objectStatus "vss(182)" )
				)
				( pin "U7C1.AT11"
					( objectStatus "vss(183)" )
				)
				( pin "U7C1.AT7"
					( objectStatus "vss(184)" )
				)
				( pin "U7C1.AR72"
					( objectStatus "vss(185)" )
				)
				( pin "U7C1.AR70"
					( objectStatus "vss(186)" )
				)
				( pin "U7C1.AR68"
					( objectStatus "vss(187)" )
				)
				( pin "U7C1.AR65"
					( objectStatus "vss(188)" )
				)
				( pin "U7C1.AR58"
					( objectStatus "vss(189)" )
				)
				( pin "U7C1.AR50"
					( objectStatus "vss(190)" )
				)
				( pin "U7C1.AR5"
					( objectStatus "vss(191)" )
				)
				( pin "U7C1.AP66"
					( objectStatus "vss(192)" )
				)
				( pin "U7C1.AP52"
					( objectStatus "vss(193)" )
				)
				( pin "U7C1.AP46"
					( objectStatus "vss(194)" )
				)
				( pin "U7C1.AP41"
					( objectStatus "vss(195)" )
				)
				( pin "U7C1.AP4"
					( objectStatus "vss(196)" )
				)
				( pin "U7C1.AP30"
					( objectStatus "vss(197)" )
				)
				( pin "U7C1.AP26"
					( objectStatus "vss(198)" )
				)
				( pin "U7C1.AP2"
					( objectStatus "vss(199)" )
				)
				( pin "U7C1.AN9"
					( objectStatus "vss(200)" )
				)
				( pin "U7C1.AN58"
					( objectStatus "vss(201)" )
				)
				( pin "U7C1.AN5"
					( objectStatus "vss(202)" )
				)
				( pin "U7C1.AN20"
					( objectStatus "vss(203)" )
				)
				( pin "U7C1.AP22"
					( objectStatus "vss(204)" )
				)
				( pin "U7C1.AN68"
					( objectStatus "vss(205)" )
				)
				( pin "U7C1.AN17"
					( objectStatus "vss(206)" )
				)
				( pin "U7C1.AN13"
					( objectStatus "vss(207)" )
				)
				( pin "U7C1.AM46"
					( objectStatus "vss(208)" )
				)
				( pin "U7C1.AM41"
					( objectStatus "vss(209)" )
				)
				( pin "U7C1.AM30"
					( objectStatus "vss(210)" )
				)
				( pin "U7C1.AM26"
					( objectStatus "vss(211)" )
				)
				( pin "U7C1.AL72"
					( objectStatus "vss(212)" )
				)
				( pin "U7C1.AL70"
					( objectStatus "vss(213)" )
				)
				( pin "U7C1.AL68"
					( objectStatus "vss(214)" )
				)
			)
			( gate "U7C1"
				( objectStatus "@baseboard_fab2_lib.baseboard_fab2(sch_1):page124_i17" )
				( pin "U7C1.AL59"
					( objectStatus "vss(215)" )
				)
				( pin "U7C1.AL52"
					( objectStatus "vss(216)" )
				)
				( pin "U7C1.AL5"
					( objectStatus "vss(217)" )
				)
				( pin "U7C1.AL22"
					( objectStatus "vss(218)" )
				)
				( pin "U7C1.AK71"
					( objectStatus "vss(219)" )
				)
				( pin "U7C1.AK69"
					( objectStatus "vss(220)" )
				)
				( pin "U7C1.AK61"
					( objectStatus "vss(221)" )
				)
				( pin "U7C1.AK58"
					( objectStatus "vss(222)" )
				)
				( pin "U7C1.AK48"
					( objectStatus "vss(223)" )
				)
				( pin "U7C1.AK46"
					( objectStatus "vss(224)" )
				)
				( pin "U7C1.AK41"
					( objectStatus "vss(225)" )
				)
				( pin "U7C1.AK26"
					( objectStatus "vss(226)" )
				)
				( pin "U7C1.AJ7"
					( objectStatus "vss(227)" )
				)
				( pin "U7C1.AJ68"
					( objectStatus "vss(228)" )
				)
				( pin "U7C1.AJ66"
					( objectStatus "vss(229)" )
				)
				( pin "U7C1.AJ59"
					( objectStatus "vss(230)" )
				)
				( pin "U7C1.AJ52"
					( objectStatus "vss(231)" )
				)
				( pin "U7C1.AJ5"
					( objectStatus "vss(232)" )
				)
				( pin "U7C1.AJ41"
					( objectStatus "vss(233)" )
				)
				( pin "U7C1.AJ39"
					( objectStatus "vss(234)" )
				)
				( pin "U7C1.AJ37"
					( objectStatus "vss(235)" )
				)
				( pin "U7C1.AJ36"
					( objectStatus "vss(236)" )
				)
				( pin "U7C1.AJ34"
					( objectStatus "vss(237)" )
				)
				( pin "U7C1.AJ30"
					( objectStatus "vss(238)" )
				)
				( pin "U7C1.AJ26"
					( objectStatus "vss(239)" )
				)
				( pin "U7C1.AJ22"
					( objectStatus "vss(240)" )
				)
				( pin "U7C1.AJ18"
					( objectStatus "vss(241)" )
				)
				( pin "U7C1.AJ15"
					( objectStatus "vss(242)" )
				)
				( pin "U7C1.AK30"
					( objectStatus "vss(243)" )
				)
				( pin "U7C1.AJ56"
					( objectStatus "vss(244)" )
				)
				( pin "U7C1.AJ32"
					( objectStatus "vss(245)" )
				)
				( pin "U7C1.AJ11"
					( objectStatus "vss(246)" )
				)
				( pin "U7C1.AH20"
					( objectStatus "vss(247)" )
				)
				( pin "U7C1.AG66"
					( objectStatus "vss(248)" )
				)
				( pin "U7C1.AG59"
					( objectStatus "vss(249)" )
				)
				( pin "U7C1.AG56"
					( objectStatus "vss(250)" )
				)
				( pin "U7C1.AG52"
					( objectStatus "vss(251)" )
				)
				( pin "U7C1.AG43"
					( objectStatus "vss(252)" )
				)
				( pin "U7C1.AG41"
					( objectStatus "vss(253)" )
				)
				( pin "U7C1.AG30"
					( objectStatus "vss(254)" )
				)
				( pin "U7C1.AG26"
					( objectStatus "vss(255)" )
				)
				( pin "U7C1.AF68"
					( objectStatus "vss(256)" )
				)
				( pin "U7C1.AF3"
					( objectStatus "vss(257)" )
				)
				( pin "U7C1.AF24"
					( objectStatus "vss(258)" )
				)
				( pin "U7C1.AF17"
					( objectStatus "vss(259)" )
				)
				( pin "U7C1.AF9"
					( objectStatus "vss(260)" )
				)
				( pin "U7C1.AF5"
					( objectStatus "vss(261)" )
				)
				( pin "U7C1.AF13"
					( objectStatus "vss(262)" )
				)
				( pin "U7C1.AF1"
					( objectStatus "vss(263)" )
				)
				( pin "U7C1.AE66"
					( objectStatus "vss(264)" )
				)
				( pin "U7C1.AE63"
					( objectStatus "vss(265)" )
				)
				( pin "U7C1.AE59"
					( objectStatus "vss(266)" )
				)
				( pin "U7C1.AE56"
					( objectStatus "vss(267)" )
				)
				( pin "U7C1.AE52"
					( objectStatus "vss(268)" )
				)
				( pin "U7C1.AE48"
					( objectStatus "vss(269)" )
				)
				( pin "U7C1.J18"
					( objectStatus "vss(270)" )
				)
				( pin "U7C1.AE29"
					( objectStatus "vss(271)" )
				)
				( pin "U7C1.AD68"
					( objectStatus "vss(272)" )
				)
				( pin "U7C1.AD65"
					( objectStatus "vss(273)" )
				)
				( pin "U7C1.AD5"
					( objectStatus "vss(274)" )
				)
				( pin "U7C1.AC7"
					( objectStatus "vss(275)" )
				)
				( pin "U7C1.AC66"
					( objectStatus "vss(276)" )
				)
				( pin "U7C1.AC63"
					( objectStatus "vss(277)" )
				)
				( pin "U7C1.AC59"
					( objectStatus "vss(278)" )
				)
				( pin "U7C1.AC52"
					( objectStatus "vss(279)" )
				)
				( pin "U7C1.AC48"
					( objectStatus "vss(280)" )
				)
				( pin "U7C1.AC46"
					( objectStatus "vss(281)" )
				)
				( pin "U7C1.AC43"
					( objectStatus "vss(282)" )
				)
				( pin "U7C1.AC27"
					( objectStatus "vss(283)" )
				)
				( pin "U7C1.AD58"
					( objectStatus "vss(284)" )
				)
				( pin "U7C1.AC45"
					( objectStatus "vss(285)" )
				)
				( pin "U7C1.AC22"
					( objectStatus "vss(286)" )
				)
				( pin "U7C1.AC18"
					( objectStatus "vss(287)" )
				)
				( pin "U7C1.AC15"
					( objectStatus "vss(288)" )
				)
				( pin "U7C1.AC11"
					( objectStatus "vss(289)" )
				)
				( pin "U7C1.AB72"
					( objectStatus "vss(290)" )
				)
				( pin "U7C1.AB70"
					( objectStatus "vss(291)" )
				)
				( pin "U7C1.AB68"
					( objectStatus "vss(292)" )
				)
				( pin "U7C1.AB5"
					( objectStatus "vss(293)" )
				)
				( pin "U7C1.AA48"
					( objectStatus "vss(294)" )
				)
				( pin "U7C1.AA43"
					( objectStatus "vss(295)" )
				)
				( pin "U7C1.AA27"
					( objectStatus "vss(296)" )
				)
				( pin "U7C1.AA26"
					( objectStatus "vss(297)" )
				)
				( pin "U7C1.Y68"
					( objectStatus "vss(298)" )
				)
				( pin "U7C1.Y63"
					( objectStatus "vss(299)" )
				)
				( pin "U7C1.Y59"
					( objectStatus "vss(300)" )
				)
				( pin "U7C1.Y52"
					( objectStatus "vss(301)" )
				)
				( pin "U7C1.Y5"
					( objectStatus "vss(302)" )
				)
				( pin "U7C1.Y48"
					( objectStatus "vss(303)" )
				)
				( pin "U7C1.Y27"
					( objectStatus "vss(304)" )
				)
				( pin "U7C1.Y22"
					( objectStatus "vss(305)" )
				)
				( pin "U7C1.W9"
					( objectStatus "vss(306)" )
				)
				( pin "U7C1.W61"
					( objectStatus "vss(307)" )
				)
				( pin "U7C1.Y43"
					( objectStatus "vss(308)" )
				)
				( pin "U7C1.AA50"
					( objectStatus "vss(309)" )
				)
				( pin "U7C1.W24"
					( objectStatus "vss(310)" )
				)
				( pin "U7C1.W20"
					( objectStatus "vss(311)" )
				)
				( pin "U7C1.W17"
					( objectStatus "vss(312)" )
				)
				( pin "U7C1.W13"
					( objectStatus "vss(313)" )
				)
				( pin "U7C1.V68"
					( objectStatus "vss(314)" )
				)
				( pin "U7C1.V66"
					( objectStatus "vss(315)" )
				)
				( pin "U7C1.W58"
					( objectStatus "vss(316)" )
				)
				( pin "U7C1.V52"
					( objectStatus "vss(317)" )
				)
				( pin "U7C1.V5"
					( objectStatus "vss(318)" )
				)
				( pin "U7C1.V48"
					( objectStatus "vss(319)" )
				)
				( pin "U7C1.V26"
					( objectStatus "vss(320)" )
				)
				( pin "U7C1.U58"
					( objectStatus "vss(321)" )
				)
				( pin "U7C1.AG46"
					( objectStatus "vss(322)" )
				)
				( pin "U7C1.AF50"
					( objectStatus "vss(323)" )
				)
				( pin "U7C1.T7"
					( objectStatus "vss(324)" )
				)
				( pin "U7C1.T66"
					( objectStatus "vss(325)" )
				)
				( pin "U7C1.T52"
					( objectStatus "vss(326)" )
				)
				( pin "U7C1.T48"
					( objectStatus "vss(327)" )
				)
				( pin "U7C1.AJ45"
					( objectStatus "vss(328)" )
				)
				( pin "U7C1.T40"
					( objectStatus "vss(329)" )
				)
				( pin "U7C1.T37"
					( objectStatus "vss(330)" )
				)
				( pin "U7C1.T33"
					( objectStatus "vss(331)" )
				)
				( pin "U7C1.T29"
					( objectStatus "vss(332)" )
				)
				( pin "U7C1.T26"
					( objectStatus "vss(333)" )
				)
				( pin "U7C1.T22"
					( objectStatus "vss(334)" )
				)
				( pin "U7C1.T18"
					( objectStatus "vss(335)" )
				)
				( pin "U7C1.T15"
					( objectStatus "vss(336)" )
				)
				( pin "U7C1.T11"
					( objectStatus "vss(337)" )
				)
				( pin "U7C1.R68"
					( objectStatus "vss(338)" )
				)
				( pin "U7C1.R58"
					( objectStatus "vss(339)" )
				)
				( pin "U7C1.T56"
					( objectStatus "vss(340)" )
				)
				( pin "U7C1.R54"
					( objectStatus "vss(341)" )
				)
				( pin "U7C1.R50"
					( objectStatus "vss(342)" )
				)
				( pin "U7C1.R5"
					( objectStatus "vss(343)" )
				)
				( pin "U7C1.U42"
					( objectStatus "vss(344)" )
				)
				( pin "U7C1.R27"
					( objectStatus "vss(345)" )
				)
				( pin "U7C1.P63"
					( objectStatus "vss(346)" )
				)
				( pin "U7C1.AE43"
					( objectStatus "vss(347)" )
				)
				( pin "U7C1.N9"
					( objectStatus "vss(348)" )
				)
				( pin "U7C1.N68"
					( objectStatus "vss(349)" )
				)
				( pin "U7C1.R38"
					( objectStatus "vss(350)" )
				)
				( pin "U7C1.N5"
					( objectStatus "vss(351)" )
				)
				( pin "U7C1.N46"
					( objectStatus "vss(352)" )
				)
				( pin "U7C1.N38"
					( objectStatus "vss(353)" )
				)
				( pin "U7C1.N35"
					( objectStatus "vss(354)" )
				)
			)
			( gate "R2R11"
				( objectStatus "@baseboard_fab2_lib.baseboard_fab2(sch_1):page125_i11" )
				( pin "R2R11.1"
					( objectStatus "a" )
				)
				( pin "R2R11.2"
					( objectStatus "b" )
				)
			)
			( gate "R2T1"
				( objectStatus "@baseboard_fab2_lib.baseboard_fab2(sch_1):page125_i15" )
				( pin "R2T1.1"
					( objectStatus "a" )
				)
				( pin "R2T1.2"
					( objectStatus "b" )
				)
			)
			( gate "R8E6"
				( objectStatus "@baseboard_fab2_lib.baseboard_fab2(sch_1):page125_i21" )
				( pin "R8E6.1"
					( objectStatus "a" )
				)
				( pin "R8E6.2"
					( objectStatus "b" )
				)
			)
			( gate "R8E4"
				( objectStatus "@baseboard_fab2_lib.baseboard_fab2(sch_1):page125_i24" )
				( pin "R8E4.1"
					( objectStatus "a" )
				)
				( pin "R8E4.2"
					( objectStatus "b" )
				)
			)
			( gate "R8C18"
				( objectStatus "@baseboard_fab2_lib.baseboard_fab2(sch_1):page125_i40" )
				( pin "R8C18.1"
					( objectStatus "a" )
				)
				( pin "R8C18.2"
					( objectStatus "b" )
				)
			)
			( gate "R8C17"
				( objectStatus "@baseboard_fab2_lib.baseboard_fab2(sch_1):page125_i41" )
				( pin "R8C17.1"
					( objectStatus "a" )
				)
				( pin "R8C17.2"
					( objectStatus "b" )
				)
			)
			( gate "R8D5"
				( objectStatus "@baseboard_fab2_lib.baseboard_fab2(sch_1):page125_i50" )
				( pin "R8D5.1"
					( objectStatus "a" )
				)
				( pin "R8D5.2"
					( objectStatus "b" )
				)
			)
			( gate "R8D13"
				( objectStatus "@baseboard_fab2_lib.baseboard_fab2(sch_1):page125_i52" )
				( pin "R8D13.1"
					( objectStatus "a" )
				)
				( pin "R8D13.2"
					( objectStatus "b" )
				)
			)
			( gate "R7D13"
				( objectStatus "@baseboard_fab2_lib.baseboard_fab2(sch_1):page125_i60" )
				( pin "R7D13.1"
					( objectStatus "a" )
				)
				( pin "R7D13.2"
					( objectStatus "b" )
				)
			)
			( gate "R7D1"
				( objectStatus "@baseboard_fab2_lib.baseboard_fab2(sch_1):page125_i70" )
				( pin "R7D1.1"
					( objectStatus "a" )
				)
				( pin "R7D1.2"
					( objectStatus "b" )
				)
			)
			( gate "R8D16"
				( objectStatus "@baseboard_fab2_lib.baseboard_fab2(sch_1):page125_i71" )
				( pin "R8D16.1"
					( objectStatus "a" )
				)
				( pin "R8D16.2"
					( objectStatus "b" )
				)
			)
			( gate "R3N2"
				( objectStatus "@baseboard_fab2_lib.baseboard_fab2(sch_1):page125_i72" )
				( pin "R3N2.1"
					( objectStatus "a" )
				)
				( pin "R3N2.2"
					( objectStatus "b" )
				)
			)
			( gate "R2U30"
				( objectStatus "@baseboard_fab2_lib.baseboard_fab2(sch_1):page125_i76" )
				( pin "R2U30.1"
					( objectStatus "a" )
				)
				( pin "R2U30.2"
					( objectStatus "b" )
				)
			)
			( gate "R3N17"
				( objectStatus "@baseboard_fab2_lib.baseboard_fab2(sch_1):page125_i78" )
				( pin "R3N17.1"
					( objectStatus "a" )
				)
				( pin "R3N17.2"
					( objectStatus "b" )
				)
			)
			( gate "R2N14"
				( objectStatus "@baseboard_fab2_lib.baseboard_fab2(sch_1):page125_i83" )
				( pin "R2N14.1"
					( objectStatus "a" )
				)
				( pin "R2N14.2"
					( objectStatus "b" )
				)
			)
			( gate "R7D19"
				( objectStatus "@baseboard_fab2_lib.baseboard_fab2(sch_1):page126_i6" )
				( pin "R7D19.1"
					( objectStatus "a" )
				)
				( pin "R7D19.2"
					( objectStatus "b" )
				)
			)
			( gate "R2N10"
				( objectStatus "@baseboard_fab2_lib.baseboard_fab2(sch_1):page126_i10" )
				( pin "R2N10.1"
					( objectStatus "a" )
				)
				( pin "R2N10.2"
					( objectStatus "b" )
				)
			)
			( gate "R1D35"
				( objectStatus "@baseboard_fab2_lib.baseboard_fab2(sch_1):page126_i12" )
				( pin "R1D35.1"
					( objectStatus "a" )
				)
				( pin "R1D35.2"
					( objectStatus "b" )
				)
			)
			( gate "Q6"
				( objectStatus "@baseboard_fab2_lib.baseboard_fab2(sch_1):page126_i13" )
				( pin "Q6.3"
					( objectStatus "drn" )
				)
				( pin "Q6.1"
					( objectStatus "gate" )
				)
				( pin "Q6.2"
					( objectStatus "src" )
				)
			)
			( gate "R8C9"
				( objectStatus "@baseboard_fab2_lib.baseboard_fab2(sch_1):page126_i20" )
				( pin "R8C9.1"
					( objectStatus "a" )
				)
				( pin "R8C9.2"
					( objectStatus "b" )
				)
			)
			( gate "C3M17"
				( objectStatus "@baseboard_fab2_lib.baseboard_fab2(sch_1):page127_i3" )
				( pin "C3M17.1"
					( objectStatus "a" )
				)
				( pin "C3M17.2"
					( objectStatus "b" )
				)
			)
			( gate "FB3M1"
				( objectStatus "@baseboard_fab2_lib.baseboard_fab2(sch_1):page127_i8" )
				( pin "FB3M1.1"
					( objectStatus "a" )
				)
				( pin "FB3M1.2"
					( objectStatus "b" )
				)
			)
			( gate "C3M21"
				( objectStatus "@baseboard_fab2_lib.baseboard_fab2(sch_1):page127_i9" )
				( pin "C3M21.1"
					( objectStatus "a" )
				)
				( pin "C3M21.2"
					( objectStatus "b" )
				)
			)
			( gate "C3M18"
				( objectStatus "@baseboard_fab2_lib.baseboard_fab2(sch_1):page127_i10" )
				( pin "C3M18.1"
					( objectStatus "a" )
				)
				( pin "C3M18.2"
					( objectStatus "b" )
				)
			)
			( gate "FB3M2"
				( objectStatus "@baseboard_fab2_lib.baseboard_fab2(sch_1):page127_i17" )
				( pin "FB3M2.1"
					( objectStatus "a" )
				)
				( pin "FB3M2.2"
					( objectStatus "b" )
				)
			)
			( gate "C3M22"
				( objectStatus "@baseboard_fab2_lib.baseboard_fab2(sch_1):page127_i18" )
				( pin "C3M22.1"
					( objectStatus "a" )
				)
				( pin "C3M22.2"
					( objectStatus "b" )
				)
			)
			( gate "C3M23"
				( objectStatus "@baseboard_fab2_lib.baseboard_fab2(sch_1):page127_i19" )
				( pin "C3M23.1"
					( objectStatus "a" )
				)
				( pin "C3M23.2"
					( objectStatus "b" )
				)
			)
			( gate "FB3M3"
				( objectStatus "@baseboard_fab2_lib.baseboard_fab2(sch_1):page127_i26" )
				( pin "FB3M3.1"
					( objectStatus "a" )
				)
				( pin "FB3M3.2"
					( objectStatus "b" )
				)
			)
			( gate "C3M30"
				( objectStatus "@baseboard_fab2_lib.baseboard_fab2(sch_1):page127_i27" )
				( pin "C3M30.1"
					( objectStatus "a" )
				)
				( pin "C3M30.2"
					( objectStatus "b" )
				)
			)
			( gate "C3M19"
				( objectStatus "@baseboard_fab2_lib.baseboard_fab2(sch_1):page127_i31" )
				( pin "C3M19.1"
					( objectStatus "a" )
				)
				( pin "C3M19.2"
					( objectStatus "b" )
				)
			)
			( gate "C3M20"
				( objectStatus "@baseboard_fab2_lib.baseboard_fab2(sch_1):page127_i33" )
				( pin "C3M20.1"
					( objectStatus "a" )
				)
				( pin "C3M20.2"
					( objectStatus "b" )
				)
			)
			( gate "C3M27"
				( objectStatus "@baseboard_fab2_lib.baseboard_fab2(sch_1):page127_i35" )
				( pin "C3M27.1"
					( objectStatus "a" )
				)
				( pin "C3M27.2"
					( objectStatus "b" )
				)
			)
			( gate "C2M6"
				( objectStatus "@baseboard_fab2_lib.baseboard_fab2(sch_1):page127_i42" )
				( pin "C2M6.1"
					( objectStatus "a" )
				)
				( pin "C2M6.2"
					( objectStatus "b" )
				)
			)
			( gate "C2M5"
				( objectStatus "@baseboard_fab2_lib.baseboard_fab2(sch_1):page127_i43" )
				( pin "C2M5.1"
					( objectStatus "a" )
				)
				( pin "C2M5.2"
					( objectStatus "b" )
				)
			)
			( gate "C2M7"
				( objectStatus "@baseboard_fab2_lib.baseboard_fab2(sch_1):page127_i44" )
				( pin "C2M7.1"
					( objectStatus "a" )
				)
				( pin "C2M7.2"
					( objectStatus "b" )
				)
			)
			( gate "FB2M1"
				( objectStatus "@baseboard_fab2_lib.baseboard_fab2(sch_1):page127_i46" )
				( pin "FB2M1.1"
					( objectStatus "a" )
				)
				( pin "FB2M1.2"
					( objectStatus "b" )
				)
			)
			( gate "C2M8"
				( objectStatus "@baseboard_fab2_lib.baseboard_fab2(sch_1):page127_i48" )
				( pin "C2M8.1"
					( objectStatus "a" )
				)
				( pin "C2M8.2"
					( objectStatus "b" )
				)
			)
			( gate "C2M10"
				( objectStatus "@baseboard_fab2_lib.baseboard_fab2(sch_1):page127_i49" )
				( pin "C2M10.1"
					( objectStatus "a" )
				)
				( pin "C2M10.2"
					( objectStatus "b" )
				)
			)
			( gate "C2M9"
				( objectStatus "@baseboard_fab2_lib.baseboard_fab2(sch_1):page127_i50" )
				( pin "C2M9.1"
					( objectStatus "a" )
				)
				( pin "C2M9.2"
					( objectStatus "b" )
				)
			)
			( gate "C3M29"
				( objectStatus "@baseboard_fab2_lib.baseboard_fab2(sch_1):page127_i53" )
				( pin "C3M29.1"
					( objectStatus "a" )
				)
				( pin "C3M29.2"
					( objectStatus "b" )
				)
			)
			( gate "C3M24"
				( objectStatus "@baseboard_fab2_lib.baseboard_fab2(sch_1):page127_i54" )
				( pin "C3M24.1"
					( objectStatus "a" )
				)
				( pin "C3M24.2"
					( objectStatus "b" )
				)
			)
			( gate "FB3M4"
				( objectStatus "@baseboard_fab2_lib.baseboard_fab2(sch_1):page127_i56" )
				( pin "FB3M4.1"
					( objectStatus "a" )
				)
				( pin "FB3M4.2"
					( objectStatus "b" )
				)
			)
			( gate "C3M31"
				( objectStatus "@baseboard_fab2_lib.baseboard_fab2(sch_1):page127_i57" )
				( pin "C3M31.1"
					( objectStatus "a" )
				)
				( pin "C3M31.2"
					( objectStatus "b" )
				)
			)
			( gate "C2N1"
				( objectStatus "@baseboard_fab2_lib.baseboard_fab2(sch_1):page127_i63" )
				( pin "C2N1.1"
					( objectStatus "a" )
				)
				( pin "C2N1.2"
					( objectStatus "b" )
				)
			)
			( gate "C2N6"
				( objectStatus "@baseboard_fab2_lib.baseboard_fab2(sch_1):page127_i64" )
				( pin "C2N6.1"
					( objectStatus "a" )
				)
				( pin "C2N6.2"
					( objectStatus "b" )
				)
			)
			( gate "C2N5"
				( objectStatus "@baseboard_fab2_lib.baseboard_fab2(sch_1):page127_i65" )
				( pin "C2N5.1"
					( objectStatus "a" )
				)
				( pin "C2N5.2"
					( objectStatus "b" )
				)
			)
			( gate "FB2M2"
				( objectStatus "@baseboard_fab2_lib.baseboard_fab2(sch_1):page127_i69" )
				( pin "FB2M2.1"
					( objectStatus "a" )
				)
				( pin "FB2M2.2"
					( objectStatus "b" )
				)
			)
			( gate "L2M1"
				( objectStatus "@baseboard_fab2_lib.baseboard_fab2(sch_1):page127_i71" )
				( pin "L2M1.1"
					( objectStatus "ina" )
				)
				( pin "L2M1.2"
					( objectStatus "inb" )
				)
			)
			( gate "C7B25"
				( objectStatus "@baseboard_fab2_lib.baseboard_fab2(sch_1):page129_i35" )
				( pin "C7B25.1"
					( objectStatus "a" )
				)
				( pin "C7B25.2"
					( objectStatus "b" )
				)
			)
			( gate "C7B27"
				( objectStatus "@baseboard_fab2_lib.baseboard_fab2(sch_1):page129_i69" )
				( pin "C7B27.1"
					( objectStatus "a" )
				)
				( pin "C7B27.2"
					( objectStatus "b" )
				)
			)
			( gate "C7B28"
				( objectStatus "@baseboard_fab2_lib.baseboard_fab2(sch_1):page129_i70" )
				( pin "C7B28.1"
					( objectStatus "a" )
				)
				( pin "C7B28.2"
					( objectStatus "b" )
				)
			)
			( gate "C7C2"
				( objectStatus "@baseboard_fab2_lib.baseboard_fab2(sch_1):page129_i71" )
				( pin "C7C2.1"
					( objectStatus "a" )
				)
				( pin "C7C2.2"
					( objectStatus "b" )
				)
			)
			( gate "C3M40"
				( objectStatus "@baseboard_fab2_lib.baseboard_fab2(sch_1):page129_i72" )
				( pin "C3M40.1"
					( objectStatus "a" )
				)
				( pin "C3M40.2"
					( objectStatus "b" )
				)
			)
			( gate "C3M37"
				( objectStatus "@baseboard_fab2_lib.baseboard_fab2(sch_1):page129_i73" )
				( pin "C3M37.1"
					( objectStatus "a" )
				)
				( pin "C3M37.2"
					( objectStatus "b" )
				)
			)
			( gate "C3N9"
				( objectStatus "@baseboard_fab2_lib.baseboard_fab2(sch_1):page129_i74" )
				( pin "C3N9.1"
					( objectStatus "a" )
				)
				( pin "C3N9.2"
					( objectStatus "b" )
				)
			)
			( gate "C3N8"
				( objectStatus "@baseboard_fab2_lib.baseboard_fab2(sch_1):page129_i75" )
				( pin "C3N8.1"
					( objectStatus "a" )
				)
				( pin "C3N8.2"
					( objectStatus "b" )
				)
			)
			( gate "C7C3"
				( objectStatus "@baseboard_fab2_lib.baseboard_fab2(sch_1):page129_i76" )
				( pin "C7C3.1"
					( objectStatus "a" )
				)
				( pin "C7C3.2"
					( objectStatus "b" )
				)
			)
			( gate "C7C1"
				( objectStatus "@baseboard_fab2_lib.baseboard_fab2(sch_1):page129_i77" )
				( pin "C7C1.1"
					( objectStatus "a" )
				)
				( pin "C7C1.2"
					( objectStatus "b" )
				)
			)
			( gate "C7B29"
				( objectStatus "@baseboard_fab2_lib.baseboard_fab2(sch_1):page129_i78" )
				( pin "C7B29.1"
					( objectStatus "a" )
				)
				( pin "C7B29.2"
					( objectStatus "b" )
				)
			)
			( gate "C7B26"
				( objectStatus "@baseboard_fab2_lib.baseboard_fab2(sch_1):page129_i79" )
				( pin "C7B26.1"
					( objectStatus "a" )
				)
				( pin "C7B26.2"
					( objectStatus "b" )
				)
			)
			( gate "C3M44"
				( objectStatus "@baseboard_fab2_lib.baseboard_fab2(sch_1):page129_i80" )
				( pin "C3M44.1"
					( objectStatus "a" )
				)
				( pin "C3M44.2"
					( objectStatus "b" )
				)
			)
			( gate "C3M41"
				( objectStatus "@baseboard_fab2_lib.baseboard_fab2(sch_1):page129_i81" )
				( pin "C3M41.1"
					( objectStatus "a" )
				)
				( pin "C3M41.2"
					( objectStatus "b" )
				)
			)
			( gate "C3M45"
				( objectStatus "@baseboard_fab2_lib.baseboard_fab2(sch_1):page129_i82" )
				( pin "C3M45.1"
					( objectStatus "a" )
				)
				( pin "C3M45.2"
					( objectStatus "b" )
				)
			)
			( gate "C3N13"
				( objectStatus "@baseboard_fab2_lib.baseboard_fab2(sch_1):page129_i83" )
				( pin "C3N13.1"
					( objectStatus "a" )
				)
				( pin "C3N13.2"
					( objectStatus "b" )
				)
			)
			( gate "C7D2"
				( objectStatus "@baseboard_fab2_lib.baseboard_fab2(sch_1):page130_i2" )
				( pin "C7D2.1"
					( objectStatus "a" )
				)
				( pin "C7D2.2"
					( objectStatus "b" )
				)
			)
			( gate "C2N26"
				( objectStatus "@baseboard_fab2_lib.baseboard_fab2(sch_1):page130_i4" )
				( pin "C2N26.1"
					( objectStatus "a" )
				)
				( pin "C2N26.2"
					( objectStatus "b" )
				)
			)
			( gate "C2N19"
				( objectStatus "@baseboard_fab2_lib.baseboard_fab2(sch_1):page130_i7" )
				( pin "C2N19.1"
					( objectStatus "a" )
				)
				( pin "C2N19.2"
					( objectStatus "b" )
				)
			)
			( gate "C2N24"
				( objectStatus "@baseboard_fab2_lib.baseboard_fab2(sch_1):page130_i8" )
				( pin "C2N24.1"
					( objectStatus "a" )
				)
				( pin "C2N24.2"
					( objectStatus "b" )
				)
			)
			( gate "C2N22"
				( objectStatus "@baseboard_fab2_lib.baseboard_fab2(sch_1):page130_i9" )
				( pin "C2N22.1"
					( objectStatus "a" )
				)
				( pin "C2N22.2"
					( objectStatus "b" )
				)
			)
			( gate "C2N20"
				( objectStatus "@baseboard_fab2_lib.baseboard_fab2(sch_1):page130_i12" )
				( pin "C2N20.1"
					( objectStatus "a" )
				)
				( pin "C2N20.2"
					( objectStatus "b" )
				)
			)
			( gate "C2N21"
				( objectStatus "@baseboard_fab2_lib.baseboard_fab2(sch_1):page130_i15" )
				( pin "C2N21.1"
					( objectStatus "a" )
				)
				( pin "C2N21.2"
					( objectStatus "b" )
				)
			)
			( gate "C3N29"
				( objectStatus "@baseboard_fab2_lib.baseboard_fab2(sch_1):page130_i16" )
				( pin "C3N29.1"
					( objectStatus "a" )
				)
				( pin "C3N29.2"
					( objectStatus "b" )
				)
			)
			( gate "C8C3"
				( objectStatus "@baseboard_fab2_lib.baseboard_fab2(sch_1):page130_i19" )
				( pin "C8C3.1"
					( objectStatus "a" )
				)
				( pin "C8C3.2"
					( objectStatus "b" )
				)
			)
			( gate "C8C4"
				( objectStatus "@baseboard_fab2_lib.baseboard_fab2(sch_1):page130_i20" )
				( pin "C8C4.1"
					( objectStatus "a" )
				)
				( pin "C8C4.2"
					( objectStatus "b" )
				)
			)
			( gate "C8C5"
				( objectStatus "@baseboard_fab2_lib.baseboard_fab2(sch_1):page130_i21" )
				( pin "C8C5.1"
					( objectStatus "a" )
				)
				( pin "C8C5.2"
					( objectStatus "b" )
				)
			)
			( gate "C8C6"
				( objectStatus "@baseboard_fab2_lib.baseboard_fab2(sch_1):page130_i22" )
				( pin "C8C6.1"
					( objectStatus "a" )
				)
				( pin "C8C6.2"
					( objectStatus "b" )
				)
			)
			( gate "C2N23"
				( objectStatus "@baseboard_fab2_lib.baseboard_fab2(sch_1):page130_i24" )
				( pin "C2N23.1"
					( objectStatus "a" )
				)
				( pin "C2N23.2"
					( objectStatus "b" )
				)
			)
			( gate "C2N14"
				( objectStatus "@baseboard_fab2_lib.baseboard_fab2(sch_1):page130_i25" )
				( pin "C2N14.1"
					( objectStatus "a" )
				)
				( pin "C2N14.2"
					( objectStatus "b" )
				)
			)
			( gate "C2N17"
				( objectStatus "@baseboard_fab2_lib.baseboard_fab2(sch_1):page130_i28" )
				( pin "C2N17.1"
					( objectStatus "a" )
				)
				( pin "C2N17.2"
					( objectStatus "b" )
				)
			)
			( gate "C2N18"
				( objectStatus "@baseboard_fab2_lib.baseboard_fab2(sch_1):page130_i29" )
				( pin "C2N18.1"
					( objectStatus "a" )
				)
				( pin "C2N18.2"
					( objectStatus "b" )
				)
			)
			( gate "C8B2"
				( objectStatus "@baseboard_fab2_lib.baseboard_fab2(sch_1):page130_i30" )
				( pin "C8B2.1"
					( objectStatus "a" )
				)
				( pin "C8B2.2"
					( objectStatus "b" )
				)
			)
			( gate "C8B3"
				( objectStatus "@baseboard_fab2_lib.baseboard_fab2(sch_1):page130_i32" )
				( pin "C8B3.1"
					( objectStatus "a" )
				)
				( pin "C8B3.2"
					( objectStatus "b" )
				)
			)
			( gate "C2N25"
				( objectStatus "@baseboard_fab2_lib.baseboard_fab2(sch_1):page130_i34" )
				( pin "C2N25.1"
					( objectStatus "a" )
				)
				( pin "C2N25.2"
					( objectStatus "b" )
				)
			)
			( gate "C2M16"
				( objectStatus "@baseboard_fab2_lib.baseboard_fab2(sch_1):page130_i37" )
				( pin "C2M16.1"
					( objectStatus "a" )
				)
				( pin "C2M16.2"
					( objectStatus "b" )
				)
			)
			( gate "C7D3"
				( objectStatus "@baseboard_fab2_lib.baseboard_fab2(sch_1):page130_i38" )
				( pin "C7D3.1"
					( objectStatus "a" )
				)
				( pin "C7D3.2"
					( objectStatus "b" )
				)
			)
			( gate "C8B4"
				( objectStatus "@baseboard_fab2_lib.baseboard_fab2(sch_1):page130_i39" )
				( pin "C8B4.1"
					( objectStatus "a" )
				)
				( pin "C8B4.2"
					( objectStatus "b" )
				)
			)
			( gate "C8B1"
				( objectStatus "@baseboard_fab2_lib.baseboard_fab2(sch_1):page130_i41" )
				( pin "C8B1.1"
					( objectStatus "a" )
				)
				( pin "C8B1.2"
					( objectStatus "b" )
				)
			)
			( gate "C3N23"
				( objectStatus "@baseboard_fab2_lib.baseboard_fab2(sch_1):page130_i42" )
				( pin "C3N23.1"
					( objectStatus "a" )
				)
				( pin "C3N23.2"
					( objectStatus "b" )
				)
			)
			( gate "C2M1"
				( objectStatus "@baseboard_fab2_lib.baseboard_fab2(sch_1):page130_i43" )
				( pin "C2M1.1"
					( objectStatus "a" )
				)
				( pin "C2M1.2"
					( objectStatus "b" )
				)
			)
			( gate "C2M2"
				( objectStatus "@baseboard_fab2_lib.baseboard_fab2(sch_1):page130_i45" )
				( pin "C2M2.1"
					( objectStatus "a" )
				)
				( pin "C2M2.2"
					( objectStatus "b" )
				)
			)
			( gate "C2N15"
				( objectStatus "@baseboard_fab2_lib.baseboard_fab2(sch_1):page130_i47" )
				( pin "C2N15.1"
					( objectStatus "a" )
				)
				( pin "C2N15.2"
					( objectStatus "b" )
				)
			)
			( gate "C3N21"
				( objectStatus "@baseboard_fab2_lib.baseboard_fab2(sch_1):page130_i49" )
				( pin "C3N21.1"
					( objectStatus "a" )
				)
				( pin "C3N21.2"
					( objectStatus "b" )
				)
			)
			( gate "C3N25"
				( objectStatus "@baseboard_fab2_lib.baseboard_fab2(sch_1):page130_i50" )
				( pin "C3N25.1"
					( objectStatus "a" )
				)
				( pin "C3N25.2"
					( objectStatus "b" )
				)
			)
			( gate "C2N16"
				( objectStatus "@baseboard_fab2_lib.baseboard_fab2(sch_1):page130_i52" )
				( pin "C2N16.1"
					( objectStatus "a" )
				)
				( pin "C2N16.2"
					( objectStatus "b" )
				)
			)
			( gate "C3N22"
				( objectStatus "@baseboard_fab2_lib.baseboard_fab2(sch_1):page130_i53" )
				( pin "C3N22.1"
					( objectStatus "a" )
				)
				( pin "C3N22.2"
					( objectStatus "b" )
				)
			)
			( gate "C7B15"
				( objectStatus "@baseboard_fab2_lib.baseboard_fab2(sch_1):page131_i1" )
				( pin "C7B15.1"
					( objectStatus "a" )
				)
				( pin "C7B15.2"
					( objectStatus "b" )
				)
			)
			( gate "C7B19"
				( objectStatus "@baseboard_fab2_lib.baseboard_fab2(sch_1):page131_i2" )
				( pin "C7B19.1"
					( objectStatus "a" )
				)
				( pin "C7B19.2"
					( objectStatus "b" )
				)
			)
			( gate "C7B16"
				( objectStatus "@baseboard_fab2_lib.baseboard_fab2(sch_1):page131_i3" )
				( pin "C7B16.1"
					( objectStatus "a" )
				)
				( pin "C7B16.2"
					( objectStatus "b" )
				)
			)
			( gate "C7B21"
				( objectStatus "@baseboard_fab2_lib.baseboard_fab2(sch_1):page131_i4" )
				( pin "C7B21.1"
					( objectStatus "a" )
				)
				( pin "C7B21.2"
					( objectStatus "b" )
				)
			)
			( gate "C7B20"
				( objectStatus "@baseboard_fab2_lib.baseboard_fab2(sch_1):page131_i6" )
				( pin "C7B20.1"
					( objectStatus "a" )
				)
				( pin "C7B20.2"
					( objectStatus "b" )
				)
			)
			( gate "C7B23"
				( objectStatus "@baseboard_fab2_lib.baseboard_fab2(sch_1):page131_i7" )
				( pin "C7B23.1"
					( objectStatus "a" )
				)
				( pin "C7B23.2"
					( objectStatus "b" )
				)
			)
			( gate "C8B10"
				( objectStatus "@baseboard_fab2_lib.baseboard_fab2(sch_1):page131_i8" )
				( pin "C8B10.1"
					( objectStatus "a" )
				)
				( pin "C8B10.2"
					( objectStatus "b" )
				)
			)
			( gate "C7B22"
				( objectStatus "@baseboard_fab2_lib.baseboard_fab2(sch_1):page131_i10" )
				( pin "C7B22.1"
					( objectStatus "a" )
				)
				( pin "C7B22.2"
					( objectStatus "b" )
				)
			)
			( gate "C7B24"
				( objectStatus "@baseboard_fab2_lib.baseboard_fab2(sch_1):page131_i11" )
				( pin "C7B24.1"
					( objectStatus "a" )
				)
				( pin "C7B24.2"
					( objectStatus "b" )
				)
			)
			( gate "C7B18"
				( objectStatus "@baseboard_fab2_lib.baseboard_fab2(sch_1):page131_i12" )
				( pin "C7B18.1"
					( objectStatus "a" )
				)
				( pin "C7B18.2"
					( objectStatus "b" )
				)
			)
			( gate "C8B9"
				( objectStatus "@baseboard_fab2_lib.baseboard_fab2(sch_1):page131_i14" )
				( pin "C8B9.1"
					( objectStatus "a" )
				)
				( pin "C8B9.2"
					( objectStatus "b" )
				)
			)
			( gate "C8B11"
				( objectStatus "@baseboard_fab2_lib.baseboard_fab2(sch_1):page131_i15" )
				( pin "C8B11.1"
					( objectStatus "a" )
				)
				( pin "C8B11.2"
					( objectStatus "b" )
				)
			)
			( gate "C8B14"
				( objectStatus "@baseboard_fab2_lib.baseboard_fab2(sch_1):page131_i16" )
				( pin "C8B14.1"
					( objectStatus "a" )
				)
				( pin "C8B14.2"
					( objectStatus "b" )
				)
			)
			( gate "C7B17"
				( objectStatus "@baseboard_fab2_lib.baseboard_fab2(sch_1):page131_i18" )
				( pin "C7B17.1"
					( objectStatus "a" )
				)
				( pin "C7B17.2"
					( objectStatus "b" )
				)
			)
			( gate "C8B13"
				( objectStatus "@baseboard_fab2_lib.baseboard_fab2(sch_1):page131_i20" )
				( pin "C8B13.1"
					( objectStatus "a" )
				)
				( pin "C8B13.2"
					( objectStatus "b" )
				)
			)
			( gate "C8B16"
				( objectStatus "@baseboard_fab2_lib.baseboard_fab2(sch_1):page131_i22" )
				( pin "C8B16.1"
					( objectStatus "a" )
				)
				( pin "C8B16.2"
					( objectStatus "b" )
				)
			)
			( gate "C8B15"
				( objectStatus "@baseboard_fab2_lib.baseboard_fab2(sch_1):page131_i24" )
				( pin "C8B15.1"
					( objectStatus "a" )
				)
				( pin "C8B15.2"
					( objectStatus "b" )
				)
			)
			( gate "C2M22"
				( objectStatus "@baseboard_fab2_lib.baseboard_fab2(sch_1):page131_i27" )
				( pin "C2M22.1"
					( objectStatus "a" )
				)
				( pin "C2M22.2"
					( objectStatus "b" )
				)
			)
			( gate "C2M21"
				( objectStatus "@baseboard_fab2_lib.baseboard_fab2(sch_1):page131_i28" )
				( pin "C2M21.1"
					( objectStatus "a" )
				)
				( pin "C2M21.2"
					( objectStatus "b" )
				)
			)
			( gate "C2M18"
				( objectStatus "@baseboard_fab2_lib.baseboard_fab2(sch_1):page131_i29" )
				( pin "C2M18.1"
					( objectStatus "a" )
				)
				( pin "C2M18.2"
					( objectStatus "b" )
				)
			)
			( gate "C2M19"
				( objectStatus "@baseboard_fab2_lib.baseboard_fab2(sch_1):page131_i31" )
				( pin "C2M19.1"
					( objectStatus "a" )
				)
				( pin "C2M19.2"
					( objectStatus "b" )
				)
			)
			( gate "C3M38"
				( objectStatus "@baseboard_fab2_lib.baseboard_fab2(sch_1):page131_i32" )
				( pin "C3M38.1"
					( objectStatus "a" )
				)
				( pin "C3M38.2"
					( objectStatus "b" )
				)
			)
			( gate "C2M17"
				( objectStatus "@baseboard_fab2_lib.baseboard_fab2(sch_1):page131_i34" )
				( pin "C2M17.1"
					( objectStatus "a" )
				)
				( pin "C2M17.2"
					( objectStatus "b" )
				)
			)
			( gate "C2M11"
				( objectStatus "@baseboard_fab2_lib.baseboard_fab2(sch_1):page131_i35" )
				( pin "C2M11.1"
					( objectStatus "a" )
				)
				( pin "C2M11.2"
					( objectStatus "b" )
				)
			)
			( gate "C8A13"
				( objectStatus "@baseboard_fab2_lib.baseboard_fab2(sch_1):page131_i37" )
				( pin "C8A13.1"
					( objectStatus "a" )
				)
				( pin "C8A13.2"
					( objectStatus "b" )
				)
			)
			( gate "C2M20"
				( objectStatus "@baseboard_fab2_lib.baseboard_fab2(sch_1):page131_i39" )
				( pin "C2M20.1"
					( objectStatus "a" )
				)
				( pin "C2M20.2"
					( objectStatus "b" )
				)
			)
			( gate "C2N13"
				( objectStatus "@baseboard_fab2_lib.baseboard_fab2(sch_1):page131_i40" )
				( pin "C2N13.1"
					( objectStatus "a" )
				)
				( pin "C2N13.2"
					( objectStatus "b" )
				)
			)
			( gate "C2N2"
				( objectStatus "@baseboard_fab2_lib.baseboard_fab2(sch_1):page131_i41" )
				( pin "C2N2.1"
					( objectStatus "a" )
				)
				( pin "C2N2.2"
					( objectStatus "b" )
				)
			)
			( gate "C3M43"
				( objectStatus "@baseboard_fab2_lib.baseboard_fab2(sch_1):page131_i42" )
				( pin "C3M43.1"
					( objectStatus "a" )
				)
				( pin "C3M43.2"
					( objectStatus "b" )
				)
			)
			( gate "C2N7"
				( objectStatus "@baseboard_fab2_lib.baseboard_fab2(sch_1):page131_i43" )
				( pin "C2N7.1"
					( objectStatus "a" )
				)
				( pin "C2N7.2"
					( objectStatus "b" )
				)
			)
			( gate "C3M39"
				( objectStatus "@baseboard_fab2_lib.baseboard_fab2(sch_1):page131_i44" )
				( pin "C3M39.1"
					( objectStatus "a" )
				)
				( pin "C3M39.2"
					( objectStatus "b" )
				)
			)
			( gate "C3M42"
				( objectStatus "@baseboard_fab2_lib.baseboard_fab2(sch_1):page131_i45" )
				( pin "C3M42.1"
					( objectStatus "a" )
				)
				( pin "C3M42.2"
					( objectStatus "b" )
				)
			)
			( gate "C2N8"
				( objectStatus "@baseboard_fab2_lib.baseboard_fab2(sch_1):page131_i47" )
				( pin "C2N8.1"
					( objectStatus "a" )
				)
				( pin "C2N8.2"
					( objectStatus "b" )
				)
			)
			( gate "C2M13"
				( objectStatus "@baseboard_fab2_lib.baseboard_fab2(sch_1):page131_i48" )
				( pin "C2M13.1"
					( objectStatus "a" )
				)
				( pin "C2M13.2"
					( objectStatus "b" )
				)
			)
			( gate "C2N10"
				( objectStatus "@baseboard_fab2_lib.baseboard_fab2(sch_1):page131_i50" )
				( pin "C2N10.1"
					( objectStatus "a" )
				)
				( pin "C2N10.2"
					( objectStatus "b" )
				)
			)
			( gate "C2M12"
				( objectStatus "@baseboard_fab2_lib.baseboard_fab2(sch_1):page131_i52" )
				( pin "C2M12.1"
					( objectStatus "a" )
				)
				( pin "C2M12.2"
					( objectStatus "b" )
				)
			)
			( gate "C3L25"
				( objectStatus "@baseboard_fab2_lib.baseboard_fab2(sch_1):page132_i1" )
				( pin "C3L25.1"
					( objectStatus "a" )
				)
				( pin "C3L25.2"
					( objectStatus "b" )
				)
			)
			( gate "C3M7"
				( objectStatus "@baseboard_fab2_lib.baseboard_fab2(sch_1):page132_i2" )
				( pin "C3M7.1"
					( objectStatus "a" )
				)
				( pin "C3M7.2"
					( objectStatus "b" )
				)
			)
			( gate "C3L26"
				( objectStatus "@baseboard_fab2_lib.baseboard_fab2(sch_1):page132_i3" )
				( pin "C3L26.1"
					( objectStatus "a" )
				)
				( pin "C3L26.2"
					( objectStatus "b" )
				)
			)
			( gate "C3L27"
				( objectStatus "@baseboard_fab2_lib.baseboard_fab2(sch_1):page132_i4" )
				( pin "C3L27.1"
					( objectStatus "a" )
				)
				( pin "C3L27.2"
					( objectStatus "b" )
				)
			)
			( gate "C3M6"
				( objectStatus "@baseboard_fab2_lib.baseboard_fab2(sch_1):page132_i6" )
				( pin "C3M6.1"
					( objectStatus "a" )
				)
				( pin "C3M6.2"
					( objectStatus "b" )
				)
			)
			( gate "C7C9"
				( objectStatus "@baseboard_fab2_lib.baseboard_fab2(sch_1):page132_i7" )
				( pin "C7C9.1"
					( objectStatus "a" )
				)
				( pin "C7C9.2"
					( objectStatus "b" )
				)
			)
			( gate "C3N27"
				( objectStatus "@baseboard_fab2_lib.baseboard_fab2(sch_1):page132_i8" )
				( pin "C3N27.1"
					( objectStatus "a" )
				)
				( pin "C3N27.2"
					( objectStatus "b" )
				)
			)
			( gate "C3N30"
				( objectStatus "@baseboard_fab2_lib.baseboard_fab2(sch_1):page132_i9" )
				( pin "C3N30.1"
					( objectStatus "a" )
				)
				( pin "C3N30.2"
					( objectStatus "b" )
				)
			)
			( gate "C7A36"
				( objectStatus "@baseboard_fab2_lib.baseboard_fab2(sch_1):page132_i11" )
				( pin "C7A36.1"
					( objectStatus "a" )
				)
				( pin "C7A36.2"
					( objectStatus "b" )
				)
			)
			( gate "C3N12"
				( objectStatus "@baseboard_fab2_lib.baseboard_fab2(sch_1):page132_i12" )
				( pin "C3N12.1"
					( objectStatus "a" )
				)
				( pin "C3N12.2"
					( objectStatus "b" )
				)
			)
			( gate "C3N10"
				( objectStatus "@baseboard_fab2_lib.baseboard_fab2(sch_1):page132_i13" )
				( pin "C3N10.1"
					( objectStatus "a" )
				)
				( pin "C3N10.2"
					( objectStatus "b" )
				)
			)
			( gate "C3N24"
				( objectStatus "@baseboard_fab2_lib.baseboard_fab2(sch_1):page132_i16" )
				( pin "C3N24.1"
					( objectStatus "a" )
				)
				( pin "C3N24.2"
					( objectStatus "b" )
				)
			)
			( gate "C3N28"
				( objectStatus "@baseboard_fab2_lib.baseboard_fab2(sch_1):page132_i17" )
				( pin "C3N28.1"
					( objectStatus "a" )
				)
				( pin "C3N28.2"
					( objectStatus "b" )
				)
			)
			( gate "C3N11"
				( objectStatus "@baseboard_fab2_lib.baseboard_fab2(sch_1):page132_i19" )
				( pin "C3N11.1"
					( objectStatus "a" )
				)
				( pin "C3N11.2"
					( objectStatus "b" )
				)
			)
			( gate "C3N31"
				( objectStatus "@baseboard_fab2_lib.baseboard_fab2(sch_1):page132_i20" )
				( pin "C3N31.1"
					( objectStatus "a" )
				)
				( pin "C3N31.2"
					( objectStatus "b" )
				)
			)
			( gate "C7A33"
				( objectStatus "@baseboard_fab2_lib.baseboard_fab2(sch_1):page132_i23" )
				( pin "C7A33.1"
					( objectStatus "a" )
				)
				( pin "C7A33.2"
					( objectStatus "b" )
				)
			)
			( gate "C7B4"
				( objectStatus "@baseboard_fab2_lib.baseboard_fab2(sch_1):page132_i24" )
				( pin "C7B4.1"
					( objectStatus "a" )
				)
				( pin "C7B4.2"
					( objectStatus "b" )
				)
			)
			( gate "C2N9"
				( objectStatus "@baseboard_fab2_lib.baseboard_fab2(sch_1):page132_i26" )
				( pin "C2N9.1"
					( objectStatus "a" )
				)
				( pin "C2N9.2"
					( objectStatus "b" )
				)
			)
			( gate "C2N3"
				( objectStatus "@baseboard_fab2_lib.baseboard_fab2(sch_1):page132_i27" )
				( pin "C2N3.1"
					( objectStatus "a" )
				)
				( pin "C2N3.2"
					( objectStatus "b" )
				)
			)
			( gate "C2N4"
				( objectStatus "@baseboard_fab2_lib.baseboard_fab2(sch_1):page132_i28" )
				( pin "C2N4.1"
					( objectStatus "a" )
				)
				( pin "C2N4.2"
					( objectStatus "b" )
				)
			)
			( gate "C2N12"
				( objectStatus "@baseboard_fab2_lib.baseboard_fab2(sch_1):page132_i29" )
				( pin "C2N12.1"
					( objectStatus "a" )
				)
				( pin "C2N12.2"
					( objectStatus "b" )
				)
			)
			( gate "C2N11"
				( objectStatus "@baseboard_fab2_lib.baseboard_fab2(sch_1):page132_i30" )
				( pin "C2N11.1"
					( objectStatus "a" )
				)
				( pin "C2N11.2"
					( objectStatus "b" )
				)
			)
			( gate "C3N19"
				( objectStatus "@baseboard_fab2_lib.baseboard_fab2(sch_1):page132_i31" )
				( pin "C3N19.1"
					( objectStatus "a" )
				)
				( pin "C3N19.2"
					( objectStatus "b" )
				)
			)
			( gate "C3N3"
				( objectStatus "@baseboard_fab2_lib.baseboard_fab2(sch_1):page132_i32" )
				( pin "C3N3.1"
					( objectStatus "a" )
				)
				( pin "C3N3.2"
					( objectStatus "b" )
				)
			)
			( gate "C3N1"
				( objectStatus "@baseboard_fab2_lib.baseboard_fab2(sch_1):page132_i34" )
				( pin "C3N1.1"
					( objectStatus "a" )
				)
				( pin "C3N1.2"
					( objectStatus "b" )
				)
			)
			( gate "C3N7"
				( objectStatus "@baseboard_fab2_lib.baseboard_fab2(sch_1):page132_i35" )
				( pin "C3N7.1"
					( objectStatus "a" )
				)
				( pin "C3N7.2"
					( objectStatus "b" )
				)
			)
			( gate "C3N16"
				( objectStatus "@baseboard_fab2_lib.baseboard_fab2(sch_1):page132_i36" )
				( pin "C3N16.1"
					( objectStatus "a" )
				)
				( pin "C3N16.2"
					( objectStatus "b" )
				)
			)
			( gate "C7A32"
				( objectStatus "@baseboard_fab2_lib.baseboard_fab2(sch_1):page132_i38" )
				( pin "C7A32.1"
					( objectStatus "a" )
				)
				( pin "C7A32.2"
					( objectStatus "b" )
				)
			)
			( gate "C7A31"
				( objectStatus "@baseboard_fab2_lib.baseboard_fab2(sch_1):page132_i40" )
				( pin "C7A31.1"
					( objectStatus "a" )
				)
				( pin "C7A31.2"
					( objectStatus "b" )
				)
			)
			( gate "C3N18"
				( objectStatus "@baseboard_fab2_lib.baseboard_fab2(sch_1):page132_i42" )
				( pin "C3N18.1"
					( objectStatus "a" )
				)
				( pin "C3N18.2"
					( objectStatus "b" )
				)
			)
			( gate "C3N2"
				( objectStatus "@baseboard_fab2_lib.baseboard_fab2(sch_1):page132_i43" )
				( pin "C3N2.1"
					( objectStatus "a" )
				)
				( pin "C3N2.2"
					( objectStatus "b" )
				)
			)
			( gate "C3N6"
				( objectStatus "@baseboard_fab2_lib.baseboard_fab2(sch_1):page132_i44" )
				( pin "C3N6.1"
					( objectStatus "a" )
				)
				( pin "C3N6.2"
					( objectStatus "b" )
				)
			)
			( gate "C3N17"
				( objectStatus "@baseboard_fab2_lib.baseboard_fab2(sch_1):page132_i45" )
				( pin "C3N17.1"
					( objectStatus "a" )
				)
				( pin "C3N17.2"
					( objectStatus "b" )
				)
			)
			( gate "C3N4"
				( objectStatus "@baseboard_fab2_lib.baseboard_fab2(sch_1):page132_i46" )
				( pin "C3N4.1"
					( objectStatus "a" )
				)
				( pin "C3N4.2"
					( objectStatus "b" )
				)
			)
			( gate "C3N5"
				( objectStatus "@baseboard_fab2_lib.baseboard_fab2(sch_1):page132_i48" )
				( pin "C3N5.1"
					( objectStatus "a" )
				)
				( pin "C3N5.2"
					( objectStatus "b" )
				)
			)
			( gate "C3N15"
				( objectStatus "@baseboard_fab2_lib.baseboard_fab2(sch_1):page132_i49" )
				( pin "C3N15.1"
					( objectStatus "a" )
				)
				( pin "C3N15.2"
					( objectStatus "b" )
				)
			)
			( gate "C3N20"
				( objectStatus "@baseboard_fab2_lib.baseboard_fab2(sch_1):page132_i51" )
				( pin "C3N20.1"
					( objectStatus "a" )
				)
				( pin "C3N20.2"
					( objectStatus "b" )
				)
			)
			( gate "C3L23"
				( objectStatus "@baseboard_fab2_lib.baseboard_fab2(sch_1):page132_i52" )
				( pin "C3L23.1"
					( objectStatus "a" )
				)
				( pin "C3L23.2"
					( objectStatus "b" )
				)
			)
			( gate "C3L22"
				( objectStatus "@baseboard_fab2_lib.baseboard_fab2(sch_1):page132_i54" )
				( pin "C3L22.1"
					( objectStatus "a" )
				)
				( pin "C3L22.2"
					( objectStatus "b" )
				)
			)
			( gate "C3L24"
				( objectStatus "@baseboard_fab2_lib.baseboard_fab2(sch_1):page132_i56" )
				( pin "C3L24.1"
					( objectStatus "a" )
				)
				( pin "C3L24.2"
					( objectStatus "b" )
				)
			)
			( gate "R3N3"
				( objectStatus "@baseboard_fab2_lib.baseboard_fab2(sch_1):page133_i120" )
				( pin "R3N3.1"
					( objectStatus "a" )
				)
				( pin "R3N3.2"
					( objectStatus "b" )
				)
			)
			( gate "R2N12"
				( objectStatus "@baseboard_fab2_lib.baseboard_fab2(sch_1):page133_i122" )
				( pin "R2N12.1"
					( objectStatus "a" )
				)
				( pin "R2N12.2"
					( objectStatus "b" )
				)
			)
			( gate "R7D8"
				( objectStatus "@baseboard_fab2_lib.baseboard_fab2(sch_1):page133_i200" )
				( pin "R7D8.1"
					( objectStatus "a" )
				)
				( pin "R7D8.2"
					( objectStatus "b" )
				)
			)
			( gate "R7D10"
				( objectStatus "@baseboard_fab2_lib.baseboard_fab2(sch_1):page133_i202" )
				( pin "R7D10.1"
					( objectStatus "a" )
				)
				( pin "R7D10.2"
					( objectStatus "b" )
				)
			)
			( gate "R7D12"
				( objectStatus "@baseboard_fab2_lib.baseboard_fab2(sch_1):page133_i237" )
				( pin "R7D12.1"
					( objectStatus "a" )
				)
				( pin "R7D12.2"
					( objectStatus "b" )
				)
			)
			( gate "R7D3"
				( objectStatus "@baseboard_fab2_lib.baseboard_fab2(sch_1):page133_i243" )
				( pin "R7D3.1"
					( objectStatus "a" )
				)
				( pin "R7D3.2"
					( objectStatus "b" )
				)
			)
			( gate "R7D4"
				( objectStatus "@baseboard_fab2_lib.baseboard_fab2(sch_1):page133_i245" )
				( pin "R7D4.1"
					( objectStatus "a" )
				)
				( pin "R7D4.2"
					( objectStatus "b" )
				)
			)
			( gate "R2N16"
				( objectStatus "@baseboard_fab2_lib.baseboard_fab2(sch_1):page133_i247" )
				( pin "R2N16.1"
					( objectStatus "a" )
				)
				( pin "R2N16.2"
					( objectStatus "b" )
				)
			)
			( gate "R2R5"
				( objectStatus "@baseboard_fab2_lib.baseboard_fab2(sch_1):page133_i258" )
				( pin "R2R5.1"
					( objectStatus "a" )
				)
				( pin "R2R5.2"
					( objectStatus "b" )
				)
			)
			( gate "R2N9"
				( objectStatus "@baseboard_fab2_lib.baseboard_fab2(sch_1):page133_i267" )
				( pin "R2N9.1"
					( objectStatus "a" )
				)
				( pin "R2N9.2"
					( objectStatus "b" )
				)
			)
			( gate "R8B23"
				( objectStatus "@baseboard_fab2_lib.baseboard_fab2(sch_1):page133_i280" )
				( pin "R8B23.1"
					( objectStatus "a" )
				)
				( pin "R8B23.2"
					( objectStatus "b" )
				)
			)
			( gate "R8B30"
				( objectStatus "@baseboard_fab2_lib.baseboard_fab2(sch_1):page133_i282" )
				( pin "R8B30.1"
					( objectStatus "a" )
				)
				( pin "R8B30.2"
					( objectStatus "b" )
				)
			)
			( gate "R2M4"
				( objectStatus "@baseboard_fab2_lib.baseboard_fab2(sch_1):page133_i284" )
				( pin "R2M4.1"
					( objectStatus "a" )
				)
				( pin "R2M4.2"
					( objectStatus "b" )
				)
			)
			( gate "R8C4"
				( objectStatus "@baseboard_fab2_lib.baseboard_fab2(sch_1):page133_i286" )
				( pin "R8C4.1"
					( objectStatus "a" )
				)
				( pin "R8C4.2"
					( objectStatus "b" )
				)
			)
			( gate "R7B6"
				( objectStatus "@baseboard_fab2_lib.baseboard_fab2(sch_1):page133_i295" )
				( pin "R7B6.1"
					( objectStatus "a" )
				)
				( pin "R7B6.2"
					( objectStatus "b" )
				)
			)
			( gate "R7C8"
				( objectStatus "@baseboard_fab2_lib.baseboard_fab2(sch_1):page133_i296" )
				( pin "R7C8.1"
					( objectStatus "a" )
				)
				( pin "R7C8.2"
					( objectStatus "b" )
				)
			)
			( gate "R7C5"
				( objectStatus "@baseboard_fab2_lib.baseboard_fab2(sch_1):page133_i297" )
				( pin "R7C5.1"
					( objectStatus "a" )
				)
				( pin "R7C5.2"
					( objectStatus "b" )
				)
			)
			( gate "R8D14"
				( objectStatus "@baseboard_fab2_lib.baseboard_fab2(sch_1):page133_i301" )
				( pin "R8D14.1"
					( objectStatus "a" )
				)
				( pin "R8D14.2"
					( objectStatus "b" )
				)
			)
			( gate "R8C6"
				( objectStatus "@baseboard_fab2_lib.baseboard_fab2(sch_1):page133_i303" )
				( pin "R8C6.1"
					( objectStatus "a" )
				)
				( pin "R8C6.2"
					( objectStatus "b" )
				)
			)
			( gate "R8C2"
				( objectStatus "@baseboard_fab2_lib.baseboard_fab2(sch_1):page133_i304" )
				( pin "R8C2.1"
					( objectStatus "a" )
				)
				( pin "R8C2.2"
					( objectStatus "b" )
				)
			)
			( gate "R7D6"
				( objectStatus "@baseboard_fab2_lib.baseboard_fab2(sch_1):page133_i306" )
				( pin "R7D6.1"
					( objectStatus "a" )
				)
				( pin "R7D6.2"
					( objectStatus "b" )
				)
			)
			( gate "R8B31"
				( objectStatus "@baseboard_fab2_lib.baseboard_fab2(sch_1):page133_i307" )
				( pin "R8B31.1"
					( objectStatus "a" )
				)
				( pin "R8B31.2"
					( objectStatus "b" )
				)
			)
			( gate "R2N7"
				( objectStatus "@baseboard_fab2_lib.baseboard_fab2(sch_1):page133_i309" )
				( pin "R2N7.1"
					( objectStatus "a" )
				)
				( pin "R2N7.2"
					( objectStatus "b" )
				)
			)
			( gate "R3P7"
				( objectStatus "@baseboard_fab2_lib.baseboard_fab2(sch_1):page133_i315" )
				( pin "R3P7.1"
					( objectStatus "a" )
				)
				( pin "R3P7.2"
					( objectStatus "b" )
				)
			)
			( gate "R3P5"
				( objectStatus "@baseboard_fab2_lib.baseboard_fab2(sch_1):page133_i316" )
				( pin "R3P5.1"
					( objectStatus "a" )
				)
				( pin "R3P5.2"
					( objectStatus "b" )
				)
			)
			( gate "R3P6"
				( objectStatus "@baseboard_fab2_lib.baseboard_fab2(sch_1):page133_i317" )
				( pin "R3P6.1"
					( objectStatus "a" )
				)
				( pin "R3P6.2"
					( objectStatus "b" )
				)
			)
			( gate "R3N15"
				( objectStatus "@baseboard_fab2_lib.baseboard_fab2(sch_1):page133_i318" )
				( pin "R3N15.1"
					( objectStatus "a" )
				)
				( pin "R3N15.2"
					( objectStatus "b" )
				)
			)
			( gate "R3N16"
				( objectStatus "@baseboard_fab2_lib.baseboard_fab2(sch_1):page133_i321" )
				( pin "R3N16.1"
					( objectStatus "a" )
				)
				( pin "R3N16.2"
					( objectStatus "b" )
				)
			)
			( gate "R3P8"
				( objectStatus "@baseboard_fab2_lib.baseboard_fab2(sch_1):page133_i322" )
				( pin "R3P8.1"
					( objectStatus "a" )
				)
				( pin "R3P8.2"
					( objectStatus "b" )
				)
			)
			( gate "R8C1"
				( objectStatus "@baseboard_fab2_lib.baseboard_fab2(sch_1):page133_i326" )
				( pin "R8C1.1"
					( objectStatus "a" )
				)
				( pin "R8C1.2"
					( objectStatus "b" )
				)
			)
			( gate "R8C7"
				( objectStatus "@baseboard_fab2_lib.baseboard_fab2(sch_1):page133_i327" )
				( pin "R8C7.1"
					( objectStatus "a" )
				)
				( pin "R8C7.2"
					( objectStatus "b" )
				)
			)
			( gate "R7D7"
				( objectStatus "@baseboard_fab2_lib.baseboard_fab2(sch_1):page133_i331" )
				( pin "R7D7.1"
					( objectStatus "a" )
				)
				( pin "R7D7.2"
					( objectStatus "b" )
				)
			)
			( gate "R7D2"
				( objectStatus "@baseboard_fab2_lib.baseboard_fab2(sch_1):page133_i332" )
				( pin "R7D2.1"
					( objectStatus "a" )
				)
				( pin "R7D2.2"
					( objectStatus "b" )
				)
			)
			( gate "R8C25"
				( objectStatus "@baseboard_fab2_lib.baseboard_fab2(sch_1):page133_i333" )
				( pin "R8C25.1"
					( objectStatus "a" )
				)
				( pin "R8C25.2"
					( objectStatus "b" )
				)
			)
			( gate "R8"
				( objectStatus "@baseboard_fab2_lib.baseboard_fab2(sch_1):page133_i341" )
				( pin "R8.1"
					( objectStatus "a" )
				)
				( pin "R8.2"
					( objectStatus "b" )
				)
			)
			( gate "R75"
				( objectStatus "@baseboard_fab2_lib.baseboard_fab2(sch_1):page133_i349" )
				( pin "R75.1"
					( objectStatus "a" )
				)
				( pin "R75.2"
					( objectStatus "b" )
				)
			)
			( gate "R76"
				( objectStatus "@baseboard_fab2_lib.baseboard_fab2(sch_1):page133_i352" )
				( pin "R76.1"
					( objectStatus "a" )
				)
				( pin "R76.2"
					( objectStatus "b" )
				)
			)
			( gate "R8E3"
				( objectStatus "@baseboard_fab2_lib.baseboard_fab2(sch_1):page133_i355" )
				( pin "R8E3.1"
					( objectStatus "a" )
				)
				( pin "R8E3.2"
					( objectStatus "b" )
				)
			)
			( gate "R155"
				( objectStatus "@baseboard_fab2_lib.baseboard_fab2(sch_1):page133_i356" )
				( pin "R155.1"
					( objectStatus "a" )
				)
				( pin "R155.2"
					( objectStatus "b" )
				)
			)
			( gate "R156"
				( objectStatus "@baseboard_fab2_lib.baseboard_fab2(sch_1):page133_i357" )
				( pin "R156.1"
					( objectStatus "a" )
				)
				( pin "R156.2"
					( objectStatus "b" )
				)
			)
			( gate "J2"
				( objectStatus "@baseboard_fab2_lib.baseboard_fab2(sch_1):page134_i5" )
				( pin "J2.1"
					( objectStatus "io1" )
				)
				( pin "J2.2"
					( objectStatus "io2" )
				)
				( pin "J2.3"
					( objectStatus "io3" )
				)
				( pin "J2.4"
					( objectStatus "io4" )
				)
				( pin "J2.5"
					( objectStatus "io5" )
				)
				( pin "J2.6"
					( objectStatus "io6" )
				)
				( pin "J2.7"
					( objectStatus "io7" )
				)
				( pin "J2.8"
					( objectStatus "io8" )
				)
				( pin "J2.9"
					( objectStatus "io9" )
				)
				( pin "J2.10"
					( objectStatus "io10" )
				)
				( pin "J2.11"
					( objectStatus "io11" )
				)
				( pin "J2.12"
					( objectStatus "io12" )
				)
			)
			( gate "R9A12"
				( objectStatus "@baseboard_fab2_lib.baseboard_fab2(sch_1):page134_i11" )
				( pin "R9A12.1"
					( objectStatus "a" )
				)
				( pin "R9A12.2"
					( objectStatus "b" )
				)
			)
			( gate "R9A16"
				( objectStatus "@baseboard_fab2_lib.baseboard_fab2(sch_1):page134_i12" )
				( pin "R9A16.1"
					( objectStatus "a" )
				)
				( pin "R9A16.2"
					( objectStatus "b" )
				)
			)
			( gate "R9A13"
				( objectStatus "@baseboard_fab2_lib.baseboard_fab2(sch_1):page134_i14" )
				( pin "R9A13.1"
					( objectStatus "a" )
				)
				( pin "R9A13.2"
					( objectStatus "b" )
				)
			)
			( gate "R2N23"
				( objectStatus "@baseboard_fab2_lib.baseboard_fab2(sch_1):page134_i17" )
				( pin "R2N23.1"
					( objectStatus "a" )
				)
				( pin "R2N23.2"
					( objectStatus "b" )
				)
			)
			( gate "R2N24"
				( objectStatus "@baseboard_fab2_lib.baseboard_fab2(sch_1):page134_i18" )
				( pin "R2N24.1"
					( objectStatus "a" )
				)
				( pin "R2N24.2"
					( objectStatus "b" )
				)
			)
			( gate "J9A1"
				( objectStatus "@baseboard_fab2_lib.baseboard_fab2(sch_1):page134_i22" )
				( pin "J9A1.1"
					( objectStatus "io1" )
				)
				( pin "J9A1.2"
					( objectStatus "io2" )
				)
				( pin "J9A1.3"
					( objectStatus "io3" )
				)
				( pin "J9A1.4"
					( objectStatus "io4" )
				)
			)
			( gate "R8D21"
				( objectStatus "@baseboard_fab2_lib.baseboard_fab2(sch_1):page134_i24" )
				( pin "R8D21.1"
					( objectStatus "a" )
				)
				( pin "R8D21.2"
					( objectStatus "b" )
				)
			)
			( gate "R7D30"
				( objectStatus "@baseboard_fab2_lib.baseboard_fab2(sch_1):page134_i27" )
				( pin "R7D30.1"
					( objectStatus "a" )
				)
				( pin "R7D30.2"
					( objectStatus "b" )
				)
			)
			( gate "R7D20"
				( objectStatus "@baseboard_fab2_lib.baseboard_fab2(sch_1):page134_i34" )
				( pin "R7D20.1"
					( objectStatus "a" )
				)
				( pin "R7D20.2"
					( objectStatus "b" )
				)
			)
			( gate "R7C21"
				( objectStatus "@baseboard_fab2_lib.baseboard_fab2(sch_1):page135_i58" )
				( pin "R7C21.1"
					( objectStatus "a" )
				)
				( pin "R7C21.2"
					( objectStatus "b" )
				)
			)
			( gate "Q7D1"
				( objectStatus "@baseboard_fab2_lib.baseboard_fab2(sch_1):page135_i76" )
				( pin "Q7D1.3"
					( objectStatus "drn" )
				)
				( pin "Q7D1.1"
					( objectStatus "gate" )
				)
				( pin "Q7D1.2"
					( objectStatus "src" )
				)
			)
			( gate "R7D18"
				( objectStatus "@baseboard_fab2_lib.baseboard_fab2(sch_1):page135_i99" )
				( pin "R7D18.1"
					( objectStatus "a" )
				)
				( pin "R7D18.2"
					( objectStatus "b" )
				)
			)
			( gate "Q1"
				( objectStatus "@baseboard_fab2_lib.baseboard_fab2(sch_1):page135_i100" )
				( pin "Q1.3"
					( objectStatus "drn" )
				)
				( pin "Q1.1"
					( objectStatus "gate" )
				)
				( pin "Q1.2"
					( objectStatus "src" )
				)
			)
			( gate "R9"
				( objectStatus "@baseboard_fab2_lib.baseboard_fab2(sch_1):page135_i104" )
				( pin "R9.1"
					( objectStatus "a" )
				)
				( pin "R9.2"
					( objectStatus "b" )
				)
			)
			( gate "R3P28"
				( objectStatus "@baseboard_fab2_lib.baseboard_fab2(sch_1):page136_i101" )
				( pin "R3P28.1"
					( objectStatus "a" )
				)
				( pin "R3P28.2"
					( objectStatus "b" )
				)
			)
			( gate "R3P31"
				( objectStatus "@baseboard_fab2_lib.baseboard_fab2(sch_1):page136_i102" )
				( pin "R3P31.1"
					( objectStatus "a" )
				)
				( pin "R3P31.2"
					( objectStatus "b" )
				)
			)
			( gate "R8E20"
				( objectStatus "@baseboard_fab2_lib.baseboard_fab2(sch_1):page136_i126" )
				( pin "R8E20.1"
					( objectStatus "a" )
				)
				( pin "R8E20.2"
					( objectStatus "b" )
				)
			)
			( gate "C8E8"
				( objectStatus "@baseboard_fab2_lib.baseboard_fab2(sch_1):page136_i128" )
				( pin "C8E8.1"
					( objectStatus "a" )
				)
				( pin "C8E8.2"
					( objectStatus "b" )
				)
			)
			( gate "U8E3"
				( objectStatus "@baseboard_fab2_lib.baseboard_fab2(sch_1):page136_i130" )
				( pin "U8E3.2"
					( objectStatus "a" )
				)
				( pin "U8E3.1"
					( objectStatus "oe" )
				)
				( pin "U8E3.4"
					( objectStatus "y" )
				)
			)
			( gate "R8E14"
				( objectStatus "@baseboard_fab2_lib.baseboard_fab2(sch_1):page136_i133" )
				( pin "R8E14.1"
					( objectStatus "a" )
				)
				( pin "R8E14.2"
					( objectStatus "b" )
				)
			)
			( gate "Q8E1"
				( objectStatus "@baseboard_fab2_lib.baseboard_fab2(sch_1):page136_i134" )
				( pin "Q8E1.3"
					( objectStatus "drn" )
				)
				( pin "Q8E1.1"
					( objectStatus "gate" )
				)
				( pin "Q8E1.2"
					( objectStatus "src" )
				)
			)
			( gate "R8F4"
				( objectStatus "@baseboard_fab2_lib.baseboard_fab2(sch_1):page136_i139" )
				( pin "R8F4.1"
					( objectStatus "a" )
				)
				( pin "R8F4.2"
					( objectStatus "b" )
				)
			)
			( gate "R8E16"
				( objectStatus "@baseboard_fab2_lib.baseboard_fab2(sch_1):page136_i140" )
				( pin "R8E16.1"
					( objectStatus "a" )
				)
				( pin "R8E16.2"
					( objectStatus "b" )
				)
			)
			( gate "R8C10"
				( objectStatus "@baseboard_fab2_lib.baseboard_fab2(sch_1):page136_i147" )
				( pin "R8C10.1"
					( objectStatus "a" )
				)
				( pin "R8C10.2"
					( objectStatus "b" )
				)
			)
			( gate "R8C8"
				( objectStatus "@baseboard_fab2_lib.baseboard_fab2(sch_1):page136_i148" )
				( pin "R8C8.1"
					( objectStatus "a" )
				)
				( pin "R8C8.2"
					( objectStatus "b" )
				)
			)
			( gate "R7D21"
				( objectStatus "@baseboard_fab2_lib.baseboard_fab2(sch_1):page136_i155" )
				( pin "R7D21.1"
					( objectStatus "a" )
				)
				( pin "R7D21.2"
					( objectStatus "b" )
				)
			)
			( gate "R7D22"
				( objectStatus "@baseboard_fab2_lib.baseboard_fab2(sch_1):page136_i156" )
				( pin "R7D22.1"
					( objectStatus "a" )
				)
				( pin "R7D22.2"
					( objectStatus "b" )
				)
			)
			( gate "J3"
				( objectStatus "@baseboard_fab2_lib.baseboard_fab2(sch_1):page136_i167" )
				( pin "J3.1"
					( objectStatus "io1" )
				)
				( pin "J3.2"
					( objectStatus "io2" )
				)
				( pin "J3.3"
					( objectStatus "io3" )
				)
				( pin "J3.4"
					( objectStatus "io4" )
				)
				( pin "J3.5"
					( objectStatus "io5" )
				)
				( pin "J3.6"
					( objectStatus "io6" )
				)
				( pin "J3.7"
					( objectStatus "io7" )
				)
				( pin "J3.8"
					( objectStatus "io8" )
				)
				( pin "J3.9"
					( objectStatus "io9" )
				)
				( pin "J3.10"
					( objectStatus "io10" )
				)
				( pin "J3.11"
					( objectStatus "io11" )
				)
				( pin "J3.12"
					( objectStatus "io12" )
				)
			)
			( gate "R7C11"
				( objectStatus "@baseboard_fab2_lib.baseboard_fab2(sch_1):page137_i11" )
				( pin "R7C11.1"
					( objectStatus "a" )
				)
				( pin "R7C11.2"
					( objectStatus "b" )
				)
			)
			( gate "R7C10"
				( objectStatus "@baseboard_fab2_lib.baseboard_fab2(sch_1):page137_i13" )
				( pin "R7C10.1"
					( objectStatus "a" )
				)
				( pin "R7C10.2"
					( objectStatus "b" )
				)
			)
			( gate "C7C19"
				( objectStatus "@baseboard_fab2_lib.baseboard_fab2(sch_1):page137_i14" )
				( pin "C7C19.1"
					( objectStatus "a" )
				)
				( pin "C7C19.2"
					( objectStatus "b" )
				)
			)
			( gate "R7C12"
				( objectStatus "@baseboard_fab2_lib.baseboard_fab2(sch_1):page137_i15" )
				( pin "R7C12.1"
					( objectStatus "a" )
				)
				( pin "R7C12.2"
					( objectStatus "b" )
				)
			)
			( gate "R3N4"
				( objectStatus "@baseboard_fab2_lib.baseboard_fab2(sch_1):page137_i19" )
				( pin "R3N4.1"
					( objectStatus "a" )
				)
				( pin "R3N4.2"
					( objectStatus "b" )
				)
			)
			( gate "C3N32"
				( objectStatus "@baseboard_fab2_lib.baseboard_fab2(sch_1):page137_i20" )
				( pin "C3N32.1"
					( objectStatus "a" )
				)
				( pin "C3N32.2"
					( objectStatus "b" )
				)
			)
			( gate "R7C13"
				( objectStatus "@baseboard_fab2_lib.baseboard_fab2(sch_1):page137_i67" )
				( pin "R7C13.1"
					( objectStatus "a" )
				)
				( pin "R7C13.2"
					( objectStatus "b" )
				)
			)
			( gate "R7C9"
				( objectStatus "@baseboard_fab2_lib.baseboard_fab2(sch_1):page137_i69" )
				( pin "R7C9.1"
					( objectStatus "a" )
				)
				( pin "R7C9.2"
					( objectStatus "b" )
				)
			)
			( gate "J4"
				( objectStatus "@baseboard_fab2_lib.baseboard_fab2(sch_1):page137_i100" )
				( pin "J4.1"
					( objectStatus "io1" )
				)
				( pin "J4.2"
					( objectStatus "io2" )
				)
				( pin "J4.3"
					( objectStatus "io3" )
				)
				( pin "J4.4"
					( objectStatus "io4" )
				)
				( pin "J4.5"
					( objectStatus "io5" )
				)
				( pin "J4.6"
					( objectStatus "io6" )
				)
				( pin "J4.7"
					( objectStatus "io7" )
				)
				( pin "J4.8"
					( objectStatus "io8" )
				)
				( pin "J4.9"
					( objectStatus "io9" )
				)
				( pin "J4.10"
					( objectStatus "io10" )
				)
				( pin "J4.11"
					( objectStatus "io11" )
				)
				( pin "J4.12"
					( objectStatus "io12" )
				)
			)
			( gate "R2T53"
				( objectStatus "@baseboard_fab2_lib.baseboard_fab2(sch_1):page138_i83" )
				( pin "R2T53.1"
					( objectStatus "a" )
				)
				( pin "R2T53.2"
					( objectStatus "b" )
				)
			)
			( gate "R2T54"
				( objectStatus "@baseboard_fab2_lib.baseboard_fab2(sch_1):page138_i84" )
				( pin "R2T54.1"
					( objectStatus "a" )
				)
				( pin "R2T54.2"
					( objectStatus "b" )
				)
			)
			( gate "R8D17"
				( objectStatus "@baseboard_fab2_lib.baseboard_fab2(sch_1):page138_i87" )
				( pin "R8D17.1"
					( objectStatus "a" )
				)
				( pin "R8D17.2"
					( objectStatus "b" )
				)
			)
			( gate "R8D15"
				( objectStatus "@baseboard_fab2_lib.baseboard_fab2(sch_1):page138_i88" )
				( pin "R8D15.1"
					( objectStatus "a" )
				)
				( pin "R8D15.2"
					( objectStatus "b" )
				)
			)
			( gate "R2N8"
				( objectStatus "@baseboard_fab2_lib.baseboard_fab2(sch_1):page138_i89" )
				( pin "R2N8.1"
					( objectStatus "a" )
				)
				( pin "R2N8.2"
					( objectStatus "b" )
				)
			)
			( gate "R2N5"
				( objectStatus "@baseboard_fab2_lib.baseboard_fab2(sch_1):page138_i90" )
				( pin "R2N5.1"
					( objectStatus "a" )
				)
				( pin "R2N5.2"
					( objectStatus "b" )
				)
			)
			( gate "R8C16"
				( objectStatus "@baseboard_fab2_lib.baseboard_fab2(sch_1):page138_i91" )
				( pin "R8C16.1"
					( objectStatus "a" )
				)
				( pin "R8C16.2"
					( objectStatus "b" )
				)
			)
			( gate "R8C15"
				( objectStatus "@baseboard_fab2_lib.baseboard_fab2(sch_1):page138_i92" )
				( pin "R8C15.1"
					( objectStatus "a" )
				)
				( pin "R8C15.2"
					( objectStatus "b" )
				)
			)
			( gate "R8B24"
				( objectStatus "@baseboard_fab2_lib.baseboard_fab2(sch_1):page138_i95" )
				( pin "R8B24.1"
					( objectStatus "a" )
				)
				( pin "R8B24.2"
					( objectStatus "b" )
				)
			)
			( gate "R8B26"
				( objectStatus "@baseboard_fab2_lib.baseboard_fab2(sch_1):page138_i96" )
				( pin "R8B26.1"
					( objectStatus "a" )
				)
				( pin "R8B26.2"
					( objectStatus "b" )
				)
			)
			( gate "R2U11"
				( objectStatus "@baseboard_fab2_lib.baseboard_fab2(sch_1):page138_i97" )
				( pin "R2U11.1"
					( objectStatus "a" )
				)
				( pin "R2U11.2"
					( objectStatus "b" )
				)
			)
			( gate "R2U3"
				( objectStatus "@baseboard_fab2_lib.baseboard_fab2(sch_1):page138_i98" )
				( pin "R2U3.1"
					( objectStatus "a" )
				)
				( pin "R2U3.2"
					( objectStatus "b" )
				)
			)
			( gate "R2T55"
				( objectStatus "@baseboard_fab2_lib.baseboard_fab2(sch_1):page138_i116" )
				( pin "R2T55.1"
					( objectStatus "a" )
				)
				( pin "R2T55.2"
					( objectStatus "b" )
				)
			)
			( gate "R2U8"
				( objectStatus "@baseboard_fab2_lib.baseboard_fab2(sch_1):page138_i158" )
				( pin "R2U8.1"
					( objectStatus "a" )
				)
				( pin "R2U8.2"
					( objectStatus "b" )
				)
			)
			( gate "R2U12"
				( objectStatus "@baseboard_fab2_lib.baseboard_fab2(sch_1):page138_i159" )
				( pin "R2U12.1"
					( objectStatus "a" )
				)
				( pin "R2U12.2"
					( objectStatus "b" )
				)
			)
			( gate "R2T56"
				( objectStatus "@baseboard_fab2_lib.baseboard_fab2(sch_1):page138_i160" )
				( pin "R2T56.1"
					( objectStatus "a" )
				)
				( pin "R2T56.2"
					( objectStatus "b" )
				)
			)
			( gate "R8D3"
				( objectStatus "@baseboard_fab2_lib.baseboard_fab2(sch_1):page138_i161" )
				( pin "R8D3.1"
					( objectStatus "a" )
				)
				( pin "R8D3.2"
					( objectStatus "b" )
				)
			)
			( gate "R8D6"
				( objectStatus "@baseboard_fab2_lib.baseboard_fab2(sch_1):page138_i162" )
				( pin "R8D6.1"
					( objectStatus "a" )
				)
				( pin "R8D6.2"
					( objectStatus "b" )
				)
			)
			( gate "R8D7"
				( objectStatus "@baseboard_fab2_lib.baseboard_fab2(sch_1):page138_i163" )
				( pin "R8D7.1"
					( objectStatus "a" )
				)
				( pin "R8D7.2"
					( objectStatus "b" )
				)
			)
			( gate "R8D4"
				( objectStatus "@baseboard_fab2_lib.baseboard_fab2(sch_1):page138_i164" )
				( pin "R8D4.1"
					( objectStatus "a" )
				)
				( pin "R8D4.2"
					( objectStatus "b" )
				)
			)
			( gate "R2U9"
				( objectStatus "@baseboard_fab2_lib.baseboard_fab2(sch_1):page138_i165" )
				( pin "R2U9.1"
					( objectStatus "a" )
				)
				( pin "R2U9.2"
					( objectStatus "b" )
				)
			)
			( gate "R2U6"
				( objectStatus "@baseboard_fab2_lib.baseboard_fab2(sch_1):page138_i166" )
				( pin "R2U6.1"
					( objectStatus "a" )
				)
				( pin "R2U6.2"
					( objectStatus "b" )
				)
			)
			( gate "R8C20"
				( objectStatus "@baseboard_fab2_lib.baseboard_fab2(sch_1):page138_i167" )
				( pin "R8C20.1"
					( objectStatus "a" )
				)
				( pin "R8C20.2"
					( objectStatus "b" )
				)
			)
			( gate "R8C14"
				( objectStatus "@baseboard_fab2_lib.baseboard_fab2(sch_1):page138_i168" )
				( pin "R8C14.1"
					( objectStatus "a" )
				)
				( pin "R8C14.2"
					( objectStatus "b" )
				)
			)
			( gate "R8C11"
				( objectStatus "@baseboard_fab2_lib.baseboard_fab2(sch_1):page138_i169" )
				( pin "R8C11.1"
					( objectStatus "a" )
				)
				( pin "R8C11.2"
					( objectStatus "b" )
				)
			)
			( gate "R8C12"
				( objectStatus "@baseboard_fab2_lib.baseboard_fab2(sch_1):page138_i170" )
				( pin "R8C12.1"
					( objectStatus "a" )
				)
				( pin "R8C12.2"
					( objectStatus "b" )
				)
			)
			( gate "R2N20"
				( objectStatus "@baseboard_fab2_lib.baseboard_fab2(sch_1):page138_i171" )
				( pin "R2N20.1"
					( objectStatus "a" )
				)
				( pin "R2N20.2"
					( objectStatus "b" )
				)
			)
			( gate "R8B27"
				( objectStatus "@baseboard_fab2_lib.baseboard_fab2(sch_1):page138_i173" )
				( pin "R8B27.1"
					( objectStatus "a" )
				)
				( pin "R8B27.2"
					( objectStatus "b" )
				)
			)
			( gate "R8B28"
				( objectStatus "@baseboard_fab2_lib.baseboard_fab2(sch_1):page138_i174" )
				( pin "R8B28.1"
					( objectStatus "a" )
				)
				( pin "R8B28.2"
					( objectStatus "b" )
				)
			)
			( gate "R2N21"
				( objectStatus "@baseboard_fab2_lib.baseboard_fab2(sch_1):page138_i175" )
				( pin "R2N21.1"
					( objectStatus "a" )
				)
				( pin "R2N21.2"
					( objectStatus "b" )
				)
			)
			( gate "EU9E1"
				( objectStatus "@baseboard_fab2_lib.baseboard_fab2(sch_1):page139_i72" )
				( pin "EU9E1.37"
					( objectStatus "cbot" )
				)
				( pin "EU9E1.40"
					( objectStatus "ctop" )
				)
				( pin "EU9E1.28"
					( objectStatus "dev_off_n" )
				)
				( pin "EU9E1.65"
					( objectStatus "gnd" )
				)
				( pin "EU9E1.19"
					( objectStatus "jtag_clk" )
				)
				( pin "EU9E1.29"
					( objectStatus "jtag_tdi" )
				)
				( pin "EU9E1.4"
					( objectStatus "jtag_tdo" )
				)
				( pin "EU9E1.18"
					( objectStatus "jtag_tms" )
				)
				( pin "EU9E1.1"
					( objectStatus "lan_pwr_good" )
				)
				( pin "EU9E1.31"
					( objectStatus "led0" )
				)
				( pin "EU9E1.30"
					( objectStatus "led1" )
				)
				( pin "EU9E1.33"
					( objectStatus "led2" )
				)
				( pin "EU9E1.57"
					( objectStatus "mdi_minus0_sfp_i2c_data" )
				)
				( pin "EU9E1.54"
					( objectStatus "mdi_minus1_srds_sig_det" )
				)
				( pin "EU9E1.52"
					( objectStatus "mdi_minus2_setn" )
				)
				( pin "EU9E1.49"
					( objectStatus "mdi_minus3_sern" )
				)
				( pin "EU9E1.58"
					( objectStatus "mdi_plus0_nc" )
				)
				( pin "EU9E1.55"
					( objectStatus "mdi_plus1_sfp_i2c_clk" )
				)
				( pin "EU9E1.53"
					( objectStatus "mdi_plus2_setp" )
				)
				( pin "EU9E1.50"
					( objectStatus "mdi_plus3_serp" )
				)
				( pin "EU9E1.22"
					( objectStatus "nc" )
				)
				( pin "EU9E1.43"
					( objectStatus "nc_si_arb_in" )
				)
				( pin "EU9E1.44"
					( objectStatus "nc_si_arb_out" )
				)
				( pin "EU9E1.2"
					( objectStatus "nc_si_clk_in" )
				)
				( pin "EU9E1.3"
					( objectStatus "nc_si_crs_dv" )
				)
				( pin "EU9E1.6"
					( objectStatus "nc_si_rxd0" )
				)
				( pin "EU9E1.5"
					( objectStatus "nc_si_rxd1" )
				)
				( pin "EU9E1.7"
					( objectStatus "nc_si_tx_en" )
				)
				( pin "EU9E1.9"
					( objectStatus "nc_si_txd0" )
				)
				( pin "EU9E1.8"
					( objectStatus "nc_si_txd1" )
				)
				( pin "EU9E1.15"
					( objectStatus "nvm_cs_n" )
				)
				( pin "EU9E1.12"
					( objectStatus "nvm_si" )
				)
				( pin "EU9E1.13"
					( objectStatus "nvm_sk" )
				)
				( pin "EU9E1.14"
					( objectStatus "nvm_so" )
				)
				( pin "EU9E1.23"
					( objectStatus "pe_rn" )
				)
				( pin "EU9E1.24"
					( objectStatus "pe_rp" )
				)
				( pin "EU9E1.17"
					( objectStatus "pe_rst_n" )
				)
				( pin "EU9E1.20"
					( objectStatus "pe_tn" )
				)
				( pin "EU9E1.21"
					( objectStatus "pe_tp" )
				)
				( pin "EU9E1.16"
					( objectStatus "pe_wake_n" )
				)
				( pin "EU9E1.25"
					( objectStatus "peclkn" )
				)
				( pin "EU9E1.26"
					( objectStatus "peclkp" )
				)
				( pin "EU9E1.48"
					( objectStatus "rset" )
				)
				( pin "EU9E1.63"
					( objectStatus "sdp0" )
				)
				( pin "EU9E1.61"
					( objectStatus "sdp1_pcie_dis_sdp1" )
				)
				( pin "EU9E1.62"
					( objectStatus "sdp2" )
				)
				( pin "EU9E1.60"
					( objectStatus "sdp3" )
				)
				( pin "EU9E1.35"
					( objectStatus "smb_alrt_n" )
				)
				( pin "EU9E1.34"
					( objectStatus "smb_clk" )
				)
				( pin "EU9E1.36"
					( objectStatus "smb_data" )
				)
				( pin "EU9E1.59"
					( objectStatus "vdd0p9(0)" )
				)
				( pin "EU9E1.32"
					( objectStatus "vdd0p9(1)" )
				)
				( pin "EU9E1.11"
					( objectStatus "vdd0p9(2)" )
				)
				( pin "EU9E1.42"
					( objectStatus "vdd0p9(3)" )
				)
				( pin "EU9E1.38"
					( objectStatus "vdd0p9_out" )
				)
				( pin "EU9E1.56"
					( objectStatus "vdd1p5(0)" )
				)
				( pin "EU9E1.47"
					( objectStatus "vdd1p5(1)" )
				)
				( pin "EU9E1.39"
					( objectStatus "vdd1p5_out" )
				)
				( pin "EU9E1.64"
					( objectStatus "vdd3p3(0)" )
				)
				( pin "EU9E1.51"
					( objectStatus "vdd3p3(1)" )
				)
				( pin "EU9E1.41"
					( objectStatus "vdd3p3(2)" )
				)
				( pin "EU9E1.27"
					( objectStatus "vdd3p3(3)" )
				)
				( pin "EU9E1.10"
					( objectStatus "vdd3p3(4)" )
				)
				( pin "EU9E1.46"
					( objectStatus "xtal1" )
				)
				( pin "EU9E1.45"
					( objectStatus "xtal2" )
				)
			)
			( gate "C9E7"
				( objectStatus "@baseboard_fab2_lib.baseboard_fab2(sch_1):page139_i76" )
				( pin "C9E7.1"
					( objectStatus "a" )
				)
				( pin "C9E7.2"
					( objectStatus "b" )
				)
			)
			( gate "C9E5"
				( objectStatus "@baseboard_fab2_lib.baseboard_fab2(sch_1):page139_i87" )
				( pin "C9E5.1"
					( objectStatus "a" )
				)
				( pin "C9E5.2"
					( objectStatus "b" )
				)
			)
			( gate "C9E4"
				( objectStatus "@baseboard_fab2_lib.baseboard_fab2(sch_1):page139_i88" )
				( pin "C9E4.1"
					( objectStatus "a" )
				)
				( pin "C9E4.2"
					( objectStatus "b" )
				)
			)
			( gate "C2M23"
				( objectStatus "@baseboard_fab2_lib.baseboard_fab2(sch_1):page139_i89" )
				( pin "C2M23.1"
					( objectStatus "a" )
				)
				( pin "C2M23.2"
					( objectStatus "b" )
				)
			)
			( gate "C2M24"
				( objectStatus "@baseboard_fab2_lib.baseboard_fab2(sch_1):page139_i90" )
				( pin "C2M24.1"
					( objectStatus "a" )
				)
				( pin "C2M24.2"
					( objectStatus "b" )
				)
			)
			( gate "Y9E1"
				( objectStatus "@baseboard_fab2_lib.baseboard_fab2(sch_1):page139_i109" )
				( pin "Y9E1.1"
					( objectStatus "a" )
				)
				( pin "Y9E1.3"
					( objectStatus "b" )
				)
			)
			( gate "R9E20"
				( objectStatus "@baseboard_fab2_lib.baseboard_fab2(sch_1):page139_i110" )
				( pin "R9E20.1"
					( objectStatus "a" )
				)
				( pin "R9E20.2"
					( objectStatus "b" )
				)
			)
			( gate "C9E8"
				( objectStatus "@baseboard_fab2_lib.baseboard_fab2(sch_1):page139_i111" )
				( pin "C9E8.1"
					( objectStatus "a" )
				)
				( pin "C9E8.2"
					( objectStatus "b" )
				)
			)
			( gate "C9E9"
				( objectStatus "@baseboard_fab2_lib.baseboard_fab2(sch_1):page139_i112" )
				( pin "C9E9.1"
					( objectStatus "a" )
				)
				( pin "C9E9.2"
					( objectStatus "b" )
				)
			)
			( gate "R9E9"
				( objectStatus "@baseboard_fab2_lib.baseboard_fab2(sch_1):page139_i128" )
				( pin "R9E9.1"
					( objectStatus "a" )
				)
				( pin "R9E9.2"
					( objectStatus "b" )
				)
			)
			( gate "R9E5"
				( objectStatus "@baseboard_fab2_lib.baseboard_fab2(sch_1):page139_i129" )
				( pin "R9E5.1"
					( objectStatus "a" )
				)
				( pin "R9E5.2"
					( objectStatus "b" )
				)
			)
			( gate "R9E8"
				( objectStatus "@baseboard_fab2_lib.baseboard_fab2(sch_1):page139_i130" )
				( pin "R9E8.1"
					( objectStatus "a" )
				)
				( pin "R9E8.2"
					( objectStatus "b" )
				)
			)
			( gate "C1T4"
				( objectStatus "@baseboard_fab2_lib.baseboard_fab2(sch_1):page139_i134" )
				( pin "C1T4.1"
					( objectStatus "a" )
				)
				( pin "C1T4.2"
					( objectStatus "b" )
				)
			)
			( gate "C1R30"
				( objectStatus "@baseboard_fab2_lib.baseboard_fab2(sch_1):page139_i135" )
				( pin "C1R30.1"
					( objectStatus "a" )
				)
				( pin "C1R30.2"
					( objectStatus "b" )
				)
			)
			( gate "C1R22"
				( objectStatus "@baseboard_fab2_lib.baseboard_fab2(sch_1):page139_i136" )
				( pin "C1R22.1"
					( objectStatus "a" )
				)
				( pin "C1R22.2"
					( objectStatus "b" )
				)
			)
			( gate "C9F2"
				( objectStatus "@baseboard_fab2_lib.baseboard_fab2(sch_1):page139_i140" )
				( pin "C9F2.1"
					( objectStatus "a" )
				)
				( pin "C9F2.2"
					( objectStatus "b" )
				)
			)
			( gate "C1R13"
				( objectStatus "@baseboard_fab2_lib.baseboard_fab2(sch_1):page139_i142" )
				( pin "C1R13.1"
					( objectStatus "a" )
				)
				( pin "C1R13.2"
					( objectStatus "b" )
				)
			)
			( gate "C1R20"
				( objectStatus "@baseboard_fab2_lib.baseboard_fab2(sch_1):page139_i143" )
				( pin "C1R20.1"
					( objectStatus "a" )
				)
				( pin "C1R20.2"
					( objectStatus "b" )
				)
			)
			( gate "C1T3"
				( objectStatus "@baseboard_fab2_lib.baseboard_fab2(sch_1):page139_i144" )
				( pin "C1T3.1"
					( objectStatus "a" )
				)
				( pin "C1T3.2"
					( objectStatus "b" )
				)
			)
			( gate "C1R14"
				( objectStatus "@baseboard_fab2_lib.baseboard_fab2(sch_1):page139_i145" )
				( pin "C1R14.1"
					( objectStatus "a" )
				)
				( pin "C1R14.2"
					( objectStatus "b" )
				)
			)
			( gate "C1R21"
				( objectStatus "@baseboard_fab2_lib.baseboard_fab2(sch_1):page139_i146" )
				( pin "C1R21.1"
					( objectStatus "a" )
				)
				( pin "C1R21.2"
					( objectStatus "b" )
				)
			)
			( gate "C1R26"
				( objectStatus "@baseboard_fab2_lib.baseboard_fab2(sch_1):page139_i149" )
				( pin "C1R26.1"
					( objectStatus "a" )
				)
				( pin "C1R26.2"
					( objectStatus "b" )
				)
			)
			( gate "C1R29"
				( objectStatus "@baseboard_fab2_lib.baseboard_fab2(sch_1):page139_i150" )
				( pin "C1R29.1"
					( objectStatus "a" )
				)
				( pin "C1R29.2"
					( objectStatus "b" )
				)
			)
			( gate "C1R19"
				( objectStatus "@baseboard_fab2_lib.baseboard_fab2(sch_1):page139_i151" )
				( pin "C1R19.1"
					( objectStatus "a" )
				)
				( pin "C1R19.2"
					( objectStatus "b" )
				)
			)
			( gate "C1T1"
				( objectStatus "@baseboard_fab2_lib.baseboard_fab2(sch_1):page139_i152" )
				( pin "C1T1.1"
					( objectStatus "a" )
				)
				( pin "C1T1.2"
					( objectStatus "b" )
				)
			)
			( gate "C1R17"
				( objectStatus "@baseboard_fab2_lib.baseboard_fab2(sch_1):page139_i153" )
				( pin "C1R17.1"
					( objectStatus "a" )
				)
				( pin "C1R17.2"
					( objectStatus "b" )
				)
			)
			( gate "C9E6"
				( objectStatus "@baseboard_fab2_lib.baseboard_fab2(sch_1):page139_i155" )
				( pin "C9E6.1"
					( objectStatus "a" )
				)
				( pin "C9E6.2"
					( objectStatus "b" )
				)
			)
			( gate "C1R18"
				( objectStatus "@baseboard_fab2_lib.baseboard_fab2(sch_1):page139_i157" )
				( pin "C1R18.1"
					( objectStatus "a" )
				)
				( pin "C1R18.2"
					( objectStatus "b" )
				)
			)
			( gate "C1T5"
				( objectStatus "@baseboard_fab2_lib.baseboard_fab2(sch_1):page139_i158" )
				( pin "C1T5.1"
					( objectStatus "a" )
				)
				( pin "C1T5.2"
					( objectStatus "b" )
				)
			)
			( gate "C1R24"
				( objectStatus "@baseboard_fab2_lib.baseboard_fab2(sch_1):page139_i159" )
				( pin "C1R24.1"
					( objectStatus "a" )
				)
				( pin "C1R24.2"
					( objectStatus "b" )
				)
			)
			( gate "C1R15"
				( objectStatus "@baseboard_fab2_lib.baseboard_fab2(sch_1):page139_i160" )
				( pin "C1R15.1"
					( objectStatus "a" )
				)
				( pin "C1R15.2"
					( objectStatus "b" )
				)
			)
			( gate "C1R16"
				( objectStatus "@baseboard_fab2_lib.baseboard_fab2(sch_1):page139_i161" )
				( pin "C1R16.1"
					( objectStatus "a" )
				)
				( pin "C1R16.2"
					( objectStatus "b" )
				)
			)
			( gate "C9E1"
				( objectStatus "@baseboard_fab2_lib.baseboard_fab2(sch_1):page139_i163" )
				( pin "C9E1.1"
					( objectStatus "a" )
				)
				( pin "C9E1.2"
					( objectStatus "b" )
				)
			)
			( gate "R9F5"
				( objectStatus "@baseboard_fab2_lib.baseboard_fab2(sch_1):page139_i173" )
				( pin "R9F5.1"
					( objectStatus "a" )
				)
				( pin "R9F5.2"
					( objectStatus "b" )
				)
			)
			( gate "R9E23"
				( objectStatus "@baseboard_fab2_lib.baseboard_fab2(sch_1):page139_i174" )
				( pin "R9E23.1"
					( objectStatus "a" )
				)
				( pin "R9E23.2"
					( objectStatus "b" )
				)
			)
			( gate "R9E2"
				( objectStatus "@baseboard_fab2_lib.baseboard_fab2(sch_1):page139_i177" )
				( pin "R9E2.1"
					( objectStatus "a" )
				)
				( pin "R9E2.2"
					( objectStatus "b" )
				)
			)
			( gate "R9E3"
				( objectStatus "@baseboard_fab2_lib.baseboard_fab2(sch_1):page139_i178" )
				( pin "R9E3.1"
					( objectStatus "a" )
				)
				( pin "R9E3.2"
					( objectStatus "b" )
				)
			)
			( gate "R9E1"
				( objectStatus "@baseboard_fab2_lib.baseboard_fab2(sch_1):page139_i179" )
				( pin "R9E1.1"
					( objectStatus "a" )
				)
				( pin "R9E1.2"
					( objectStatus "b" )
				)
			)
			( gate "R9E22"
				( objectStatus "@baseboard_fab2_lib.baseboard_fab2(sch_1):page139_i181" )
				( pin "R9E22.1"
					( objectStatus "a" )
				)
				( pin "R9E22.2"
					( objectStatus "b" )
				)
			)
			( gate "R9E7"
				( objectStatus "@baseboard_fab2_lib.baseboard_fab2(sch_1):page139_i193" )
				( pin "R9E7.1"
					( objectStatus "a" )
				)
				( pin "R9E7.2"
					( objectStatus "b" )
				)
			)
			( gate "R1R1"
				( objectStatus "@baseboard_fab2_lib.baseboard_fab2(sch_1):page139_i195" )
				( pin "R1R1.1"
					( objectStatus "a" )
				)
				( pin "R1R1.2"
					( objectStatus "b" )
				)
			)
			( gate "R9E4"
				( objectStatus "@baseboard_fab2_lib.baseboard_fab2(sch_1):page139_i200" )
				( pin "R9E4.1"
					( objectStatus "a" )
				)
				( pin "R9E4.2"
					( objectStatus "b" )
				)
			)
			( gate "R9E18"
				( objectStatus "@baseboard_fab2_lib.baseboard_fab2(sch_1):page139_i201" )
				( pin "R9E18.1"
					( objectStatus "a" )
				)
				( pin "R9E18.2"
					( objectStatus "b" )
				)
			)
			( gate "R9E13"
				( objectStatus "@baseboard_fab2_lib.baseboard_fab2(sch_1):page139_i212" )
				( pin "R9E13.1"
					( objectStatus "a" )
				)
				( pin "R9E13.2"
					( objectStatus "b" )
				)
			)
			( gate "R1R12"
				( objectStatus "@baseboard_fab2_lib.baseboard_fab2(sch_1):page139_i213" )
				( pin "R1R12.1"
					( objectStatus "a" )
				)
				( pin "R1R12.2"
					( objectStatus "b" )
				)
			)
			( gate "R1T1"
				( objectStatus "@baseboard_fab2_lib.baseboard_fab2(sch_1):page139_i214" )
				( pin "R1T1.1"
					( objectStatus "a" )
				)
				( pin "R1T1.2"
					( objectStatus "b" )
				)
			)
			( gate "R9F1"
				( objectStatus "@baseboard_fab2_lib.baseboard_fab2(sch_1):page139_i225" )
				( pin "R9F1.1"
					( objectStatus "a" )
				)
				( pin "R9F1.2"
					( objectStatus "b" )
				)
			)
			( gate "R9E19"
				( objectStatus "@baseboard_fab2_lib.baseboard_fab2(sch_1):page139_i228" )
				( pin "R9E19.1"
					( objectStatus "a" )
				)
				( pin "R9E19.2"
					( objectStatus "b" )
				)
			)
			( gate "R9E17"
				( objectStatus "@baseboard_fab2_lib.baseboard_fab2(sch_1):page139_i229" )
				( pin "R9E17.1"
					( objectStatus "a" )
				)
				( pin "R9E17.2"
					( objectStatus "b" )
				)
			)
			( gate "R9E16"
				( objectStatus "@baseboard_fab2_lib.baseboard_fab2(sch_1):page139_i235" )
				( pin "R9E16.1"
					( objectStatus "a" )
				)
				( pin "R9E16.2"
					( objectStatus "b" )
				)
			)
			( gate "R1R15"
				( objectStatus "@baseboard_fab2_lib.baseboard_fab2(sch_1):page139_i237" )
				( pin "R1R15.1"
					( objectStatus "a" )
				)
				( pin "R1R15.2"
					( objectStatus "b" )
				)
			)
			( gate "R1T32"
				( objectStatus "@baseboard_fab2_lib.baseboard_fab2(sch_1):page139_i238" )
				( pin "R1T32.1"
					( objectStatus "a" )
				)
				( pin "R1T32.2"
					( objectStatus "b" )
				)
			)
			( gate "R1T34"
				( objectStatus "@baseboard_fab2_lib.baseboard_fab2(sch_1):page139_i239" )
				( pin "R1T34.1"
					( objectStatus "a" )
				)
				( pin "R1T34.2"
					( objectStatus "b" )
				)
			)
			( gate "R1T33"
				( objectStatus "@baseboard_fab2_lib.baseboard_fab2(sch_1):page139_i240" )
				( pin "R1T33.1"
					( objectStatus "a" )
				)
				( pin "R1T33.2"
					( objectStatus "b" )
				)
			)
			( gate "C42"
				( objectStatus "@baseboard_fab2_lib.baseboard_fab2(sch_1):page139_i241" )
				( pin "C42.1"
					( objectStatus "a" )
				)
				( pin "C42.2"
					( objectStatus "b" )
				)
			)
			( gate "U9E1"
				( objectStatus "@baseboard_fab2_lib.baseboard_fab2(sch_1):page140_i1" )
				( pin "U9E1.6"
					( objectStatus "c" )
				)
				( pin "U9E1.5"
					( objectStatus "dq0" )
				)
				( pin "U9E1.2"
					( objectStatus "dq1" )
				)
				( pin "U9E1.7"
					( objectStatus "reset_n" )
				)
				( pin "U9E1.1"
					( objectStatus "s_n" )
				)
				( pin "U9E1.8"
					( objectStatus "vcc" )
				)
				( pin "U9E1.4"
					( objectStatus "vss" )
				)
				( pin "U9E1.3"
					( objectStatus "w_n" )
				)
			)
			( gate "C1R25"
				( objectStatus "@baseboard_fab2_lib.baseboard_fab2(sch_1):page140_i3" )
				( pin "C1R25.1"
					( objectStatus "a" )
				)
				( pin "C1R25.2"
					( objectStatus "b" )
				)
			)
			( gate "R1R9"
				( objectStatus "@baseboard_fab2_lib.baseboard_fab2(sch_1):page140_i10" )
				( pin "R1R9.1"
					( objectStatus "a" )
				)
				( pin "R1R9.2"
					( objectStatus "b" )
				)
			)
			( gate "R1R3"
				( objectStatus "@baseboard_fab2_lib.baseboard_fab2(sch_1):page140_i11" )
				( pin "R1R3.1"
					( objectStatus "a" )
				)
				( pin "R1R3.2"
					( objectStatus "b" )
				)
			)
			( gate "R1R7"
				( objectStatus "@baseboard_fab2_lib.baseboard_fab2(sch_1):page140_i12" )
				( pin "R1R7.1"
					( objectStatus "a" )
				)
				( pin "R1R7.2"
					( objectStatus "b" )
				)
			)
			( gate "R1R6"
				( objectStatus "@baseboard_fab2_lib.baseboard_fab2(sch_1):page140_i14" )
				( pin "R1R6.1"
					( objectStatus "a" )
				)
				( pin "R1R6.2"
					( objectStatus "b" )
				)
			)
			( gate "R9E6"
				( objectStatus "@baseboard_fab2_lib.baseboard_fab2(sch_1):page140_i17" )
				( pin "R9E6.1"
					( objectStatus "a" )
				)
				( pin "R9E6.2"
					( objectStatus "b" )
				)
			)
			( gate "R9G3"
				( objectStatus "@baseboard_fab2_lib.baseboard_fab2(sch_1):page141_i28" )
				( pin "R9G3.1"
					( objectStatus "a" )
				)
				( pin "R9G3.2"
					( objectStatus "b" )
				)
			)
			( gate "R9G2"
				( objectStatus "@baseboard_fab2_lib.baseboard_fab2(sch_1):page141_i30" )
				( pin "R9G2.1"
					( objectStatus "a" )
				)
				( pin "R9G2.2"
					( objectStatus "b" )
				)
			)
			( gate "C9G7"
				( objectStatus "@baseboard_fab2_lib.baseboard_fab2(sch_1):page141_i33" )
				( pin "C9G7.1"
					( objectStatus "a" )
				)
				( pin "C9G7.2"
					( objectStatus "b" )
				)
			)
			( gate "C9G2"
				( objectStatus "@baseboard_fab2_lib.baseboard_fab2(sch_1):page141_i36" )
				( pin "C9G2.1"
					( objectStatus "a" )
				)
				( pin "C9G2.2"
					( objectStatus "b" )
				)
			)
			( gate "C9G4"
				( objectStatus "@baseboard_fab2_lib.baseboard_fab2(sch_1):page141_i46" )
				( pin "C9G4.1"
					( objectStatus "a" )
				)
				( pin "C9G4.2"
					( objectStatus "b" )
				)
			)
			( gate "C9G6"
				( objectStatus "@baseboard_fab2_lib.baseboard_fab2(sch_1):page141_i47" )
				( pin "C9G6.1"
					( objectStatus "a" )
				)
				( pin "C9G6.2"
					( objectStatus "b" )
				)
			)
			( gate "C9G5"
				( objectStatus "@baseboard_fab2_lib.baseboard_fab2(sch_1):page141_i48" )
				( pin "C9G5.1"
					( objectStatus "a" )
				)
				( pin "C9G5.2"
					( objectStatus "b" )
				)
			)
			( gate "R9G1"
				( objectStatus "@baseboard_fab2_lib.baseboard_fab2(sch_1):page141_i54" )
				( pin "R9G1.1"
					( objectStatus "a" )
				)
				( pin "R9G1.2"
					( objectStatus "b" )
				)
			)
			( gate "R9G4"
				( objectStatus "@baseboard_fab2_lib.baseboard_fab2(sch_1):page141_i56" )
				( pin "R9G4.1"
					( objectStatus "a" )
				)
				( pin "R9G4.2"
					( objectStatus "b" )
				)
			)
			( gate "C9G1"
				( objectStatus "@baseboard_fab2_lib.baseboard_fab2(sch_1):page141_i58" )
				( pin "C9G1.1"
					( objectStatus "a" )
				)
				( pin "C9G1.2"
					( objectStatus "b" )
				)
			)
			( gate "C9G3"
				( objectStatus "@baseboard_fab2_lib.baseboard_fab2(sch_1):page141_i59" )
				( pin "C9G3.1"
					( objectStatus "a" )
				)
				( pin "C9G3.2"
					( objectStatus "b" )
				)
			)
			( gate "C9F22"
				( objectStatus "@baseboard_fab2_lib.baseboard_fab2(sch_1):page141_i60" )
				( pin "C9F22.1"
					( objectStatus "a" )
				)
				( pin "C9F22.2"
					( objectStatus "b" )
				)
			)
			( gate "R9G9"
				( objectStatus "@baseboard_fab2_lib.baseboard_fab2(sch_1):page141_i75" )
				( pin "R9G9.1"
					( objectStatus "a" )
				)
				( pin "R9G9.2"
					( objectStatus "b" )
				)
			)
			( gate "R9G11"
				( objectStatus "@baseboard_fab2_lib.baseboard_fab2(sch_1):page141_i76" )
				( pin "R9G11.1"
					( objectStatus "a" )
				)
				( pin "R9G11.2"
					( objectStatus "b" )
				)
			)
			( gate "R9G18"
				( objectStatus "@baseboard_fab2_lib.baseboard_fab2(sch_1):page141_i77" )
				( pin "R9G18.1"
					( objectStatus "a" )
				)
				( pin "R9G18.2"
					( objectStatus "b" )
				)
			)
			( gate "R9G17"
				( objectStatus "@baseboard_fab2_lib.baseboard_fab2(sch_1):page141_i78" )
				( pin "R9G17.1"
					( objectStatus "a" )
				)
				( pin "R9G17.2"
					( objectStatus "b" )
				)
			)
			( gate "R9G19"
				( objectStatus "@baseboard_fab2_lib.baseboard_fab2(sch_1):page141_i79" )
				( pin "R9G19.1"
					( objectStatus "a" )
				)
				( pin "R9G19.2"
					( objectStatus "b" )
				)
			)
			( gate "R9G20"
				( objectStatus "@baseboard_fab2_lib.baseboard_fab2(sch_1):page141_i80" )
				( pin "R9G20.1"
					( objectStatus "a" )
				)
				( pin "R9G20.2"
					( objectStatus "b" )
				)
			)
			( gate "R9G24"
				( objectStatus "@baseboard_fab2_lib.baseboard_fab2(sch_1):page141_i81" )
				( pin "R9G24.1"
					( objectStatus "a" )
				)
				( pin "R9G24.2"
					( objectStatus "b" )
				)
			)
			( gate "R9G22"
				( objectStatus "@baseboard_fab2_lib.baseboard_fab2(sch_1):page141_i82" )
				( pin "R9G22.1"
					( objectStatus "a" )
				)
				( pin "R9G22.2"
					( objectStatus "b" )
				)
			)
			( gate "C9G9"
				( objectStatus "@baseboard_fab2_lib.baseboard_fab2(sch_1):page141_i99" )
				( pin "C9G9.1"
					( objectStatus "a" )
				)
				( pin "C9G9.2"
					( objectStatus "b" )
				)
			)
			( gate "C9G12"
				( objectStatus "@baseboard_fab2_lib.baseboard_fab2(sch_1):page141_i100" )
				( pin "C9G12.1"
					( objectStatus "a" )
				)
				( pin "C9G12.2"
					( objectStatus "b" )
				)
			)
			( gate "C9G16"
				( objectStatus "@baseboard_fab2_lib.baseboard_fab2(sch_1):page141_i101" )
				( pin "C9G16.1"
					( objectStatus "a" )
				)
				( pin "C9G16.2"
					( objectStatus "b" )
				)
			)
			( gate "C9G13"
				( objectStatus "@baseboard_fab2_lib.baseboard_fab2(sch_1):page141_i102" )
				( pin "C9G13.1"
					( objectStatus "a" )
				)
				( pin "C9G13.2"
					( objectStatus "b" )
				)
			)
			( gate "JA9G1"
				( objectStatus "@baseboard_fab2_lib.baseboard_fab2(sch_1):page141_i109" )
				( pin "JA9G1.L1"
					( objectStatus "l1" )
				)
				( pin "JA9G1.L2"
					( objectStatus "l2" )
				)
				( pin "JA9G1.L3"
					( objectStatus "l3" )
				)
				( pin "JA9G1.L4"
					( objectStatus "l4" )
				)
				( pin "JA9G1.L5"
					( objectStatus "l5" )
				)
				( pin "JA9G1.MH1"
					( objectStatus "mh1" )
				)
				( pin "JA9G1.MH2"
					( objectStatus "mh2" )
				)
				( pin "JA9G1.R12"
					( objectStatus "trct1" )
				)
				( pin "JA9G1.R6"
					( objectStatus "trct2" )
				)
				( pin "JA9G1.R1"
					( objectStatus "trct3" )
				)
				( pin "JA9G1.R7"
					( objectStatus "trct4" )
				)
				( pin "JA9G1.R10"
					( objectStatus "trd1n" )
				)
				( pin "JA9G1.R11"
					( objectStatus "trd1p" )
				)
				( pin "JA9G1.R5"
					( objectStatus "trd2n" )
				)
				( pin "JA9G1.R4"
					( objectStatus "trd2p" )
				)
				( pin "JA9G1.R2"
					( objectStatus "trd3n" )
				)
				( pin "JA9G1.R3"
					( objectStatus "trd3p" )
				)
				( pin "JA9G1.R9"
					( objectStatus "trd4n" )
				)
				( pin "JA9G1.R8"
					( objectStatus "trd4p" )
				)
			)
			( gate "R1U51"
				( objectStatus "@baseboard_fab2_lib.baseboard_fab2(sch_1):page141_i112" )
				( pin "R1U51.1"
					( objectStatus "a" )
				)
				( pin "R1U51.2"
					( objectStatus "b" )
				)
			)
			( gate "R1U3"
				( objectStatus "@baseboard_fab2_lib.baseboard_fab2(sch_1):page141_i114" )
				( pin "R1U3.1"
					( objectStatus "a" )
				)
				( pin "R1U3.2"
					( objectStatus "b" )
				)
			)
			( gate "U8E4"
				( objectStatus "@baseboard_fab2_lib.baseboard_fab2(sch_1):page142_i1" )
				( pin "U8E4.2"
					( objectStatus "a" )
				)
				( pin "U8E4.1"
					( objectStatus "oe" )
				)
				( pin "U8E4.4"
					( objectStatus "y" )
				)
			)
			( gate "R8E17"
				( objectStatus "@baseboard_fab2_lib.baseboard_fab2(sch_1):page142_i2" )
				( pin "R8E17.1"
					( objectStatus "a" )
				)
				( pin "R8E17.2"
					( objectStatus "b" )
				)
			)
			( gate "R8E23"
				( objectStatus "@baseboard_fab2_lib.baseboard_fab2(sch_1):page142_i3" )
				( pin "R8E23.1"
					( objectStatus "a" )
				)
				( pin "R8E23.2"
					( objectStatus "b" )
				)
			)
			( gate "R8E29"
				( objectStatus "@baseboard_fab2_lib.baseboard_fab2(sch_1):page142_i18" )
				( pin "R8E29.1"
					( objectStatus "a" )
				)
				( pin "R8E29.2"
					( objectStatus "b" )
				)
			)
			( gate "C8E5"
				( objectStatus "@baseboard_fab2_lib.baseboard_fab2(sch_1):page142_i20" )
				( pin "C8E5.1"
					( objectStatus "a" )
				)
				( pin "C8E5.2"
					( objectStatus "b" )
				)
			)
			( gate "R8E30"
				( objectStatus "@baseboard_fab2_lib.baseboard_fab2(sch_1):page142_i23" )
				( pin "R8E30.1"
					( objectStatus "a" )
				)
				( pin "R8E30.2"
					( objectStatus "b" )
				)
			)
			( gate "R8E36"
				( objectStatus "@baseboard_fab2_lib.baseboard_fab2(sch_1):page142_i28" )
				( pin "R8E36.1"
					( objectStatus "a" )
				)
				( pin "R8E36.2"
					( objectStatus "b" )
				)
			)
			( gate "R8E26"
				( objectStatus "@baseboard_fab2_lib.baseboard_fab2(sch_1):page142_i30" )
				( pin "R8E26.1"
					( objectStatus "a" )
				)
				( pin "R8E26.2"
					( objectStatus "b" )
				)
			)
			( gate "R8E28"
				( objectStatus "@baseboard_fab2_lib.baseboard_fab2(sch_1):page142_i31" )
				( pin "R8E28.1"
					( objectStatus "a" )
				)
				( pin "R8E28.2"
					( objectStatus "b" )
				)
			)
			( gate "R8E27"
				( objectStatus "@baseboard_fab2_lib.baseboard_fab2(sch_1):page142_i32" )
				( pin "R8E27.1"
					( objectStatus "a" )
				)
				( pin "R8E27.2"
					( objectStatus "b" )
				)
			)
			( gate "R8E21"
				( objectStatus "@baseboard_fab2_lib.baseboard_fab2(sch_1):page142_i33" )
				( pin "R8E21.1"
					( objectStatus "a" )
				)
				( pin "R8E21.2"
					( objectStatus "b" )
				)
			)
			( gate "U9F4"
				( objectStatus "@baseboard_fab2_lib.baseboard_fab2(sch_1):page143_i281" )
				( pin "U9F4.AB14"
					( objectStatus "ma(0)" )
				)
				( pin "U9F4.W15"
					( objectStatus "ma(1)" )
				)
				( pin "U9F4.V15"
					( objectStatus "ma(2)" )
				)
				( pin "U9F4.Y16"
					( objectStatus "ma(3)" )
				)
				( pin "U9F4.AB15"
					( objectStatus "ma(4)" )
				)
				( pin "U9F4.W16"
					( objectStatus "ma(5)" )
				)
				( pin "U9F4.AA15"
					( objectStatus "ma(6)" )
				)
				( pin "U9F4.AB18"
					( objectStatus "ma(7)" )
				)
				( pin "U9F4.AB16"
					( objectStatus "ma(8)" )
				)
				( pin "U9F4.AA17"
					( objectStatus "ma(9)" )
				)
				( pin "U9F4.Y15"
					( objectStatus "ma(10)" )
				)
				( pin "U9F4.AA16"
					( objectStatus "ma(11)" )
				)
				( pin "U9F4.W17"
					( objectStatus "ma(12)" )
				)
				( pin "U9F4.Y17"
					( objectStatus "ma(13)" )
				)
				( pin "U9F4.AB17"
					( objectStatus "ma(14)" )
				)
				( pin "U9F4.W14"
					( objectStatus "mba(0)" )
				)
				( pin "U9F4.AA14"
					( objectStatus "mba(1)" )
				)
				( pin "U9F4.Y14"
					( objectStatus "mba(2)" )
				)
				( pin "U9F4.AB13"
					( objectStatus "mcas_n" )
				)
				( pin "U9F4.Y12"
					( objectStatus "mcke" )
				)
				( pin "U9F4.AA12"
					( objectStatus "mckn" )
				)
				( pin "U9F4.AB12"
					( objectStatus "mckp" )
				)
				( pin "U9F4.AA13"
					( objectStatus "mcs_n" )
				)
				( pin "U9F4.W10"
					( objectStatus "mdm(0)" )
				)
				( pin "U9F4.V8"
					( objectStatus "mdm(1)" )
				)
				( pin "U9F4.W12"
					( objectStatus "mdq(0)" )
				)
				( pin "U9F4.V12"
					( objectStatus "mdq(1)" )
				)
				( pin "U9F4.AB11"
					( objectStatus "mdq(2)" )
				)
				( pin "U9F4.AA11"
					( objectStatus "mdq(3)" )
				)
				( pin "U9F4.Y11"
					( objectStatus "mdq(4)" )
				)
				( pin "U9F4.W11"
					( objectStatus "mdq(5)" )
				)
				( pin "U9F4.V11"
					( objectStatus "mdq(6)" )
				)
				( pin "U9F4.Y10"
					( objectStatus "mdq(7)" )
				)
				( pin "U9F4.V10"
					( objectStatus "mdq(8)" )
				)
				( pin "U9F4.AB9"
					( objectStatus "mdq(9)" )
				)
				( pin "U9F4.AA9"
					( objectStatus "mdq(10)" )
				)
				( pin "U9F4.Y9"
					( objectStatus "mdq(11)" )
				)
				( pin "U9F4.W9"
					( objectStatus "mdq(12)" )
				)
				( pin "U9F4.V9"
					( objectStatus "mdq(13)" )
				)
				( pin "U9F4.Y8"
					( objectStatus "mdq(14)" )
				)
				( pin "U9F4.W8"
					( objectStatus "mdq(15)" )
				)
				( pin "U9F4.AB10"
					( objectStatus "mdqs0" )
				)
				( pin "U9F4.AA10"
					( objectStatus "mdqs0_n" )
				)
				( pin "U9F4.AA8"
					( objectStatus "mdqs1" )
				)
				( pin "U9F4.AB8"
					( objectStatus "mdqs1_n" )
				)
				( pin "U9F4.V16"
					( objectStatus "mioz" )
				)
				( pin "U9F4.V14"
					( objectStatus "modt" )
				)
				( pin "U9F4.W13"
					( objectStatus "mras_n" )
				)
				( pin "U9F4.V13"
					( objectStatus "mvref" )
				)
				( pin "U9F4.Y13"
					( objectStatus "mwe_n" )
				)
			)
			( gate "C1T37"
				( objectStatus "@baseboard_fab2_lib.baseboard_fab2(sch_1):page143_i336" )
				( pin "C1T37.1"
					( objectStatus "a" )
				)
				( pin "C1T37.2"
					( objectStatus "b" )
				)
			)
			( gate "U9F4"
				( objectStatus "@baseboard_fab2_lib.baseboard_fab2(sch_1):page144_i347" )
				( pin "U9F4.R4"
					( objectStatus "dacb" )
				)
				( pin "U9F4.R3"
					( objectStatus "dacg" )
				)
				( pin "U9F4.R2"
					( objectStatus "dacr" )
				)
				( pin "U9F4.R1"
					( objectStatus "dacrset" )
				)
				( pin "U9F4.T2"
					( objectStatus "ddcclk_gpioj6" )
				)
				( pin "U9F4.T1"
					( objectStatus "ddcdat_gpioj7" )
				)
				( pin "U9F4.AB20"
					( objectStatus "dn_usb2_dn_usb2_hdn" )
				)
				( pin "U9F4.K3"
					( objectStatus "dn_usb11_dn_usb11_hdn2" )
				)
				( pin "U9F4.AB21"
					( objectStatus "dp_usb2_dp_usb2_hdp" )
				)
				( pin "U9F4.K4"
					( objectStatus "dp_usb11_dp_usb11_hdp2" )
				)
				( pin "U9F4.C5"
					( objectStatus "gpioa4_timer5_scl9" )
				)
				( pin "U9F4.B4"
					( objectStatus "gpioa5_timer6_sda9" )
				)
				( pin "U9F4.J21"
					( objectStatus "gpiob0_salt1" )
				)
				( pin "U9F4.J20"
					( objectStatus "gpiob1_salt2" )
				)
				( pin "U9F4.H18"
					( objectStatus "gpiob2_salt3" )
				)
				( pin "U9F4.F18"
					( objectStatus "gpiob3_salt4" )
				)
				( pin "U9F4.E19"
					( objectStatus "gpiob4_lpcrst_n" )
				)
				( pin "U9F4.H19"
					( objectStatus "gpiob5_lpcpd_n_lpcsmi_n" )
				)
				( pin "U9F4.H20"
					( objectStatus "gpiob6_lpcpme_n" )
				)
				( pin "U9F4.A14"
					( objectStatus "gpiog0_sgpsck" )
				)
				( pin "U9F4.E13"
					( objectStatus "gpiog1_sgpsld" )
				)
				( pin "U9F4.D13"
					( objectStatus "gpiog2_sgpsi0" )
				)
				( pin "U9F4.C13"
					( objectStatus "gpiog3_sgpsi1" )
				)
				( pin "U9F4.C22"
					( objectStatus "gpioi0_syscs_n" )
				)
				( pin "U9F4.G18"
					( objectStatus "gpioi1_sysck" )
				)
				( pin "U9F4.D19"
					( objectStatus "gpioi2_sysdo" )
				)
				( pin "U9F4.C20"
					( objectStatus "gpioi3_sysdi" )
				)
				( pin "U9F4.B22"
					( objectStatus "gpioi4_spics0_n_vbcs_n" )
				)
				( pin "U9F4.G19"
					( objectStatus "gpioi5_spick_vbck" )
				)
				( pin "U9F4.C18"
					( objectStatus "gpioi6_spido_vbdo" )
				)
				( pin "U9F4.E20"
					( objectStatus "gpioi7_spidi_vbdi" )
				)
				( pin "U9F4.J5"
					( objectStatus "gpioj0_sgpmck" )
				)
				( pin "U9F4.J4"
					( objectStatus "gpioj1_sgpmld" )
				)
				( pin "U9F4.K5"
					( objectStatus "gpioj2_sgpmo" )
				)
				( pin "U9F4.J3"
					( objectStatus "gpioj3_sgpmi" )
				)
				( pin "U9F4.E3"
					( objectStatus "gpiok0_scl5" )
				)
				( pin "U9F4.D2"
					( objectStatus "gpiok1_sda5" )
				)
				( pin "U9F4.C1"
					( objectStatus "gpiok2_scl6" )
				)
				( pin "U9F4.F4"
					( objectStatus "gpiok3_sda6" )
				)
				( pin "U9F4.E2"
					( objectStatus "gpiok4_scl7" )
				)
				( pin "U9F4.D1"
					( objectStatus "gpiok5_sda7" )
				)
				( pin "U9F4.G5"
					( objectStatus "gpiok6_scl8" )
				)
				( pin "U9F4.F3"
					( objectStatus "gpiok7_sda8" )
				)
				( pin "U9F4.D3"
					( objectStatus "gpioq0_scl3" )
				)
				( pin "U9F4.C2"
					( objectStatus "gpioq1_sda3" )
				)
				( pin "U9F4.B1"
					( objectStatus "gpioq2_scl4" )
				)
				( pin "U9F4.F5"
					( objectStatus "gpioq3_sda4" )
				)
				( pin "U9F4.B21"
					( objectStatus "lad(0)" )
				)
				( pin "U9F4.A22"
					( objectStatus "lad(1)" )
				)
				( pin "U9F4.F19"
					( objectStatus "lad(2)" )
				)
				( pin "U9F4.C19"
					( objectStatus "lad(3)" )
				)
				( pin "U9F4.B20"
					( objectStatus "lclk" )
				)
				( pin "U9F4.A21"
					( objectStatus "lframe_n" )
				)
				( pin "U9F4.E17"
					( objectStatus "lsirq_n" )
				)
				( pin "U9F4.E1"
					( objectStatus "ntrst" )
				)
				( pin "U9F4.G4"
					( objectStatus "rtck" )
				)
				( pin "U9F4.K21"
					( objectStatus "scl(1)" )
				)
				( pin "U9F4.J19"
					( objectStatus "scl(2)" )
				)
				( pin "U9F4.K22"
					( objectStatus "sda(1)" )
				)
				( pin "U9F4.J18"
					( objectStatus "sda(2)" )
				)
				( pin "U9F4.F2"
					( objectStatus "tck" )
				)
				( pin "U9F4.F1"
					( objectStatus "tdi" )
				)
				( pin "U9F4.G3"
					( objectStatus "tdo" )
				)
				( pin "U9F4.G2"
					( objectStatus "tms" )
				)
				( pin "U9F4.AA20"
					( objectStatus "usb2vres" )
				)
				( pin "U9F4.J2"
					( objectStatus "usb11_hdn" )
				)
				( pin "U9F4.J1"
					( objectStatus "usb11_hdp" )
				)
				( pin "U9F4.T4"
					( objectStatus "vgahs_gpioj4" )
				)
				( pin "U9F4.U2"
					( objectStatus "vgavs_gpioj5" )
				)
			)
			( gate "R9F7"
				( objectStatus "@baseboard_fab2_lib.baseboard_fab2(sch_1):page144_i405" )
				( pin "R9F7.1"
					( objectStatus "a" )
				)
				( pin "R9F7.2"
					( objectStatus "b" )
				)
			)
			( gate "R9G8"
				( objectStatus "@baseboard_fab2_lib.baseboard_fab2(sch_1):page144_i457" )
				( pin "R9G8.1"
					( objectStatus "a" )
				)
				( pin "R9G8.2"
					( objectStatus "b" )
				)
			)
			( gate "R1T25"
				( objectStatus "@baseboard_fab2_lib.baseboard_fab2(sch_1):page144_i461" )
				( pin "R1T25.1"
					( objectStatus "a" )
				)
				( pin "R1T25.2"
					( objectStatus "b" )
				)
			)
			( gate "R9G5"
				( objectStatus "@baseboard_fab2_lib.baseboard_fab2(sch_1):page144_i516" )
				( pin "R9G5.1"
					( objectStatus "a" )
				)
				( pin "R9G5.2"
					( objectStatus "b" )
				)
			)
			( gate "R9G6"
				( objectStatus "@baseboard_fab2_lib.baseboard_fab2(sch_1):page144_i517" )
				( pin "R9G6.1"
					( objectStatus "a" )
				)
				( pin "R9G6.2"
					( objectStatus "b" )
				)
			)
			( gate "R2T24"
				( objectStatus "@baseboard_fab2_lib.baseboard_fab2(sch_1):page144_i520" )
				( pin "R2T24.1"
					( objectStatus "a" )
				)
				( pin "R2T24.2"
					( objectStatus "b" )
				)
			)
			( gate "R3N27"
				( objectStatus "@baseboard_fab2_lib.baseboard_fab2(sch_1):page144_i521" )
				( pin "R3N27.1"
					( objectStatus "a" )
				)
				( pin "R3N27.2"
					( objectStatus "b" )
				)
			)
			( gate "R3N25"
				( objectStatus "@baseboard_fab2_lib.baseboard_fab2(sch_1):page144_i527" )
				( pin "R3N25.1"
					( objectStatus "a" )
				)
				( pin "R3N25.2"
					( objectStatus "b" )
				)
			)
			( gate "R2T15"
				( objectStatus "@baseboard_fab2_lib.baseboard_fab2(sch_1):page144_i532" )
				( pin "R2T15.1"
					( objectStatus "a" )
				)
				( pin "R2T15.2"
					( objectStatus "b" )
				)
			)
			( gate "R1U13"
				( objectStatus "@baseboard_fab2_lib.baseboard_fab2(sch_1):page144_i546" )
				( pin "R1U13.1"
					( objectStatus "a" )
				)
				( pin "R1U13.2"
					( objectStatus "b" )
				)
			)
			( gate "R1U12"
				( objectStatus "@baseboard_fab2_lib.baseboard_fab2(sch_1):page144_i547" )
				( pin "R1U12.1"
					( objectStatus "a" )
				)
				( pin "R1U12.2"
					( objectStatus "b" )
				)
			)
			( gate "R1U14"
				( objectStatus "@baseboard_fab2_lib.baseboard_fab2(sch_1):page144_i548" )
				( pin "R1U14.1"
					( objectStatus "a" )
				)
				( pin "R1U14.2"
					( objectStatus "b" )
				)
			)
			( gate "R3N24"
				( objectStatus "@baseboard_fab2_lib.baseboard_fab2(sch_1):page144_i553" )
				( pin "R3N24.1"
					( objectStatus "a" )
				)
				( pin "R3N24.2"
					( objectStatus "b" )
				)
			)
			( gate "R3N28"
				( objectStatus "@baseboard_fab2_lib.baseboard_fab2(sch_1):page144_i554" )
				( pin "R3N28.1"
					( objectStatus "a" )
				)
				( pin "R3N28.2"
					( objectStatus "b" )
				)
			)
			( gate "R3N26"
				( objectStatus "@baseboard_fab2_lib.baseboard_fab2(sch_1):page144_i555" )
				( pin "R3N26.1"
					( objectStatus "a" )
				)
				( pin "R3N26.2"
					( objectStatus "b" )
				)
			)
			( gate "R1U52"
				( objectStatus "@baseboard_fab2_lib.baseboard_fab2(sch_1):page144_i557" )
				( pin "R1U52.1"
					( objectStatus "a" )
				)
				( pin "R1U52.2"
					( objectStatus "b" )
				)
			)
			( gate "U9F4"
				( objectStatus "@baseboard_fab2_lib.baseboard_fab2(sch_1):page145_i100" )
				( pin "U9F4.AB22"
					( objectStatus "clkin" )
				)
				( pin "U9F4.E4"
					( objectStatus "entest" )
				)
				( pin "U9F4.D6"
					( objectStatus "gpioa0_mac1link" )
				)
				( pin "U9F4.B5"
					( objectStatus "gpioa1_mac2link" )
				)
				( pin "U9F4.A4"
					( objectStatus "gpioa2_timer3" )
				)
				( pin "U9F4.E6"
					( objectStatus "gpioa3_timer4" )
				)
				( pin "U9F4.E18"
					( objectStatus "gpiob7_extrst_n_spics1_n" )
				)
				( pin "U9F4.C4"
					( objectStatus "gpioc0_sd1clk_scl10" )
				)
				( pin "U9F4.B3"
					( objectStatus "gpioc1_sd1cmd_sda10" )
				)
				( pin "U9F4.A2"
					( objectStatus "gpioc2_sd1dat0_scl11" )
				)
				( pin "U9F4.E5"
					( objectStatus "gpioc3_sd1dat1_sda11" )
				)
				( pin "U9F4.D4"
					( objectStatus "gpioc4_sd1dat2_scl12" )
				)
				( pin "U9F4.C3"
					( objectStatus "gpioc5_sd1dat3_sda12" )
				)
				( pin "U9F4.B2"
					( objectStatus "gpioc6_sd1cd_n_scl13" )
				)
				( pin "U9F4.A1"
					( objectStatus "gpioc7_sd1wp_n_sda13" )
				)
				( pin "U9F4.A18"
					( objectStatus "gpiod0_sd2clk" )
				)
				( pin "U9F4.D16"
					( objectStatus "gpiod1_sd2cmd" )
				)
				( pin "U9F4.B17"
					( objectStatus "gpiod2_sd2dat0" )
				)
				( pin "U9F4.A17"
					( objectStatus "gpiod3_sd2dat1" )
				)
				( pin "U9F4.C16"
					( objectStatus "gpiod4_sd2dat2" )
				)
				( pin "U9F4.B16"
					( objectStatus "gpiod5_sd2dat3" )
				)
				( pin "U9F4.A16"
					( objectStatus "gpiod6_sd2cd_n" )
				)
				( pin "U9F4.E15"
					( objectStatus "gpiod7_sd2wp_n" )
				)
				( pin "U9F4.D15"
					( objectStatus "gpioe0_ncts3" )
				)
				( pin "U9F4.C15"
					( objectStatus "gpioe1_ndcd3" )
				)
				( pin "U9F4.B15"
					( objectStatus "gpioe2_ndsr3" )
				)
				( pin "U9F4.A15"
					( objectStatus "gpioe3_nri3" )
				)
				( pin "U9F4.E14"
					( objectStatus "gpioe4_ndtr3" )
				)
				( pin "U9F4.D14"
					( objectStatus "gpioe5_nrts3" )
				)
				( pin "U9F4.C14"
					( objectStatus "gpioe6_txd3" )
				)
				( pin "U9F4.B14"
					( objectStatus "gpioe7_rxd3" )
				)
				( pin "U9F4.D18"
					( objectStatus "gpiof0_ncts4" )
				)
				( pin "U9F4.B19"
					( objectStatus "gpiof1_ndcd4_siopbi_n" )
				)
				( pin "U9F4.A20"
					( objectStatus "gpiof2_ndsr4_siopwrgd" )
				)
				( pin "U9F4.D17"
					( objectStatus "gpiof3_nri4_siopbo_n" )
				)
				( pin "U9F4.B18"
					( objectStatus "gpiof4_ndtr4" )
				)
				( pin "U9F4.A19"
					( objectStatus "gpiof5_nrts4_siosci_n" )
				)
				( pin "U9F4.E16"
					( objectStatus "gpiof6_txd4" )
				)
				( pin "U9F4.C17"
					( objectStatus "gpiof7_rxd4" )
				)
				( pin "U9F4.B13"
					( objectStatus "gpiog4_wdtrst1_oscclk" )
				)
				( pin "U9F4.Y21"
					( objectStatus "gpiog5_wdtrst2_usbcki" )
				)
				( pin "U9F4.U1"
					( objectStatus "gpiol0_ncts1" )
				)
				( pin "U9F4.T5"
					( objectStatus "gpiol1_ndcd1_vpide" )
				)
				( pin "U9F4.U3"
					( objectStatus "gpiol2_ndsr1_vpiodd" )
				)
				( pin "U9F4.V1"
					( objectStatus "gpiol3_nri1_vpihs" )
				)
				( pin "U9F4.U4"
					( objectStatus "gpiol4_ndtr1_vpivs" )
				)
				( pin "U9F4.V2"
					( objectStatus "gpiol5_nrts1_vpiclk" )
				)
				( pin "U9F4.W1"
					( objectStatus "gpiol6_txd1_vpib0" )
				)
				( pin "U9F4.U5"
					( objectStatus "gpiol7_rxd1_vpib1" )
				)
				( pin "U9F4.V3"
					( objectStatus "gpiom0_ncts2_vpib2" )
				)
				( pin "U9F4.W2"
					( objectStatus "gpiom1_ndcd2_vpib3" )
				)
				( pin "U9F4.Y1"
					( objectStatus "gpiom2_ndsr2_vpib4" )
				)
				( pin "U9F4.V4"
					( objectStatus "gpiom3_nri2_vpib5" )
				)
				( pin "U9F4.W3"
					( objectStatus "gpiom4_ndtr2_vpib6" )
				)
				( pin "U9F4.Y2"
					( objectStatus "gpiom5_nrts2_vpib7" )
				)
				( pin "U9F4.AA1"
					( objectStatus "gpiom6_txd2_vpib8" )
				)
				( pin "U9F4.V5"
					( objectStatus "gpiom7_rxd2_vpib9" )
				)
				( pin "U9F4.H2"
					( objectStatus "gpioq(6)" )
				)
				( pin "U9F4.H1"
					( objectStatus "gpioq(7)" )
				)
				( pin "U9F4.H4"
					( objectStatus "gpioq4_scl14" )
				)
				( pin "U9F4.H3"
					( objectStatus "gpioq5_sda14" )
				)
				( pin "U9F4.K20"
					( objectStatus "gpioy3_sioonctrl_n" )
				)
				( pin "U9F4.G21"
					( objectStatus "nc_perefclkn" )
				)
				( pin "U9F4.G22"
					( objectStatus "nc_perefclkp" )
				)
				( pin "U9F4.D20"
					( objectStatus "nc_perext" )
				)
				( pin "U9F4.F22"
					( objectStatus "nc_perxn" )
				)
				( pin "U9F4.F21"
					( objectStatus "nc_perxp" )
				)
				( pin "U9F4.E21"
					( objectStatus "nc_petxn" )
				)
				( pin "U9F4.E22"
					( objectStatus "nc_petxp" )
				)
				( pin "U9F4.J22"
					( objectStatus "nc_pewake_n" )
				)
				( pin "U9F4.AA21"
					( objectStatus "peci" )
				)
				( pin "U9F4.K19"
					( objectStatus "perst_n" )
				)
				( pin "U9F4.G1"
					( objectStatus "rxd5" )
				)
				( pin "U9F4.W20"
					( objectStatus "srst_n" )
				)
				( pin "U9F4.H5"
					( objectStatus "txd5" )
				)
			)
			( gate "R1U7"
				( objectStatus "@baseboard_fab2_lib.baseboard_fab2(sch_1):page145_i127" )
				( pin "R1U7.1"
					( objectStatus "a" )
				)
				( pin "R1U7.2"
					( objectStatus "b" )
				)
			)
			( gate "R9F33"
				( objectStatus "@baseboard_fab2_lib.baseboard_fab2(sch_1):page145_i132" )
				( pin "R9F33.1"
					( objectStatus "a" )
				)
				( pin "R9F33.2"
					( objectStatus "b" )
				)
			)
			( gate "R9F20"
				( objectStatus "@baseboard_fab2_lib.baseboard_fab2(sch_1):page145_i133" )
				( pin "R9F20.1"
					( objectStatus "a" )
				)
				( pin "R9F20.2"
					( objectStatus "b" )
				)
			)
			( gate "R1T15"
				( objectStatus "@baseboard_fab2_lib.baseboard_fab2(sch_1):page145_i183" )
				( pin "R1T15.1"
					( objectStatus "a" )
				)
				( pin "R1T15.2"
					( objectStatus "b" )
				)
			)
			( gate "R1T23"
				( objectStatus "@baseboard_fab2_lib.baseboard_fab2(sch_1):page145_i184" )
				( pin "R1T23.1"
					( objectStatus "a" )
				)
				( pin "R1T23.2"
					( objectStatus "b" )
				)
			)
			( gate "R9G10"
				( objectStatus "@baseboard_fab2_lib.baseboard_fab2(sch_1):page145_i187" )
				( pin "R9G10.1"
					( objectStatus "a" )
				)
				( pin "R9G10.2"
					( objectStatus "b" )
				)
			)
			( gate "R9G16"
				( objectStatus "@baseboard_fab2_lib.baseboard_fab2(sch_1):page145_i188" )
				( pin "R9G16.1"
					( objectStatus "a" )
				)
				( pin "R9G16.2"
					( objectStatus "b" )
				)
			)
			( gate "C9F17"
				( objectStatus "@baseboard_fab2_lib.baseboard_fab2(sch_1):page145_i201" )
				( pin "C9F17.1"
					( objectStatus "a" )
				)
				( pin "C9F17.2"
					( objectStatus "b" )
				)
			)
			( gate "C9F16"
				( objectStatus "@baseboard_fab2_lib.baseboard_fab2(sch_1):page145_i202" )
				( pin "C9F16.1"
					( objectStatus "a" )
				)
				( pin "C9F16.2"
					( objectStatus "b" )
				)
			)
			( gate "R2T41"
				( objectStatus "@baseboard_fab2_lib.baseboard_fab2(sch_1):page145_i203" )
				( pin "R2T41.1"
					( objectStatus "a" )
				)
				( pin "R2T41.2"
					( objectStatus "b" )
				)
			)
			( gate "R2T12"
				( objectStatus "@baseboard_fab2_lib.baseboard_fab2(sch_1):page145_i205" )
				( pin "R2T12.1"
					( objectStatus "a" )
				)
				( pin "R2T12.2"
					( objectStatus "b" )
				)
			)
			( gate "R9F4"
				( objectStatus "@baseboard_fab2_lib.baseboard_fab2(sch_1):page145_i208" )
				( pin "R9F4.1"
					( objectStatus "a" )
				)
				( pin "R9F4.2"
					( objectStatus "b" )
				)
			)
			( gate "R9F45"
				( objectStatus "@baseboard_fab2_lib.baseboard_fab2(sch_1):page145_i210" )
				( pin "R9F45.1"
					( objectStatus "a" )
				)
				( pin "R9F45.2"
					( objectStatus "b" )
				)
			)
			( gate "R9F44"
				( objectStatus "@baseboard_fab2_lib.baseboard_fab2(sch_1):page145_i211" )
				( pin "R9F44.1"
					( objectStatus "a" )
				)
				( pin "R9F44.2"
					( objectStatus "b" )
				)
			)
			( gate "R9F42"
				( objectStatus "@baseboard_fab2_lib.baseboard_fab2(sch_1):page145_i214" )
				( pin "R9F42.1"
					( objectStatus "a" )
				)
				( pin "R9F42.2"
					( objectStatus "b" )
				)
			)
			( gate "R9F43"
				( objectStatus "@baseboard_fab2_lib.baseboard_fab2(sch_1):page145_i216" )
				( pin "R9F43.1"
					( objectStatus "a" )
				)
				( pin "R9F43.2"
					( objectStatus "b" )
				)
			)
			( gate "R9F46"
				( objectStatus "@baseboard_fab2_lib.baseboard_fab2(sch_1):page145_i218" )
				( pin "R9F46.1"
					( objectStatus "a" )
				)
				( pin "R9F46.2"
					( objectStatus "b" )
				)
			)
			( gate "Y1"
				( objectStatus "@baseboard_fab2_lib.baseboard_fab2(sch_1):page145_i250" )
				( pin "Y1.1"
					( objectStatus "enable_control" )
				)
				( pin "Y1.2"
					( objectStatus "gnd" )
				)
				( pin "Y1.3"
					( objectStatus "\out\" )
				)
				( pin "Y1.4"
					( objectStatus "vdd" )
				)
			)
			( gate "R136"
				( objectStatus "@baseboard_fab2_lib.baseboard_fab2(sch_1):page145_i252" )
				( pin "R136.1"
					( objectStatus "a" )
				)
				( pin "R136.2"
					( objectStatus "b" )
				)
			)
			( gate "R138"
				( objectStatus "@baseboard_fab2_lib.baseboard_fab2(sch_1):page145_i256" )
				( pin "R138.1"
					( objectStatus "a" )
				)
				( pin "R138.2"
					( objectStatus "b" )
				)
			)
			( gate "R137"
				( objectStatus "@baseboard_fab2_lib.baseboard_fab2(sch_1):page145_i257" )
				( pin "R137.1"
					( objectStatus "a" )
				)
				( pin "R137.2"
					( objectStatus "b" )
				)
			)
			( gate "C39"
				( objectStatus "@baseboard_fab2_lib.baseboard_fab2(sch_1):page145_i258" )
				( pin "C39.1"
					( objectStatus "a" )
				)
				( pin "C39.2"
					( objectStatus "b" )
				)
			)
			( gate "U9F4"
				( objectStatus "@baseboard_fab2_lib.baseboard_fab2(sch_1):page146_i1" )
				( pin "U9F4.AA22"
					( objectStatus "gpiog6_flbusy_n" )
				)
				( pin "U9F4.U18"
					( objectStatus "gpiog7_flwp_n" )
				)
				( pin "U9F4.A8"
					( objectStatus "gpioh0_romd8_ncts6" )
				)
				( pin "U9F4.C7"
					( objectStatus "gpioh1_romd9_ndcd6" )
				)
				( pin "U9F4.B7"
					( objectStatus "gpioh2_romd10_ndsr6" )
				)
				( pin "U9F4.A7"
					( objectStatus "gpioh3_romd11_nri6" )
				)
				( pin "U9F4.D7"
					( objectStatus "gpioh4_romd12_ndtr6" )
				)
				( pin "U9F4.B6"
					( objectStatus "gpioh5_romd13_nrts6" )
				)
				( pin "U9F4.A6"
					( objectStatus "gpioh6_romd14_txd6" )
				)
				( pin "U9F4.E7"
					( objectStatus "gpioh7_romd15_rxd6" )
				)
				( pin "U9F4.V20"
					( objectStatus "gpior0_romcs1_n" )
				)
				( pin "U9F4.W21"
					( objectStatus "gpior1_romcs2_n" )
				)
				( pin "U9F4.Y22"
					( objectStatus "gpior2_romcs3_n" )
				)
				( pin "U9F4.U19"
					( objectStatus "gpior3_romcs4_n" )
				)
				( pin "U9F4.V21"
					( objectStatus "gpior4_roma24_vpor6" )
				)
				( pin "U9F4.W22"
					( objectStatus "gpior5_roma25_vpor7" )
				)
				( pin "U9F4.C6"
					( objectStatus "gpior6_mdc1" )
				)
				( pin "U9F4.A5"
					( objectStatus "gpior7_mdio1" )
				)
				( pin "U9F4.R20"
					( objectStatus "roma(0)" )
				)
				( pin "U9F4.R21"
					( objectStatus "roma(1)" )
				)
				( pin "U9F4.R22"
					( objectStatus "roma2_gpioz0_vpob0" )
				)
				( pin "U9F4.P18"
					( objectStatus "roma3_gpioz1_vpob1" )
				)
				( pin "U9F4.P19"
					( objectStatus "roma4_gpioz2_vpob2" )
				)
				( pin "U9F4.P20"
					( objectStatus "roma5_gpioz3_vpob3" )
				)
				( pin "U9F4.P21"
					( objectStatus "roma6_gpioz4_vpob4" )
				)
				( pin "U9F4.P22"
					( objectStatus "roma7_gpioz5_vpob5" )
				)
				( pin "U9F4.M19"
					( objectStatus "roma8_gpioz6_vpob6" )
				)
				( pin "U9F4.M20"
					( objectStatus "roma9_gpioz7_vpob7" )
				)
				( pin "U9F4.M21"
					( objectStatus "roma10_gpioaa0_vpog0" )
				)
				( pin "U9F4.M22"
					( objectStatus "roma11_gpioaa1_vpog1" )
				)
				( pin "U9F4.L18"
					( objectStatus "roma12_gpioaa2_vpog2" )
				)
				( pin "U9F4.L19"
					( objectStatus "roma13_gpioaa3_vpog3" )
				)
				( pin "U9F4.L20"
					( objectStatus "roma14_gpioaa4_vpog4" )
				)
				( pin "U9F4.L21"
					( objectStatus "roma15_gpioaa5_vpog5" )
				)
				( pin "U9F4.T18"
					( objectStatus "roma16_gpioaa6_vpog6" )
				)
				( pin "U9F4.N18"
					( objectStatus "roma17_gpioaa7_vpog7" )
				)
				( pin "U9F4.N19"
					( objectStatus "roma18_gpioab0_vpor0" )
				)
				( pin "U9F4.M18"
					( objectStatus "roma19_gpioab1_vpor1" )
				)
				( pin "U9F4.N22"
					( objectStatus "roma20_gpioab2_vpor2" )
				)
				( pin "U9F4.N20"
					( objectStatus "roma21_gpioab3_vpor3" )
				)
				( pin "U9F4.L22"
					( objectStatus "roma22_gpios6_vpor4" )
				)
				( pin "U9F4.K18"
					( objectStatus "roma23_gpios7_vpor5" )
				)
				( pin "U9F4.R19"
					( objectStatus "romcs0_n" )
				)
				( pin "U9F4.T22"
					( objectStatus "romd0" )
				)
				( pin "U9F4.T21"
					( objectStatus "romd1" )
				)
				( pin "U9F4.T20"
					( objectStatus "romd2" )
				)
				( pin "U9F4.U22"
					( objectStatus "romd3" )
				)
				( pin "U9F4.U21"
					( objectStatus "romd4_gpios0_vpode" )
				)
				( pin "U9F4.T19"
					( objectStatus "romd5_gpios1_vpohs" )
				)
				( pin "U9F4.V22"
					( objectStatus "romd6_gpios2_vpovs" )
				)
				( pin "U9F4.U20"
					( objectStatus "romd7_gpios3_vpoclk" )
				)
				( pin "U9F4.R18"
					( objectStatus "romoe_n_gpios4" )
				)
				( pin "U9F4.N21"
					( objectStatus "romwe_n_gpios5" )
				)
			)
			( gate "R1T26"
				( objectStatus "@baseboard_fab2_lib.baseboard_fab2(sch_1):page146_i35" )
				( pin "R1T26.1"
					( objectStatus "a" )
				)
				( pin "R1T26.2"
					( objectStatus "b" )
				)
			)
			( gate "R9F41"
				( objectStatus "@baseboard_fab2_lib.baseboard_fab2(sch_1):page146_i108" )
				( pin "R9F41.1"
					( objectStatus "a" )
				)
				( pin "R9F41.2"
					( objectStatus "b" )
				)
			)
			( gate "R9F21"
				( objectStatus "@baseboard_fab2_lib.baseboard_fab2(sch_1):page146_i109" )
				( pin "R9F21.1"
					( objectStatus "a" )
				)
				( pin "R9F21.2"
					( objectStatus "b" )
				)
			)
			( gate "R1T24"
				( objectStatus "@baseboard_fab2_lib.baseboard_fab2(sch_1):page146_i127" )
				( pin "R1T24.1"
					( objectStatus "a" )
				)
				( pin "R1T24.2"
					( objectStatus "b" )
				)
			)
			( gate "U9F4"
				( objectStatus "@baseboard_fab2_lib.baseboard_fab2(sch_1):page147_i1" )
				( pin "U9F4.L5"
					( objectStatus "adc0_gpiw0" )
				)
				( pin "U9F4.L4"
					( objectStatus "adc1_gpiw1" )
				)
				( pin "U9F4.L3"
					( objectStatus "adc2_gpiw2" )
				)
				( pin "U9F4.L2"
					( objectStatus "adc3_gpiw3" )
				)
				( pin "U9F4.L1"
					( objectStatus "adc4_gpiw4" )
				)
				( pin "U9F4.M5"
					( objectStatus "adc5_gpiw5" )
				)
				( pin "U9F4.M4"
					( objectStatus "adc6_gpiw6" )
				)
				( pin "U9F4.M3"
					( objectStatus "adc7_gpiw7" )
				)
				( pin "U9F4.M2"
					( objectStatus "adc8_gpix0" )
				)
				( pin "U9F4.M1"
					( objectStatus "adc9_gpix1" )
				)
				( pin "U9F4.N5"
					( objectStatus "adc10_gpix2" )
				)
				( pin "U9F4.N4"
					( objectStatus "adc11_gpix3" )
				)
				( pin "U9F4.N3"
					( objectStatus "adc12_gpix4" )
				)
				( pin "U9F4.N2"
					( objectStatus "adc13_gpix5" )
				)
				( pin "U9F4.N1"
					( objectStatus "adc14_gpix6" )
				)
				( pin "U9F4.P5"
					( objectStatus "adc15_gpix7" )
				)
				( pin "U9F4.P2"
					( objectStatus "adcrext" )
				)
				( pin "U9F4.K2"
					( objectStatus "adcvrefn" )
				)
				( pin "U9F4.K1"
					( objectStatus "adcvrefp" )
				)
				( pin "U9F4.A3"
					( objectStatus "gpioa6_timer7_mdc2" )
				)
				( pin "U9F4.D5"
					( objectStatus "gpioa7_timer8_mdio2" )
				)
				( pin "U9F4.W4"
					( objectStatus "gpion0_pwm0_vpig0" )
				)
				( pin "U9F4.Y3"
					( objectStatus "gpion1_pwm1_vpig1" )
				)
				( pin "U9F4.AA2"
					( objectStatus "gpion2_pwm2_vpig2" )
				)
				( pin "U9F4.AB1"
					( objectStatus "gpion3_pwm3_vpig3" )
				)
				( pin "U9F4.W5"
					( objectStatus "gpion4_pwm4_vpig4" )
				)
				( pin "U9F4.Y4"
					( objectStatus "gpion5_pwm5_vpig5" )
				)
				( pin "U9F4.AA3"
					( objectStatus "gpion6_pwm6_vpig6" )
				)
				( pin "U9F4.AB2"
					( objectStatus "gpion7_pwm7_vpig7" )
				)
				( pin "U9F4.V6"
					( objectStatus "gpioo0_tach0_vpig8" )
				)
				( pin "U9F4.Y5"
					( objectStatus "gpioo1_tach1_vpig9" )
				)
				( pin "U9F4.AA4"
					( objectStatus "gpioo2_tach2_vpir0" )
				)
				( pin "U9F4.AB3"
					( objectStatus "gpioo3_tach3_vpir1" )
				)
				( pin "U9F4.W6"
					( objectStatus "gpioo4_tach4_vpir2" )
				)
				( pin "U9F4.AA5"
					( objectStatus "gpioo5_tach5_vpir3" )
				)
				( pin "U9F4.AB4"
					( objectStatus "gpioo6_tach6_vpir4" )
				)
				( pin "U9F4.V7"
					( objectStatus "gpioo7_tach7_vpir5" )
				)
				( pin "U9F4.Y6"
					( objectStatus "gpiop0_tach8_vpir6" )
				)
				( pin "U9F4.AB5"
					( objectStatus "gpiop1_tach9_vpir7" )
				)
				( pin "U9F4.W7"
					( objectStatus "gpiop2_tach10_vpir8" )
				)
				( pin "U9F4.AA6"
					( objectStatus "gpiop3_tach11_vpir9" )
				)
				( pin "U9F4.AB6"
					( objectStatus "gpiop4_tach12" )
				)
				( pin "U9F4.Y7"
					( objectStatus "gpiop5_tach13" )
				)
				( pin "U9F4.AA7"
					( objectStatus "gpiop6_tach14_bmcint" )
				)
				( pin "U9F4.AB7"
					( objectStatus "gpiop7_tach15_flack" )
				)
				( pin "U9F4.E11"
					( objectStatus "rgmii1rxck_rmii1rclk_gpiou4" )
				)
				( pin "U9F4.D11"
					( objectStatus "rgmii1rxctl_gpiou5" )
				)
				( pin "U9F4.C11"
					( objectStatus "rgmii1rxd0_rmii1rxd0_gpiou6" )
				)
				( pin "U9F4.B11"
					( objectStatus "rgmii1rxd1_rmii1rxd1_gpiou7" )
				)
				( pin "U9F4.A11"
					( objectStatus "rgmii1rxd2_rmii1crsdv_gpiov0" )
				)
				( pin "U9F4.E10"
					( objectStatus "rgmii1rxd3_rmii1rxer_gpiov1" )
				)
				( pin "U9F4.A12"
					( objectStatus "rgmii1txck_rmii1txen_gpiot0" )
				)
				( pin "U9F4.B12"
					( objectStatus "rgmii1txctl_gpiot1" )
				)
				( pin "U9F4.C12"
					( objectStatus "rgmii1txd0_rmii1txd0_gpiot2" )
				)
				( pin "U9F4.D12"
					( objectStatus "rgmii1txd1_rmii1txd1_gpiot3" )
				)
				( pin "U9F4.E12"
					( objectStatus "rgmii1txd2_gpiot4" )
				)
				( pin "U9F4.A13"
					( objectStatus "rgmii1txd3_gpiot5" )
				)
				( pin "U9F4.C9"
					( objectStatus "rgmii2rxck_rmii2rclk_gpiov2" )
				)
				( pin "U9F4.B9"
					( objectStatus "rgmii2rxctl_gpiov3" )
				)
				( pin "U9F4.A9"
					( objectStatus "rgmii2rxd0_rmii2rxd0_gpiov4" )
				)
				( pin "U9F4.E8"
					( objectStatus "rgmii2rxd1_rmii2rxd1_gpiov5" )
				)
				( pin "U9F4.D8"
					( objectStatus "rgmii2rxd2_rmii2crsdv_gpiov6" )
				)
				( pin "U9F4.C8"
					( objectStatus "rgmii2rxd3_rmii2rxer_gpiov7" )
				)
				( pin "U9F4.D9"
					( objectStatus "rgmii2txck_rmii2txen_gpiot6" )
				)
				( pin "U9F4.E9"
					( objectStatus "rgmii2txctl_gpiot7" )
				)
				( pin "U9F4.A10"
					( objectStatus "rgmii2txd0_rmii2txd0_gpiou0" )
				)
				( pin "U9F4.B10"
					( objectStatus "rgmii2txd1_rmii2txd1_gpiou1" )
				)
				( pin "U9F4.C10"
					( objectStatus "rgmii2txd2_gpiou2" )
				)
				( pin "U9F4.D10"
					( objectStatus "rgmii2txd3_gpiou3" )
				)
				( pin "U9F4.B8"
					( objectStatus "rgmiick" )
				)
			)
			( gate "Q9E1"
				( objectStatus "@baseboard_fab2_lib.baseboard_fab2(sch_1):page147_i55" )
				( pin "Q9E1.3"
					( objectStatus "drain(0)" )
				)
				( pin "Q9E1.5"
					( objectStatus "gate(0)" )
				)
				( pin "Q9E1.4"
					( objectStatus "source(0)" )
				)
			)
			( gate "DS9E1"
				( objectStatus "@baseboard_fab2_lib.baseboard_fab2(sch_1):page147_i56" )
				( pin "DS9E1.1"
					( objectStatus "a" )
				)
				( pin "DS9E1.2"
					( objectStatus "c" )
				)
			)
			( gate "R9F2"
				( objectStatus "@baseboard_fab2_lib.baseboard_fab2(sch_1):page147_i57" )
				( pin "R9F2.1"
					( objectStatus "a" )
				)
				( pin "R9F2.2"
					( objectStatus "b" )
				)
			)
			( gate "C9G8"
				( objectStatus "@baseboard_fab2_lib.baseboard_fab2(sch_1):page147_i75" )
				( pin "C9G8.1"
					( objectStatus "a" )
				)
				( pin "C9G8.2"
					( objectStatus "b" )
				)
			)
			( gate "C9G11"
				( objectStatus "@baseboard_fab2_lib.baseboard_fab2(sch_1):page147_i76" )
				( pin "C9G11.1"
					( objectStatus "a" )
				)
				( pin "C9G11.2"
					( objectStatus "b" )
				)
			)
			( gate "R9G7"
				( objectStatus "@baseboard_fab2_lib.baseboard_fab2(sch_1):page147_i78" )
				( pin "R9G7.1"
					( objectStatus "a" )
				)
				( pin "R9G7.2"
					( objectStatus "b" )
				)
			)
			( gate "C9G10"
				( objectStatus "@baseboard_fab2_lib.baseboard_fab2(sch_1):page147_i79" )
				( pin "C9G10.1"
					( objectStatus "a" )
				)
				( pin "C9G10.2"
					( objectStatus "b" )
				)
			)
			( gate "R1R10"
				( objectStatus "@baseboard_fab2_lib.baseboard_fab2(sch_1):page147_i108" )
				( pin "R1R10.1"
					( objectStatus "a" )
				)
				( pin "R1R10.2"
					( objectStatus "b" )
				)
			)
			( gate "R1R13"
				( objectStatus "@baseboard_fab2_lib.baseboard_fab2(sch_1):page147_i109" )
				( pin "R1R13.1"
					( objectStatus "a" )
				)
				( pin "R1R13.2"
					( objectStatus "b" )
				)
			)
			( gate "R2T45"
				( objectStatus "@baseboard_fab2_lib.baseboard_fab2(sch_1):page147_i115" )
				( pin "R2T45.1"
					( objectStatus "a" )
				)
				( pin "R2T45.2"
					( objectStatus "b" )
				)
			)
			( gate "R8F33"
				( objectStatus "@baseboard_fab2_lib.baseboard_fab2(sch_1):page147_i116" )
				( pin "R8F33.1"
					( objectStatus "a" )
				)
				( pin "R8F33.2"
					( objectStatus "b" )
				)
			)
			( gate "R8F32"
				( objectStatus "@baseboard_fab2_lib.baseboard_fab2(sch_1):page147_i118" )
				( pin "R8F32.1"
					( objectStatus "a" )
				)
				( pin "R8F32.2"
					( objectStatus "b" )
				)
			)
			( gate "R1R4"
				( objectStatus "@baseboard_fab2_lib.baseboard_fab2(sch_1):page147_i119" )
				( pin "R1R4.1"
					( objectStatus "a" )
				)
				( pin "R1R4.2"
					( objectStatus "b" )
				)
			)
			( gate "R1T28"
				( objectStatus "@baseboard_fab2_lib.baseboard_fab2(sch_1):page147_i121" )
				( pin "R1T28.1"
					( objectStatus "a" )
				)
				( pin "R1T28.2"
					( objectStatus "b" )
				)
			)
			( gate "R8F28"
				( objectStatus "@baseboard_fab2_lib.baseboard_fab2(sch_1):page147_i125" )
				( pin "R8F28.1"
					( objectStatus "a" )
				)
				( pin "R8F28.2"
					( objectStatus "b" )
				)
			)
			( gate "R8F31"
				( objectStatus "@baseboard_fab2_lib.baseboard_fab2(sch_1):page147_i126" )
				( pin "R8F31.1"
					( objectStatus "a" )
				)
				( pin "R8F31.2"
					( objectStatus "b" )
				)
			)
			( gate "Q9E1"
				( objectStatus "@baseboard_fab2_lib.baseboard_fab2(sch_1):page147_i135" )
				( pin "Q9E1.6"
					( objectStatus "drain(0)" )
				)
				( pin "Q9E1.2"
					( objectStatus "gate(0)" )
				)
				( pin "Q9E1.1"
					( objectStatus "source(0)" )
				)
			)
			( gate "R9E21"
				( objectStatus "@baseboard_fab2_lib.baseboard_fab2(sch_1):page147_i137" )
				( pin "R9E21.1"
					( objectStatus "a" )
				)
				( pin "R9E21.2"
					( objectStatus "b" )
				)
			)
			( gate "R8B25"
				( objectStatus "@baseboard_fab2_lib.baseboard_fab2(sch_1):page147_i140" )
				( pin "R8B25.1"
					( objectStatus "a" )
				)
				( pin "R8B25.2"
					( objectStatus "b" )
				)
			)
			( gate "R2N13"
				( objectStatus "@baseboard_fab2_lib.baseboard_fab2(sch_1):page147_i142" )
				( pin "R2N13.1"
					( objectStatus "a" )
				)
				( pin "R2N13.2"
					( objectStatus "b" )
				)
			)
			( gate "R1U1"
				( objectStatus "@baseboard_fab2_lib.baseboard_fab2(sch_1):page147_i144" )
				( pin "R1U1.1"
					( objectStatus "a" )
				)
				( pin "R1U1.2"
					( objectStatus "b" )
				)
			)
			( gate "R1U2"
				( objectStatus "@baseboard_fab2_lib.baseboard_fab2(sch_1):page147_i145" )
				( pin "R1U2.1"
					( objectStatus "a" )
				)
				( pin "R1U2.2"
					( objectStatus "b" )
				)
			)
			( gate "R1U5"
				( objectStatus "@baseboard_fab2_lib.baseboard_fab2(sch_1):page147_i148" )
				( pin "R1U5.1"
					( objectStatus "a" )
				)
				( pin "R1U5.2"
					( objectStatus "b" )
				)
			)
			( gate "R1U4"
				( objectStatus "@baseboard_fab2_lib.baseboard_fab2(sch_1):page147_i149" )
				( pin "R1U4.1"
					( objectStatus "a" )
				)
				( pin "R1U4.2"
					( objectStatus "b" )
				)
			)
			( gate "R8F30"
				( objectStatus "@baseboard_fab2_lib.baseboard_fab2(sch_1):page147_i154" )
				( pin "R8F30.1"
					( objectStatus "a" )
				)
				( pin "R8F30.2"
					( objectStatus "b" )
				)
			)
			( gate "U9F4"
				( objectStatus "@baseboard_fab2_lib.baseboard_fab2(sch_1):page148_i11" )
				( pin "U9F4.P3"
					( objectStatus "adcav33" )
				)
				( pin "U9F4.P4"
					( objectStatus "adcavss" )
				)
				( pin "U9F4.P1"
					( objectStatus "dacav33" )
				)
				( pin "U9F4.R5"
					( objectStatus "dacavss" )
				)
				( pin "U9F4.T3"
					( objectStatus "dacdv33" )
				)
				( pin "U9F4.J10"
					( objectStatus "gnd(0)" )
				)
				( pin "U9F4.J11"
					( objectStatus "gnd(1)" )
				)
				( pin "U9F4.J12"
					( objectStatus "gnd(2)" )
				)
				( pin "U9F4.J13"
					( objectStatus "gnd(3)" )
				)
				( pin "U9F4.J14"
					( objectStatus "gnd(4)" )
				)
				( pin "U9F4.J9"
					( objectStatus "gnd(5)" )
				)
				( pin "U9F4.K10"
					( objectStatus "gnd(6)" )
				)
				( pin "U9F4.K11"
					( objectStatus "gnd(7)" )
				)
				( pin "U9F4.K12"
					( objectStatus "gnd(8)" )
				)
				( pin "U9F4.K13"
					( objectStatus "gnd(9)" )
				)
				( pin "U9F4.K14"
					( objectStatus "gnd(10)" )
				)
				( pin "U9F4.K9"
					( objectStatus "gnd(11)" )
				)
				( pin "U9F4.L10"
					( objectStatus "gnd(12)" )
				)
				( pin "U9F4.L11"
					( objectStatus "gnd(13)" )
				)
				( pin "U9F4.L12"
					( objectStatus "gnd(14)" )
				)
				( pin "U9F4.L13"
					( objectStatus "gnd(15)" )
				)
				( pin "U9F4.L14"
					( objectStatus "gnd(16)" )
				)
				( pin "U9F4.L9"
					( objectStatus "gnd(17)" )
				)
				( pin "U9F4.M10"
					( objectStatus "gnd(18)" )
				)
				( pin "U9F4.M11"
					( objectStatus "gnd(19)" )
				)
				( pin "U9F4.M12"
					( objectStatus "gnd(20)" )
				)
				( pin "U9F4.M13"
					( objectStatus "gnd(21)" )
				)
				( pin "U9F4.M14"
					( objectStatus "gnd(22)" )
				)
				( pin "U9F4.M9"
					( objectStatus "gnd(23)" )
				)
				( pin "U9F4.N10"
					( objectStatus "gnd(24)" )
				)
				( pin "U9F4.N11"
					( objectStatus "gnd(25)" )
				)
				( pin "U9F4.N12"
					( objectStatus "gnd(26)" )
				)
				( pin "U9F4.N13"
					( objectStatus "gnd(27)" )
				)
				( pin "U9F4.N14"
					( objectStatus "gnd(28)" )
				)
				( pin "U9F4.N9"
					( objectStatus "gnd(29)" )
				)
				( pin "U9F4.P10"
					( objectStatus "gnd(30)" )
				)
				( pin "U9F4.P11"
					( objectStatus "gnd(31)" )
				)
				( pin "U9F4.P12"
					( objectStatus "gnd(32)" )
				)
				( pin "U9F4.P13"
					( objectStatus "gnd(33)" )
				)
				( pin "U9F4.P14"
					( objectStatus "gnd(34)" )
				)
				( pin "U9F4.P9"
					( objectStatus "gnd(35)" )
				)
				( pin "U9F4.C21"
					( objectStatus "gpioy0_sios3_n" )
				)
				( pin "U9F4.F20"
					( objectStatus "gpioy1_sios5_n" )
				)
				( pin "U9F4.G20"
					( objectStatus "gpioy2_siopwreq_n" )
				)
				( pin "U9F4.V17"
					( objectStatus "hpllav33" )
				)
				( pin "U9F4.F14"
					( objectStatus "iv12d(0)" )
				)
				( pin "U9F4.F15"
					( objectStatus "iv12d(1)" )
				)
				( pin "U9F4.K6"
					( objectStatus "iv12d(2)" )
				)
				( pin "U9F4.L6"
					( objectStatus "iv12d(3)" )
				)
				( pin "U9F4.L17"
					( objectStatus "iv12d(4)" )
				)
				( pin "U9F4.P6"
					( objectStatus "iv12d(5)" )
				)
				( pin "U9F4.P17"
					( objectStatus "iv12d(6)" )
				)
				( pin "U9F4.R6"
					( objectStatus "iv12d(7)" )
				)
				( pin "U9F4.R17"
					( objectStatus "iv12d(8)" )
				)
				( pin "U9F4.U12"
					( objectStatus "iv12d(9)" )
				)
				( pin "U9F4.U13"
					( objectStatus "iv12d(10)" )
				)
				( pin "U9F4.AB19"
					( objectStatus "mpllav33" )
				)
				( pin "U9F4.Y18"
					( objectStatus "mplldv12" )
				)
				( pin "U9F4.U10"
					( objectStatus "mvdd(0)" )
				)
				( pin "U9F4.U11"
					( objectStatus "mvdd(1)" )
				)
				( pin "U9F4.U14"
					( objectStatus "mvdd(2)" )
				)
				( pin "U9F4.U15"
					( objectStatus "mvdd(3)" )
				)
				( pin "U9F4.H21"
					( objectStatus "nc(0)" )
				)
				( pin "U9F4.H22"
					( objectStatus "nc(1)" )
				)
				( pin "U9F4.D21"
					( objectStatus "peagnd(0)" )
				)
				( pin "U9F4.D22"
					( objectStatus "peagnd(1)" )
				)
				( pin "U9F4.K17"
					( objectStatus "peav12" )
				)
				( pin "U9F4.J17"
					( objectStatus "peav33" )
				)
				( pin "U9F4.V19"
					( objectStatus "pecivdd" )
				)
				( pin "U9F4.AA18"
					( objectStatus "pllvss(0)" )
				)
				( pin "U9F4.AA19"
					( objectStatus "pllvss(1)" )
				)
				( pin "U9F4.V18"
					( objectStatus "pllvss(2)" )
				)
				( pin "U9F4.F12"
					( objectStatus "pv33d(0)" )
				)
				( pin "U9F4.F13"
					( objectStatus "pv33d(1)" )
				)
				( pin "U9F4.H6"
					( objectStatus "pv33d(2)" )
				)
				( pin "U9F4.H17"
					( objectStatus "pv33d(3)" )
				)
				( pin "U9F4.J6"
					( objectStatus "pv33d(4)" )
				)
				( pin "U9F4.M6"
					( objectStatus "pv33d(5)" )
				)
				( pin "U9F4.M17"
					( objectStatus "pv33d(6)" )
				)
				( pin "U9F4.N6"
					( objectStatus "pv33d(7)" )
				)
				( pin "U9F4.N17"
					( objectStatus "pv33d(8)" )
				)
				( pin "U9F4.U8"
					( objectStatus "pv33d(9)" )
				)
				( pin "U9F4.U9"
					( objectStatus "pv33d(10)" )
				)
				( pin "U9F4.F10"
					( objectStatus "r1vdd(0)" )
				)
				( pin "U9F4.F11"
					( objectStatus "r1vdd(1)" )
				)
				( pin "U9F4.F8"
					( objectStatus "r2vdd(0)" )
				)
				( pin "U9F4.F9"
					( objectStatus "r2vdd(1)" )
				)
				( pin "U9F4.W18"
					( objectStatus "usb2av33" )
				)
				( pin "U9F4.Y19"
					( objectStatus "usb2avss" )
				)
				( pin "U9F4.W19"
					( objectStatus "v1pllav12" )
				)
				( pin "U9F4.Y20"
					( objectStatus "v2pllav12" )
				)
			)
			( gate "C1T44"
				( objectStatus "@baseboard_fab2_lib.baseboard_fab2(sch_1):page148_i25" )
				( pin "C1T44.1"
					( objectStatus "a" )
				)
				( pin "C1T44.2"
					( objectStatus "b" )
				)
			)
			( gate "C1U2"
				( objectStatus "@baseboard_fab2_lib.baseboard_fab2(sch_1):page148_i26" )
				( pin "C1U2.1"
					( objectStatus "a" )
				)
				( pin "C1U2.2"
					( objectStatus "b" )
				)
			)
			( gate "C1T21"
				( objectStatus "@baseboard_fab2_lib.baseboard_fab2(sch_1):page148_i28" )
				( pin "C1T21.1"
					( objectStatus "a" )
				)
				( pin "C1T21.2"
					( objectStatus "b" )
				)
			)
			( gate "C1T52"
				( objectStatus "@baseboard_fab2_lib.baseboard_fab2(sch_1):page149_i1" )
				( pin "C1T52.1"
					( objectStatus "a" )
				)
				( pin "C1T52.2"
					( objectStatus "b" )
				)
			)
			( gate "C1U3"
				( objectStatus "@baseboard_fab2_lib.baseboard_fab2(sch_1):page149_i4" )
				( pin "C1U3.1"
					( objectStatus "a" )
				)
				( pin "C1U3.2"
					( objectStatus "b" )
				)
			)
			( gate "C1T29"
				( objectStatus "@baseboard_fab2_lib.baseboard_fab2(sch_1):page149_i5" )
				( pin "C1T29.1"
					( objectStatus "a" )
				)
				( pin "C1T29.2"
					( objectStatus "b" )
				)
			)
			( gate "C1T30"
				( objectStatus "@baseboard_fab2_lib.baseboard_fab2(sch_1):page149_i6" )
				( pin "C1T30.1"
					( objectStatus "a" )
				)
				( pin "C1T30.2"
					( objectStatus "b" )
				)
			)
			( gate "C1T12"
				( objectStatus "@baseboard_fab2_lib.baseboard_fab2(sch_1):page149_i8" )
				( pin "C1T12.1"
					( objectStatus "a" )
				)
				( pin "C1T12.2"
					( objectStatus "b" )
				)
			)
			( gate "C1U5"
				( objectStatus "@baseboard_fab2_lib.baseboard_fab2(sch_1):page149_i17" )
				( pin "C1U5.1"
					( objectStatus "a" )
				)
				( pin "C1U5.2"
					( objectStatus "b" )
				)
			)
			( gate "C1U4"
				( objectStatus "@baseboard_fab2_lib.baseboard_fab2(sch_1):page149_i18" )
				( pin "C1U4.1"
					( objectStatus "a" )
				)
				( pin "C1U4.2"
					( objectStatus "b" )
				)
			)
			( gate "C1U8"
				( objectStatus "@baseboard_fab2_lib.baseboard_fab2(sch_1):page149_i19" )
				( pin "C1U8.1"
					( objectStatus "a" )
				)
				( pin "C1U8.2"
					( objectStatus "b" )
				)
			)
			( gate "C1T43"
				( objectStatus "@baseboard_fab2_lib.baseboard_fab2(sch_1):page149_i20" )
				( pin "C1T43.1"
					( objectStatus "a" )
				)
				( pin "C1T43.2"
					( objectStatus "b" )
				)
			)
			( gate "C1T45"
				( objectStatus "@baseboard_fab2_lib.baseboard_fab2(sch_1):page149_i21" )
				( pin "C1T45.1"
					( objectStatus "a" )
				)
				( pin "C1T45.2"
					( objectStatus "b" )
				)
			)
			( gate "C1T38"
				( objectStatus "@baseboard_fab2_lib.baseboard_fab2(sch_1):page149_i22" )
				( pin "C1T38.1"
					( objectStatus "a" )
				)
				( pin "C1T38.2"
					( objectStatus "b" )
				)
			)
			( gate "C1U9"
				( objectStatus "@baseboard_fab2_lib.baseboard_fab2(sch_1):page149_i23" )
				( pin "C1U9.1"
					( objectStatus "a" )
				)
				( pin "C1U9.2"
					( objectStatus "b" )
				)
			)
			( gate "C1T47"
				( objectStatus "@baseboard_fab2_lib.baseboard_fab2(sch_1):page149_i24" )
				( pin "C1T47.1"
					( objectStatus "a" )
				)
				( pin "C1T47.2"
					( objectStatus "b" )
				)
			)
			( gate "C1U11"
				( objectStatus "@baseboard_fab2_lib.baseboard_fab2(sch_1):page149_i25" )
				( pin "C1U11.1"
					( objectStatus "a" )
				)
				( pin "C1U11.2"
					( objectStatus "b" )
				)
			)
			( gate "C1T50"
				( objectStatus "@baseboard_fab2_lib.baseboard_fab2(sch_1):page149_i41" )
				( pin "C1T50.1"
					( objectStatus "a" )
				)
				( pin "C1T50.2"
					( objectStatus "b" )
				)
			)
			( gate "C1T25"
				( objectStatus "@baseboard_fab2_lib.baseboard_fab2(sch_1):page149_i42" )
				( pin "C1T25.1"
					( objectStatus "a" )
				)
				( pin "C1T25.2"
					( objectStatus "b" )
				)
			)
			( gate "C1T22"
				( objectStatus "@baseboard_fab2_lib.baseboard_fab2(sch_1):page149_i43" )
				( pin "C1T22.1"
					( objectStatus "a" )
				)
				( pin "C1T22.2"
					( objectStatus "b" )
				)
			)
			( gate "C1T8"
				( objectStatus "@baseboard_fab2_lib.baseboard_fab2(sch_1):page149_i44" )
				( pin "C1T8.1"
					( objectStatus "a" )
				)
				( pin "C1T8.2"
					( objectStatus "b" )
				)
			)
			( gate "C1T26"
				( objectStatus "@baseboard_fab2_lib.baseboard_fab2(sch_1):page149_i46" )
				( pin "C1T26.1"
					( objectStatus "a" )
				)
				( pin "C1T26.2"
					( objectStatus "b" )
				)
			)
			( gate "C1T14"
				( objectStatus "@baseboard_fab2_lib.baseboard_fab2(sch_1):page149_i49" )
				( pin "C1T14.1"
					( objectStatus "a" )
				)
				( pin "C1T14.2"
					( objectStatus "b" )
				)
			)
			( gate "C1T13"
				( objectStatus "@baseboard_fab2_lib.baseboard_fab2(sch_1):page149_i74" )
				( pin "C1T13.1"
					( objectStatus "a" )
				)
				( pin "C1T13.2"
					( objectStatus "b" )
				)
			)
			( gate "C1T9"
				( objectStatus "@baseboard_fab2_lib.baseboard_fab2(sch_1):page149_i75" )
				( pin "C1T9.1"
					( objectStatus "a" )
				)
				( pin "C1T9.2"
					( objectStatus "b" )
				)
			)
			( gate "C1T28"
				( objectStatus "@baseboard_fab2_lib.baseboard_fab2(sch_1):page149_i77" )
				( pin "C1T28.1"
					( objectStatus "a" )
				)
				( pin "C1T28.2"
					( objectStatus "b" )
				)
			)
			( gate "C1U6"
				( objectStatus "@baseboard_fab2_lib.baseboard_fab2(sch_1):page149_i78" )
				( pin "C1U6.1"
					( objectStatus "a" )
				)
				( pin "C1U6.2"
					( objectStatus "b" )
				)
			)
			( gate "C1U7"
				( objectStatus "@baseboard_fab2_lib.baseboard_fab2(sch_1):page149_i79" )
				( pin "C1U7.1"
					( objectStatus "a" )
				)
				( pin "C1U7.2"
					( objectStatus "b" )
				)
			)
			( gate "C1T34"
				( objectStatus "@baseboard_fab2_lib.baseboard_fab2(sch_1):page149_i80" )
				( pin "C1T34.1"
					( objectStatus "a" )
				)
				( pin "C1T34.2"
					( objectStatus "b" )
				)
			)
			( gate "C1T24"
				( objectStatus "@baseboard_fab2_lib.baseboard_fab2(sch_1):page149_i81" )
				( pin "C1T24.1"
					( objectStatus "a" )
				)
				( pin "C1T24.2"
					( objectStatus "b" )
				)
			)
			( gate "C1T27"
				( objectStatus "@baseboard_fab2_lib.baseboard_fab2(sch_1):page149_i82" )
				( pin "C1T27.1"
					( objectStatus "a" )
				)
				( pin "C1T27.2"
					( objectStatus "b" )
				)
			)
			( gate "C1T36"
				( objectStatus "@baseboard_fab2_lib.baseboard_fab2(sch_1):page149_i83" )
				( pin "C1T36.1"
					( objectStatus "a" )
				)
				( pin "C1T36.2"
					( objectStatus "b" )
				)
			)
			( gate "C1U1"
				( objectStatus "@baseboard_fab2_lib.baseboard_fab2(sch_1):page149_i84" )
				( pin "C1U1.1"
					( objectStatus "a" )
				)
				( pin "C1U1.2"
					( objectStatus "b" )
				)
			)
			( gate "C1T42"
				( objectStatus "@baseboard_fab2_lib.baseboard_fab2(sch_1):page149_i85" )
				( pin "C1T42.1"
					( objectStatus "a" )
				)
				( pin "C1T42.2"
					( objectStatus "b" )
				)
			)
			( gate "C1U12"
				( objectStatus "@baseboard_fab2_lib.baseboard_fab2(sch_1):page149_i88" )
				( pin "C1U12.1"
					( objectStatus "a" )
				)
				( pin "C1U12.2"
					( objectStatus "b" )
				)
			)
			( gate "C1T32"
				( objectStatus "@baseboard_fab2_lib.baseboard_fab2(sch_1):page149_i89" )
				( pin "C1T32.1"
					( objectStatus "a" )
				)
				( pin "C1T32.2"
					( objectStatus "b" )
				)
			)
			( gate "C1T55"
				( objectStatus "@baseboard_fab2_lib.baseboard_fab2(sch_1):page149_i90" )
				( pin "C1T55.1"
					( objectStatus "a" )
				)
				( pin "C1T55.2"
					( objectStatus "b" )
				)
			)
			( gate "C1T46"
				( objectStatus "@baseboard_fab2_lib.baseboard_fab2(sch_1):page149_i91" )
				( pin "C1T46.1"
					( objectStatus "a" )
				)
				( pin "C1T46.2"
					( objectStatus "b" )
				)
			)
			( gate "C1T31"
				( objectStatus "@baseboard_fab2_lib.baseboard_fab2(sch_1):page149_i92" )
				( pin "C1T31.1"
					( objectStatus "a" )
				)
				( pin "C1T31.2"
					( objectStatus "b" )
				)
			)
			( gate "C1T35"
				( objectStatus "@baseboard_fab2_lib.baseboard_fab2(sch_1):page149_i93" )
				( pin "C1T35.1"
					( objectStatus "a" )
				)
				( pin "C1T35.2"
					( objectStatus "b" )
				)
			)
			( gate "C1T49"
				( objectStatus "@baseboard_fab2_lib.baseboard_fab2(sch_1):page149_i94" )
				( pin "C1T49.1"
					( objectStatus "a" )
				)
				( pin "C1T49.2"
					( objectStatus "b" )
				)
			)
			( gate "C9F18"
				( objectStatus "@baseboard_fab2_lib.baseboard_fab2(sch_1):page149_i104" )
				( pin "C9F18.1"
					( objectStatus "a" )
				)
				( pin "C9F18.2"
					( objectStatus "b" )
				)
			)
			( gate "C9F14"
				( objectStatus "@baseboard_fab2_lib.baseboard_fab2(sch_1):page149_i105" )
				( pin "C9F14.1"
					( objectStatus "a" )
				)
				( pin "C9F14.2"
					( objectStatus "b" )
				)
			)
			( gate "C9F12"
				( objectStatus "@baseboard_fab2_lib.baseboard_fab2(sch_1):page149_i106" )
				( pin "C9F12.1"
					( objectStatus "a" )
				)
				( pin "C9F12.2"
					( objectStatus "b" )
				)
			)
			( gate "FB9F1"
				( objectStatus "@baseboard_fab2_lib.baseboard_fab2(sch_1):page149_i107" )
				( pin "FB9F1.1"
					( objectStatus "a" )
				)
				( pin "FB9F1.2"
					( objectStatus "b" )
				)
			)
			( gate "C1T20"
				( objectStatus "@baseboard_fab2_lib.baseboard_fab2(sch_1):page149_i119" )
				( pin "C1T20.1"
					( objectStatus "a" )
				)
				( pin "C1T20.2"
					( objectStatus "b" )
				)
			)
			( gate "C1T19"
				( objectStatus "@baseboard_fab2_lib.baseboard_fab2(sch_1):page149_i121" )
				( pin "C1T19.1"
					( objectStatus "a" )
				)
				( pin "C1T19.2"
					( objectStatus "b" )
				)
			)
			( gate "FB1T2"
				( objectStatus "@baseboard_fab2_lib.baseboard_fab2(sch_1):page149_i122" )
				( pin "FB1T2.1"
					( objectStatus "a" )
				)
				( pin "FB1T2.2"
					( objectStatus "b" )
				)
			)
			( gate "FB1U1"
				( objectStatus "@baseboard_fab2_lib.baseboard_fab2(sch_1):page149_i140" )
				( pin "FB1U1.1"
					( objectStatus "a" )
				)
				( pin "FB1U1.2"
					( objectStatus "b" )
				)
			)
			( gate "C1U18"
				( objectStatus "@baseboard_fab2_lib.baseboard_fab2(sch_1):page149_i141" )
				( pin "C1U18.1"
					( objectStatus "a" )
				)
				( pin "C1U18.2"
					( objectStatus "b" )
				)
			)
			( gate "C1U17"
				( objectStatus "@baseboard_fab2_lib.baseboard_fab2(sch_1):page149_i142" )
				( pin "C1U17.1"
					( objectStatus "a" )
				)
				( pin "C1U17.2"
					( objectStatus "b" )
				)
			)
			( gate "C1T23"
				( objectStatus "@baseboard_fab2_lib.baseboard_fab2(sch_1):page149_i147" )
				( pin "C1T23.1"
					( objectStatus "a" )
				)
				( pin "C1T23.2"
					( objectStatus "b" )
				)
			)
			( gate "C1T16"
				( objectStatus "@baseboard_fab2_lib.baseboard_fab2(sch_1):page149_i150" )
				( pin "C1T16.1"
					( objectStatus "a" )
				)
				( pin "C1T16.2"
					( objectStatus "b" )
				)
			)
			( gate "C1T17"
				( objectStatus "@baseboard_fab2_lib.baseboard_fab2(sch_1):page149_i151" )
				( pin "C1T17.1"
					( objectStatus "a" )
				)
				( pin "C1T17.2"
					( objectStatus "b" )
				)
			)
			( gate "C1T18"
				( objectStatus "@baseboard_fab2_lib.baseboard_fab2(sch_1):page149_i152" )
				( pin "C1T18.1"
					( objectStatus "a" )
				)
				( pin "C1T18.2"
					( objectStatus "b" )
				)
			)
			( gate "FB1T1"
				( objectStatus "@baseboard_fab2_lib.baseboard_fab2(sch_1):page149_i153" )
				( pin "FB1T1.1"
					( objectStatus "a" )
				)
				( pin "FB1T1.2"
					( objectStatus "b" )
				)
			)
			( gate "C8F10"
				( objectStatus "@baseboard_fab2_lib.baseboard_fab2(sch_1):page149_i159" )
				( pin "C8F10.1"
					( objectStatus "a" )
				)
				( pin "C8F10.2"
					( objectStatus "b" )
				)
			)
			( gate "C9F15"
				( objectStatus "@baseboard_fab2_lib.baseboard_fab2(sch_1):page149_i160" )
				( pin "C9F15.1"
					( objectStatus "a" )
				)
				( pin "C9F15.2"
					( objectStatus "b" )
				)
			)
			( gate "C8F9"
				( objectStatus "@baseboard_fab2_lib.baseboard_fab2(sch_1):page149_i161" )
				( pin "C8F9.1"
					( objectStatus "a" )
				)
				( pin "C8F9.2"
					( objectStatus "b" )
				)
			)
			( gate "FB2T1"
				( objectStatus "@baseboard_fab2_lib.baseboard_fab2(sch_1):page149_i163" )
				( pin "FB2T1.1"
					( objectStatus "a" )
				)
				( pin "FB2T1.2"
					( objectStatus "b" )
				)
			)
			( gate "R1T13"
				( objectStatus "@baseboard_fab2_lib.baseboard_fab2(sch_1):page150_i43" )
				( pin "R1T13.1"
					( objectStatus "a" )
				)
				( pin "R1T13.2"
					( objectStatus "b" )
				)
			)
			( gate "R9F36"
				( objectStatus "@baseboard_fab2_lib.baseboard_fab2(sch_1):page150_i44" )
				( pin "R9F36.1"
					( objectStatus "a" )
				)
				( pin "R9F36.2"
					( objectStatus "b" )
				)
			)
			( gate "R9F17"
				( objectStatus "@baseboard_fab2_lib.baseboard_fab2(sch_1):page150_i46" )
				( pin "R9F17.1"
					( objectStatus "a" )
				)
				( pin "R9F17.2"
					( objectStatus "b" )
				)
			)
			( gate "R9F14"
				( objectStatus "@baseboard_fab2_lib.baseboard_fab2(sch_1):page150_i47" )
				( pin "R9F14.1"
					( objectStatus "a" )
				)
				( pin "R9F14.2"
					( objectStatus "b" )
				)
			)
			( gate "R1T18"
				( objectStatus "@baseboard_fab2_lib.baseboard_fab2(sch_1):page150_i48" )
				( pin "R1T18.1"
					( objectStatus "a" )
				)
				( pin "R1T18.2"
					( objectStatus "b" )
				)
			)
			( gate "R1T20"
				( objectStatus "@baseboard_fab2_lib.baseboard_fab2(sch_1):page150_i49" )
				( pin "R1T20.1"
					( objectStatus "a" )
				)
				( pin "R1T20.2"
					( objectStatus "b" )
				)
			)
			( gate "R1T22"
				( objectStatus "@baseboard_fab2_lib.baseboard_fab2(sch_1):page150_i50" )
				( pin "R1T22.1"
					( objectStatus "a" )
				)
				( pin "R1T22.2"
					( objectStatus "b" )
				)
			)
			( gate "R9F35"
				( objectStatus "@baseboard_fab2_lib.baseboard_fab2(sch_1):page150_i51" )
				( pin "R9F35.1"
					( objectStatus "a" )
				)
				( pin "R9F35.2"
					( objectStatus "b" )
				)
			)
			( gate "R9F9"
				( objectStatus "@baseboard_fab2_lib.baseboard_fab2(sch_1):page150_i52" )
				( pin "R9F9.1"
					( objectStatus "a" )
				)
				( pin "R9F9.2"
					( objectStatus "b" )
				)
			)
			( gate "R1T21"
				( objectStatus "@baseboard_fab2_lib.baseboard_fab2(sch_1):page150_i53" )
				( pin "R1T21.1"
					( objectStatus "a" )
				)
				( pin "R1T21.2"
					( objectStatus "b" )
				)
			)
			( gate "R1T14"
				( objectStatus "@baseboard_fab2_lib.baseboard_fab2(sch_1):page150_i54" )
				( pin "R1T14.1"
					( objectStatus "a" )
				)
				( pin "R1T14.2"
					( objectStatus "b" )
				)
			)
			( gate "R9F37"
				( objectStatus "@baseboard_fab2_lib.baseboard_fab2(sch_1):page150_i55" )
				( pin "R9F37.1"
					( objectStatus "a" )
				)
				( pin "R9F37.2"
					( objectStatus "b" )
				)
			)
			( gate "R9F16"
				( objectStatus "@baseboard_fab2_lib.baseboard_fab2(sch_1):page150_i56" )
				( pin "R9F16.1"
					( objectStatus "a" )
				)
				( pin "R9F16.2"
					( objectStatus "b" )
				)
			)
			( gate "R1T19"
				( objectStatus "@baseboard_fab2_lib.baseboard_fab2(sch_1):page150_i57" )
				( pin "R1T19.1"
					( objectStatus "a" )
				)
				( pin "R1T19.2"
					( objectStatus "b" )
				)
			)
			( gate "R9F38"
				( objectStatus "@baseboard_fab2_lib.baseboard_fab2(sch_1):page150_i59" )
				( pin "R9F38.1"
					( objectStatus "a" )
				)
				( pin "R9F38.2"
					( objectStatus "b" )
				)
			)
			( gate "R9F10"
				( objectStatus "@baseboard_fab2_lib.baseboard_fab2(sch_1):page150_i60" )
				( pin "R9F10.1"
					( objectStatus "a" )
				)
				( pin "R9F10.2"
					( objectStatus "b" )
				)
			)
			( gate "R1T16"
				( objectStatus "@baseboard_fab2_lib.baseboard_fab2(sch_1):page150_i61" )
				( pin "R1T16.1"
					( objectStatus "a" )
				)
				( pin "R1T16.2"
					( objectStatus "b" )
				)
			)
			( gate "R9F18"
				( objectStatus "@baseboard_fab2_lib.baseboard_fab2(sch_1):page150_i62" )
				( pin "R9F18.1"
					( objectStatus "a" )
				)
				( pin "R9F18.2"
					( objectStatus "b" )
				)
			)
			( gate "R9F19"
				( objectStatus "@baseboard_fab2_lib.baseboard_fab2(sch_1):page150_i63" )
				( pin "R9F19.1"
					( objectStatus "a" )
				)
				( pin "R9F19.2"
					( objectStatus "b" )
				)
			)
			( gate "R9F39"
				( objectStatus "@baseboard_fab2_lib.baseboard_fab2(sch_1):page150_i64" )
				( pin "R9F39.1"
					( objectStatus "a" )
				)
				( pin "R9F39.2"
					( objectStatus "b" )
				)
			)
			( gate "R9F40"
				( objectStatus "@baseboard_fab2_lib.baseboard_fab2(sch_1):page150_i65" )
				( pin "R9F40.1"
					( objectStatus "a" )
				)
				( pin "R9F40.2"
					( objectStatus "b" )
				)
			)
			( gate "R1R11"
				( objectStatus "@baseboard_fab2_lib.baseboard_fab2(sch_1):page150_i66" )
				( pin "R1R11.1"
					( objectStatus "a" )
				)
				( pin "R1R11.2"
					( objectStatus "b" )
				)
			)
			( gate "R9F15"
				( objectStatus "@baseboard_fab2_lib.baseboard_fab2(sch_1):page150_i111" )
				( pin "R9F15.1"
					( objectStatus "a" )
				)
				( pin "R9F15.2"
					( objectStatus "b" )
				)
			)
			( gate "R1T17"
				( objectStatus "@baseboard_fab2_lib.baseboard_fab2(sch_1):page150_i112" )
				( pin "R1T17.1"
					( objectStatus "a" )
				)
				( pin "R1T17.2"
					( objectStatus "b" )
				)
			)
			( gate "R9E15"
				( objectStatus "@baseboard_fab2_lib.baseboard_fab2(sch_1):page150_i114" )
				( pin "R9E15.1"
					( objectStatus "a" )
				)
				( pin "R9E15.2"
					( objectStatus "b" )
				)
			)
			( gate "U9F5"
				( objectStatus "@baseboard_fab2_lib.baseboard_fab2(sch_1):page151_i1" )
				( pin "U9F5.N3"
					( objectStatus "a0" )
				)
				( pin "U9F5.P7"
					( objectStatus "a1" )
				)
				( pin "U9F5.P3"
					( objectStatus "a2" )
				)
				( pin "U9F5.N2"
					( objectStatus "a3" )
				)
				( pin "U9F5.P8"
					( objectStatus "a4" )
				)
				( pin "U9F5.P2"
					( objectStatus "a5" )
				)
				( pin "U9F5.R8"
					( objectStatus "a6" )
				)
				( pin "U9F5.R2"
					( objectStatus "a7" )
				)
				( pin "U9F5.T8"
					( objectStatus "a8" )
				)
				( pin "U9F5.R3"
					( objectStatus "a9" )
				)
				( pin "U9F5.L7"
					( objectStatus "a10_ap" )
				)
				( pin "U9F5.R7"
					( objectStatus "a11" )
				)
				( pin "U9F5.N7"
					( objectStatus "\a12/bc_n\" )
				)
				( pin "U9F5.M2"
					( objectStatus "ba0" )
				)
				( pin "U9F5.N8"
					( objectStatus "ba1" )
				)
				( pin "U9F5.M3"
					( objectStatus "ba2" )
				)
				( pin "U9F5.K3"
					( objectStatus "cas_n" )
				)
				( pin "U9F5.J7"
					( objectStatus "ck" )
				)
				( pin "U9F5.K7"
					( objectStatus "ck_n" )
				)
				( pin "U9F5.K9"
					( objectStatus "cke" )
				)
				( pin "U9F5.L2"
					( objectStatus "cs_n" )
				)
				( pin "U9F5.E7"
					( objectStatus "dml" )
				)
				( pin "U9F5.D3"
					( objectStatus "dmu" )
				)
				( pin "U9F5.E3"
					( objectStatus "dql0" )
				)
				( pin "U9F5.F7"
					( objectStatus "dql1" )
				)
				( pin "U9F5.F2"
					( objectStatus "dql2" )
				)
				( pin "U9F5.F8"
					( objectStatus "dql3" )
				)
				( pin "U9F5.H3"
					( objectStatus "dql4" )
				)
				( pin "U9F5.H8"
					( objectStatus "dql5" )
				)
				( pin "U9F5.G2"
					( objectStatus "dql6" )
				)
				( pin "U9F5.H7"
					( objectStatus "dql7" )
				)
				( pin "U9F5.F3"
					( objectStatus "dqsl" )
				)
				( pin "U9F5.G3"
					( objectStatus "dqsl_n" )
				)
				( pin "U9F5.C7"
					( objectStatus "dqsu" )
				)
				( pin "U9F5.B7"
					( objectStatus "dqsu_n" )
				)
				( pin "U9F5.D7"
					( objectStatus "dqu0" )
				)
				( pin "U9F5.C3"
					( objectStatus "dqu1" )
				)
				( pin "U9F5.C8"
					( objectStatus "dqu2" )
				)
				( pin "U9F5.C2"
					( objectStatus "dqu3" )
				)
				( pin "U9F5.A7"
					( objectStatus "dqu4" )
				)
				( pin "U9F5.A2"
					( objectStatus "dqu5" )
				)
				( pin "U9F5.B8"
					( objectStatus "dqu6" )
				)
				( pin "U9F5.A3"
					( objectStatus "dqu7" )
				)
				( pin "U9F5.J1"
					( objectStatus "nc(0)" )
				)
				( pin "U9F5.J9"
					( objectStatus "nc(1)" )
				)
				( pin "U9F5.L1"
					( objectStatus "nc(2)" )
				)
				( pin "U9F5.L9"
					( objectStatus "nc(3)" )
				)
				( pin "U9F5.M7"
					( objectStatus "nc(4)" )
				)
				( pin "U9F5.T3"
					( objectStatus "nc(5)" )
				)
				( pin "U9F5.T7"
					( objectStatus "nc(6)" )
				)
				( pin "U9F5.K1"
					( objectStatus "odt" )
				)
				( pin "U9F5.J3"
					( objectStatus "ras_n" )
				)
				( pin "U9F5.T2"
					( objectStatus "reset_n" )
				)
				( pin "U9F5.B2"
					( objectStatus "vdd(0)" )
				)
				( pin "U9F5.D9"
					( objectStatus "vdd(1)" )
				)
				( pin "U9F5.G7"
					( objectStatus "vdd(2)" )
				)
				( pin "U9F5.K2"
					( objectStatus "vdd(3)" )
				)
				( pin "U9F5.K8"
					( objectStatus "vdd(4)" )
				)
				( pin "U9F5.N1"
					( objectStatus "vdd(5)" )
				)
				( pin "U9F5.N9"
					( objectStatus "vdd(6)" )
				)
				( pin "U9F5.R1"
					( objectStatus "vdd(7)" )
				)
				( pin "U9F5.R9"
					( objectStatus "vdd(8)" )
				)
				( pin "U9F5.A1"
					( objectStatus "vddq(0)" )
				)
				( pin "U9F5.A8"
					( objectStatus "vddq(1)" )
				)
				( pin "U9F5.C1"
					( objectStatus "vddq(2)" )
				)
				( pin "U9F5.C9"
					( objectStatus "vddq(3)" )
				)
				( pin "U9F5.D2"
					( objectStatus "vddq(4)" )
				)
				( pin "U9F5.E9"
					( objectStatus "vddq(5)" )
				)
				( pin "U9F5.F1"
					( objectStatus "vddq(6)" )
				)
				( pin "U9F5.H2"
					( objectStatus "vddq(7)" )
				)
				( pin "U9F5.H9"
					( objectStatus "vddq(8)" )
				)
				( pin "U9F5.M8"
					( objectStatus "vrefca" )
				)
				( pin "U9F5.H1"
					( objectStatus "vrefdq" )
				)
				( pin "U9F5.A9"
					( objectStatus "vss(0)" )
				)
				( pin "U9F5.B3"
					( objectStatus "vss(1)" )
				)
				( pin "U9F5.E1"
					( objectStatus "vss(2)" )
				)
				( pin "U9F5.G8"
					( objectStatus "vss(3)" )
				)
				( pin "U9F5.J2"
					( objectStatus "vss(4)" )
				)
				( pin "U9F5.J8"
					( objectStatus "vss(5)" )
				)
				( pin "U9F5.M1"
					( objectStatus "vss(6)" )
				)
				( pin "U9F5.M9"
					( objectStatus "vss(7)" )
				)
				( pin "U9F5.P1"
					( objectStatus "vss(8)" )
				)
				( pin "U9F5.P9"
					( objectStatus "vss(9)" )
				)
				( pin "U9F5.T1"
					( objectStatus "vss(10)" )
				)
				( pin "U9F5.T9"
					( objectStatus "vss(11)" )
				)
				( pin "U9F5.B1"
					( objectStatus "vssq(0)" )
				)
				( pin "U9F5.B9"
					( objectStatus "vssq(1)" )
				)
				( pin "U9F5.D1"
					( objectStatus "vssq(2)" )
				)
				( pin "U9F5.D8"
					( objectStatus "vssq(3)" )
				)
				( pin "U9F5.E2"
					( objectStatus "vssq(4)" )
				)
				( pin "U9F5.E8"
					( objectStatus "vssq(5)" )
				)
				( pin "U9F5.F9"
					( objectStatus "vssq(6)" )
				)
				( pin "U9F5.G1"
					( objectStatus "vssq(7)" )
				)
				( pin "U9F5.G9"
					( objectStatus "vssq(8)" )
				)
				( pin "U9F5.L3"
					( objectStatus "we_n" )
				)
				( pin "U9F5.L8"
					( objectStatus "zq" )
				)
			)
			( gate "R1T27"
				( objectStatus "@baseboard_fab2_lib.baseboard_fab2(sch_1):page151_i32" )
				( pin "R1T27.1"
					( objectStatus "a" )
				)
				( pin "R1T27.2"
					( objectStatus "b" )
				)
			)
			( gate "C1T48"
				( objectStatus "@baseboard_fab2_lib.baseboard_fab2(sch_1):page151_i58" )
				( pin "C1T48.1"
					( objectStatus "a" )
				)
				( pin "C1T48.2"
					( objectStatus "b" )
				)
			)
			( gate "R1T30"
				( objectStatus "@baseboard_fab2_lib.baseboard_fab2(sch_1):page151_i60" )
				( pin "R1T30.1"
					( objectStatus "a" )
				)
				( pin "R1T30.2"
					( objectStatus "b" )
				)
			)
			( gate "R1T29"
				( objectStatus "@baseboard_fab2_lib.baseboard_fab2(sch_1):page151_i61" )
				( pin "R1T29.1"
					( objectStatus "a" )
				)
				( pin "R1T29.2"
					( objectStatus "b" )
				)
			)
			( gate "C1T51"
				( objectStatus "@baseboard_fab2_lib.baseboard_fab2(sch_1):page151_i62" )
				( pin "C1T51.1"
					( objectStatus "a" )
				)
				( pin "C1T51.2"
					( objectStatus "b" )
				)
			)
			( gate "C1T41"
				( objectStatus "@baseboard_fab2_lib.baseboard_fab2(sch_1):page151_i63" )
				( pin "C1T41.1"
					( objectStatus "a" )
				)
				( pin "C1T41.2"
					( objectStatus "b" )
				)
			)
			( gate "C1T39"
				( objectStatus "@baseboard_fab2_lib.baseboard_fab2(sch_1):page151_i64" )
				( pin "C1T39.1"
					( objectStatus "a" )
				)
				( pin "C1T39.2"
					( objectStatus "b" )
				)
			)
			( gate "U9F3"
				( objectStatus "@baseboard_fab2_lib.baseboard_fab2(sch_1):page151_i69" )
				( pin "U9F3.2"
					( objectStatus "a" )
				)
				( pin "U9F3.4"
					( objectStatus "y" )
				)
			)
			( gate "R9F34"
				( objectStatus "@baseboard_fab2_lib.baseboard_fab2(sch_1):page151_i70" )
				( pin "R9F34.1"
					( objectStatus "a" )
				)
				( pin "R9F34.2"
					( objectStatus "b" )
				)
			)
			( gate "R9F29"
				( objectStatus "@baseboard_fab2_lib.baseboard_fab2(sch_1):page151_i71" )
				( pin "R9F29.1"
					( objectStatus "a" )
				)
				( pin "R9F29.2"
					( objectStatus "b" )
				)
			)
			( gate "C1T40"
				( objectStatus "@baseboard_fab2_lib.baseboard_fab2(sch_1):page151_i76" )
				( pin "C1T40.1"
					( objectStatus "a" )
				)
				( pin "C1T40.2"
					( objectStatus "b" )
				)
			)
			( gate "C1U15"
				( objectStatus "@baseboard_fab2_lib.baseboard_fab2(sch_1):page151_i78" )
				( pin "C1U15.1"
					( objectStatus "a" )
				)
				( pin "C1U15.2"
					( objectStatus "b" )
				)
			)
			( gate "C1U13"
				( objectStatus "@baseboard_fab2_lib.baseboard_fab2(sch_1):page151_i79" )
				( pin "C1U13.1"
					( objectStatus "a" )
				)
				( pin "C1U13.2"
					( objectStatus "b" )
				)
			)
			( gate "C1T33"
				( objectStatus "@baseboard_fab2_lib.baseboard_fab2(sch_1):page151_i80" )
				( pin "C1T33.1"
					( objectStatus "a" )
				)
				( pin "C1T33.2"
					( objectStatus "b" )
				)
			)
			( gate "C1U16"
				( objectStatus "@baseboard_fab2_lib.baseboard_fab2(sch_1):page151_i81" )
				( pin "C1U16.1"
					( objectStatus "a" )
				)
				( pin "C1U16.2"
					( objectStatus "b" )
				)
			)
			( gate "C1T53"
				( objectStatus "@baseboard_fab2_lib.baseboard_fab2(sch_1):page151_i82" )
				( pin "C1T53.1"
					( objectStatus "a" )
				)
				( pin "C1T53.2"
					( objectStatus "b" )
				)
			)
			( gate "C1T54"
				( objectStatus "@baseboard_fab2_lib.baseboard_fab2(sch_1):page151_i83" )
				( pin "C1T54.1"
					( objectStatus "a" )
				)
				( pin "C1T54.2"
					( objectStatus "b" )
				)
			)
			( gate "C1U14"
				( objectStatus "@baseboard_fab2_lib.baseboard_fab2(sch_1):page151_i84" )
				( pin "C1U14.1"
					( objectStatus "a" )
				)
				( pin "C1U14.2"
					( objectStatus "b" )
				)
			)
			( gate "C1U10"
				( objectStatus "@baseboard_fab2_lib.baseboard_fab2(sch_1):page151_i86" )
				( pin "C1U10.1"
					( objectStatus "a" )
				)
				( pin "C1U10.2"
					( objectStatus "b" )
				)
			)
			( gate "C9F11"
				( objectStatus "@baseboard_fab2_lib.baseboard_fab2(sch_1):page151_i90" )
				( pin "C9F11.1"
					( objectStatus "a" )
				)
				( pin "C9F11.2"
					( objectStatus "b" )
				)
			)
			( gate "U9G1"
				( objectStatus "@baseboard_fab2_lib.baseboard_fab2(sch_1):page152_i1" )
				( pin "U9G1.13"
					( objectStatus "a0" )
				)
				( pin "U9G1.12"
					( objectStatus "a1" )
				)
				( pin "U9G1.10"
					( objectStatus "a2" )
				)
				( pin "U9G1.9"
					( objectStatus "a3" )
				)
				( pin "U9G1.2"
					( objectStatus "b0" )
				)
				( pin "U9G1.3"
					( objectStatus "b1" )
				)
				( pin "U9G1.5"
					( objectStatus "b2" )
				)
				( pin "U9G1.6"
					( objectStatus "b3" )
				)
				( pin "U9G1.1"
					( objectStatus "dir" )
				)
				( pin "U9G1.7"
					( objectStatus "gnd(0)" )
				)
				( pin "U9G1.8"
					( objectStatus "gnd(1)" )
				)
				( pin "U9G1.11"
					( objectStatus "gnd(2)" )
				)
				( pin "U9G1.14"
					( objectStatus "vcc" )
				)
				( pin "U9G1.4"
					( objectStatus "vref" )
				)
			)
			( gate "R1U30"
				( objectStatus "@baseboard_fab2_lib.baseboard_fab2(sch_1):page152_i2" )
				( pin "R1U30.1"
					( objectStatus "a" )
				)
				( pin "R1U30.2"
					( objectStatus "b" )
				)
			)
			( gate "R1U46"
				( objectStatus "@baseboard_fab2_lib.baseboard_fab2(sch_1):page152_i6" )
				( pin "R1U46.1"
					( objectStatus "a" )
				)
				( pin "R1U46.2"
					( objectStatus "b" )
				)
			)
			( gate "R1U42"
				( objectStatus "@baseboard_fab2_lib.baseboard_fab2(sch_1):page152_i14" )
				( pin "R1U42.1"
					( objectStatus "a" )
				)
				( pin "R1U42.2"
					( objectStatus "b" )
				)
			)
			( gate "R1U36"
				( objectStatus "@baseboard_fab2_lib.baseboard_fab2(sch_1):page152_i15" )
				( pin "R1U36.1"
					( objectStatus "a" )
				)
				( pin "R1U36.2"
					( objectStatus "b" )
				)
			)
			( gate "R1U34"
				( objectStatus "@baseboard_fab2_lib.baseboard_fab2(sch_1):page152_i16" )
				( pin "R1U34.1"
					( objectStatus "a" )
				)
				( pin "R1U34.2"
					( objectStatus "b" )
				)
			)
			( gate "C1U19"
				( objectStatus "@baseboard_fab2_lib.baseboard_fab2(sch_1):page152_i18" )
				( pin "C1U19.1"
					( objectStatus "a" )
				)
				( pin "C1U19.2"
					( objectStatus "b" )
				)
			)
			( gate "R1U43"
				( objectStatus "@baseboard_fab2_lib.baseboard_fab2(sch_1):page152_i25" )
				( pin "R1U43.1"
					( objectStatus "a" )
				)
				( pin "R1U43.2"
					( objectStatus "b" )
				)
			)
			( gate "R1U37"
				( objectStatus "@baseboard_fab2_lib.baseboard_fab2(sch_1):page152_i26" )
				( pin "R1U37.1"
					( objectStatus "a" )
				)
				( pin "R1U37.2"
					( objectStatus "b" )
				)
			)
			( gate "C1U22"
				( objectStatus "@baseboard_fab2_lib.baseboard_fab2(sch_1):page152_i27" )
				( pin "C1U22.1"
					( objectStatus "a" )
				)
				( pin "C1U22.2"
					( objectStatus "b" )
				)
			)
			( gate "R103"
				( objectStatus "@baseboard_fab2_lib.baseboard_fab2(sch_1):page152_i45" )
				( pin "R103.1"
					( objectStatus "a" )
				)
				( pin "R103.2"
					( objectStatus "b" )
				)
			)
			( gate "R107"
				( objectStatus "@baseboard_fab2_lib.baseboard_fab2(sch_1):page152_i47" )
				( pin "R107.1"
					( objectStatus "a" )
				)
				( pin "R107.2"
					( objectStatus "b" )
				)
			)
			( gate "R104"
				( objectStatus "@baseboard_fab2_lib.baseboard_fab2(sch_1):page152_i49" )
				( pin "R104.1"
					( objectStatus "a" )
				)
				( pin "R104.2"
					( objectStatus "b" )
				)
			)
			( gate "R101"
				( objectStatus "@baseboard_fab2_lib.baseboard_fab2(sch_1):page152_i50" )
				( pin "R101.1"
					( objectStatus "a" )
				)
				( pin "R101.2"
					( objectStatus "b" )
				)
			)
			( gate "R99"
				( objectStatus "@baseboard_fab2_lib.baseboard_fab2(sch_1):page152_i51" )
				( pin "R99.1"
					( objectStatus "a" )
				)
				( pin "R99.2"
					( objectStatus "b" )
				)
			)
			( gate "R2U40"
				( objectStatus "@baseboard_fab2_lib.baseboard_fab2(sch_1):page152_i53" )
				( pin "R2U40.1"
					( objectStatus "a" )
				)
				( pin "R2U40.2"
					( objectStatus "b" )
				)
			)
			( gate "R2U41"
				( objectStatus "@baseboard_fab2_lib.baseboard_fab2(sch_1):page152_i54" )
				( pin "R2U41.1"
					( objectStatus "a" )
				)
				( pin "R2U41.2"
					( objectStatus "b" )
				)
			)
			( gate "R1U41"
				( objectStatus "@baseboard_fab2_lib.baseboard_fab2(sch_1):page152_i56" )
				( pin "R1U41.1"
					( objectStatus "a" )
				)
				( pin "R1U41.2"
					( objectStatus "b" )
				)
			)
			( gate "R1U35"
				( objectStatus "@baseboard_fab2_lib.baseboard_fab2(sch_1):page152_i57" )
				( pin "R1U35.1"
					( objectStatus "a" )
				)
				( pin "R1U35.2"
					( objectStatus "b" )
				)
			)
			( gate "R4P17"
				( objectStatus "@baseboard_fab2_lib.baseboard_fab2(sch_1):page152_i58" )
				( pin "R4P17.1"
					( objectStatus "a" )
				)
				( pin "R4P17.2"
					( objectStatus "b" )
				)
			)
			( gate "R4P20"
				( objectStatus "@baseboard_fab2_lib.baseboard_fab2(sch_1):page152_i59" )
				( pin "R4P20.1"
					( objectStatus "a" )
				)
				( pin "R4P20.2"
					( objectStatus "b" )
				)
			)
			( gate "R7P5"
				( objectStatus "@baseboard_fab2_lib.baseboard_fab2(sch_1):page152_i61" )
				( pin "R7P5.1"
					( objectStatus "a" )
				)
				( pin "R7P5.2"
					( objectStatus "b" )
				)
			)
			( gate "R7P21"
				( objectStatus "@baseboard_fab2_lib.baseboard_fab2(sch_1):page152_i62" )
				( pin "R7P21.1"
					( objectStatus "a" )
				)
				( pin "R7P21.2"
					( objectStatus "b" )
				)
			)
			( gate "R105"
				( objectStatus "@baseboard_fab2_lib.baseboard_fab2(sch_1):page152_i64" )
				( pin "R105.1"
					( objectStatus "a" )
				)
				( pin "R105.2"
					( objectStatus "b" )
				)
			)
			( gate "R106"
				( objectStatus "@baseboard_fab2_lib.baseboard_fab2(sch_1):page152_i65" )
				( pin "R106.1"
					( objectStatus "a" )
				)
				( pin "R106.2"
					( objectStatus "b" )
				)
			)
			( gate "R109"
				( objectStatus "@baseboard_fab2_lib.baseboard_fab2(sch_1):page152_i66" )
				( pin "R109.1"
					( objectStatus "a" )
				)
				( pin "R109.2"
					( objectStatus "b" )
				)
			)
			( gate "R102"
				( objectStatus "@baseboard_fab2_lib.baseboard_fab2(sch_1):page152_i67" )
				( pin "R102.1"
					( objectStatus "a" )
				)
				( pin "R102.2"
					( objectStatus "b" )
				)
			)
			( gate "R100"
				( objectStatus "@baseboard_fab2_lib.baseboard_fab2(sch_1):page152_i68" )
				( pin "R100.1"
					( objectStatus "a" )
				)
				( pin "R100.2"
					( objectStatus "b" )
				)
			)
			( gate "R108"
				( objectStatus "@baseboard_fab2_lib.baseboard_fab2(sch_1):page152_i69" )
				( pin "R108.1"
					( objectStatus "a" )
				)
				( pin "R108.2"
					( objectStatus "b" )
				)
			)
			( gate "R110"
				( objectStatus "@baseboard_fab2_lib.baseboard_fab2(sch_1):page152_i70" )
				( pin "R110.1"
					( objectStatus "a" )
				)
				( pin "R110.2"
					( objectStatus "b" )
				)
			)
			( gate "R125"
				( objectStatus "@baseboard_fab2_lib.baseboard_fab2(sch_1):page152_i71" )
				( pin "R125.1"
					( objectStatus "a" )
				)
				( pin "R125.2"
					( objectStatus "b" )
				)
			)
			( gate "R124"
				( objectStatus "@baseboard_fab2_lib.baseboard_fab2(sch_1):page152_i72" )
				( pin "R124.1"
					( objectStatus "a" )
				)
				( pin "R124.2"
					( objectStatus "b" )
				)
			)
			( gate "R123"
				( objectStatus "@baseboard_fab2_lib.baseboard_fab2(sch_1):page152_i73" )
				( pin "R123.1"
					( objectStatus "a" )
				)
				( pin "R123.2"
					( objectStatus "b" )
				)
			)
			( gate "R122"
				( objectStatus "@baseboard_fab2_lib.baseboard_fab2(sch_1):page152_i74" )
				( pin "R122.1"
					( objectStatus "a" )
				)
				( pin "R122.2"
					( objectStatus "b" )
				)
			)
			( gate "R126"
				( objectStatus "@baseboard_fab2_lib.baseboard_fab2(sch_1):page152_i79" )
				( pin "R126.1"
					( objectStatus "a" )
				)
				( pin "R126.2"
					( objectStatus "b" )
				)
			)
			( gate "R127"
				( objectStatus "@baseboard_fab2_lib.baseboard_fab2(sch_1):page152_i92" )
				( pin "R127.1"
					( objectStatus "a" )
				)
				( pin "R127.2"
					( objectStatus "b" )
				)
			)
			( gate "R128"
				( objectStatus "@baseboard_fab2_lib.baseboard_fab2(sch_1):page152_i93" )
				( pin "R128.1"
					( objectStatus "a" )
				)
				( pin "R128.2"
					( objectStatus "b" )
				)
			)
			( gate "R129"
				( objectStatus "@baseboard_fab2_lib.baseboard_fab2(sch_1):page152_i94" )
				( pin "R129.1"
					( objectStatus "a" )
				)
				( pin "R129.2"
					( objectStatus "b" )
				)
			)
			( gate "R168"
				( objectStatus "@baseboard_fab2_lib.baseboard_fab2(sch_1):page152_i95" )
				( pin "R168.1"
					( objectStatus "a" )
				)
				( pin "R168.2"
					( objectStatus "b" )
				)
			)
			( gate "R169"
				( objectStatus "@baseboard_fab2_lib.baseboard_fab2(sch_1):page152_i98" )
				( pin "R169.1"
					( objectStatus "a" )
				)
				( pin "R169.2"
					( objectStatus "b" )
				)
			)
			( gate "R170"
				( objectStatus "@baseboard_fab2_lib.baseboard_fab2(sch_1):page152_i100" )
				( pin "R170.1"
					( objectStatus "a" )
				)
				( pin "R170.2"
					( objectStatus "b" )
				)
			)
			( gate "R171"
				( objectStatus "@baseboard_fab2_lib.baseboard_fab2(sch_1):page152_i102" )
				( pin "R171.1"
					( objectStatus "a" )
				)
				( pin "R171.2"
					( objectStatus "b" )
				)
			)
			( gate "R7F6"
				( objectStatus "@baseboard_fab2_lib.baseboard_fab2(sch_1):page153_i90" )
				( pin "R7F6.1"
					( objectStatus "a" )
				)
				( pin "R7F6.2"
					( objectStatus "b" )
				)
			)
			( gate "R7F5"
				( objectStatus "@baseboard_fab2_lib.baseboard_fab2(sch_1):page153_i94" )
				( pin "R7F5.1"
					( objectStatus "a" )
				)
				( pin "R7F5.2"
					( objectStatus "b" )
				)
			)
			( gate "R7F4"
				( objectStatus "@baseboard_fab2_lib.baseboard_fab2(sch_1):page153_i98" )
				( pin "R7F4.1"
					( objectStatus "a" )
				)
				( pin "R7F4.2"
					( objectStatus "b" )
				)
			)
			( gate "R7G1"
				( objectStatus "@baseboard_fab2_lib.baseboard_fab2(sch_1):page153_i108" )
				( pin "R7G1.1"
					( objectStatus "a" )
				)
				( pin "R7G1.2"
					( objectStatus "b" )
				)
			)
			( gate "R7F3"
				( objectStatus "@baseboard_fab2_lib.baseboard_fab2(sch_1):page153_i109" )
				( pin "R7F3.1"
					( objectStatus "a" )
				)
				( pin "R7F3.2"
					( objectStatus "b" )
				)
			)
			( gate "C7F2"
				( objectStatus "@baseboard_fab2_lib.baseboard_fab2(sch_1):page153_i130" )
				( pin "C7F2.1"
					( objectStatus "a" )
				)
				( pin "C7F2.2"
					( objectStatus "b" )
				)
			)
			( gate "C7F1"
				( objectStatus "@baseboard_fab2_lib.baseboard_fab2(sch_1):page153_i131" )
				( pin "C7F1.1"
					( objectStatus "a" )
				)
				( pin "C7F1.2"
					( objectStatus "b" )
				)
			)
			( gate "C3T5"
				( objectStatus "@baseboard_fab2_lib.baseboard_fab2(sch_1):page153_i136" )
				( pin "C3T5.1"
					( objectStatus "a" )
				)
				( pin "C3T5.2"
					( objectStatus "b" )
				)
			)
			( gate "C3T4"
				( objectStatus "@baseboard_fab2_lib.baseboard_fab2(sch_1):page153_i138" )
				( pin "C3T4.1"
					( objectStatus "a" )
				)
				( pin "C3T4.2"
					( objectStatus "b" )
				)
			)
			( gate "R7F32"
				( objectStatus "@baseboard_fab2_lib.baseboard_fab2(sch_1):page153_i140" )
				( pin "R7F32.1"
					( objectStatus "a" )
				)
				( pin "R7F32.2"
					( objectStatus "b" )
				)
			)
			( gate "U7F1"
				( objectStatus "@baseboard_fab2_lib.baseboard_fab2(sch_1):page153_i146" )
				( pin "U7F1.16"
					( objectStatus "clk" )
				)
				( pin "U7F1.7"
					( objectStatus "cs_n" )
				)
				( pin "U7F1.15"
					( objectStatus "di_io(0)" )
				)
				( pin "U7F1.8"
					( objectStatus "do_io(1)" )
				)
				( pin "U7F1.10"
					( objectStatus "gnd" )
				)
				( pin "U7F1.1"
					( objectStatus "hold_n_io(3)" )
				)
				( pin "U7F1.14"
					( objectStatus "nc(0)" )
				)
				( pin "U7F1.13"
					( objectStatus "nc(1)" )
				)
				( pin "U7F1.12"
					( objectStatus "nc(2)" )
				)
				( pin "U7F1.11"
					( objectStatus "nc(3)" )
				)
				( pin "U7F1.6"
					( objectStatus "nc(4)" )
				)
				( pin "U7F1.5"
					( objectStatus "nc(5)" )
				)
				( pin "U7F1.4"
					( objectStatus "nc(6)" )
				)
				( pin "U7F1.3"
					( objectStatus "reset_n" )
				)
				( pin "U7F1.2"
					( objectStatus "vcc" )
				)
				( pin "U7F1.9"
					( objectStatus "wp_n_io(2)" )
				)
			)
			( gate "R3T3"
				( objectStatus "@baseboard_fab2_lib.baseboard_fab2(sch_1):page153_i150" )
				( pin "R3T3.1"
					( objectStatus "a" )
				)
				( pin "R3T3.2"
					( objectStatus "b" )
				)
			)
			( gate "R3T5"
				( objectStatus "@baseboard_fab2_lib.baseboard_fab2(sch_1):page153_i152" )
				( pin "R3T5.1"
					( objectStatus "a" )
				)
				( pin "R3T5.2"
					( objectStatus "b" )
				)
			)
			( gate "R3T2"
				( objectStatus "@baseboard_fab2_lib.baseboard_fab2(sch_1):page153_i155" )
				( pin "R3T2.1"
					( objectStatus "a" )
				)
				( pin "R3T2.2"
					( objectStatus "b" )
				)
			)
			( gate "R3U1"
				( objectStatus "@baseboard_fab2_lib.baseboard_fab2(sch_1):page153_i156" )
				( pin "R3U1.1"
					( objectStatus "a" )
				)
				( pin "R3U1.2"
					( objectStatus "b" )
				)
			)
			( gate "R3T1"
				( objectStatus "@baseboard_fab2_lib.baseboard_fab2(sch_1):page153_i157" )
				( pin "R3T1.1"
					( objectStatus "a" )
				)
				( pin "R3T1.2"
					( objectStatus "b" )
				)
			)
			( gate "U3T1"
				( objectStatus "@baseboard_fab2_lib.baseboard_fab2(sch_1):page153_i165" )
				( pin "U3T1.16"
					( objectStatus "clk" )
				)
				( pin "U3T1.7"
					( objectStatus "cs_n" )
				)
				( pin "U3T1.15"
					( objectStatus "di_io(0)" )
				)
				( pin "U3T1.8"
					( objectStatus "do_io(1)" )
				)
				( pin "U3T1.10"
					( objectStatus "gnd" )
				)
				( pin "U3T1.1"
					( objectStatus "hold_n_io(3)" )
				)
				( pin "U3T1.14"
					( objectStatus "nc(0)" )
				)
				( pin "U3T1.13"
					( objectStatus "nc(1)" )
				)
				( pin "U3T1.12"
					( objectStatus "nc(2)" )
				)
				( pin "U3T1.11"
					( objectStatus "nc(3)" )
				)
				( pin "U3T1.6"
					( objectStatus "nc(4)" )
				)
				( pin "U3T1.5"
					( objectStatus "nc(5)" )
				)
				( pin "U3T1.4"
					( objectStatus "nc(6)" )
				)
				( pin "U3T1.3"
					( objectStatus "reset_n" )
				)
				( pin "U3T1.2"
					( objectStatus "vcc" )
				)
				( pin "U3T1.9"
					( objectStatus "wp_n_io(2)" )
				)
			)
			( gate "R8F8"
				( objectStatus "@baseboard_fab2_lib.baseboard_fab2(sch_1):page153_i166" )
				( pin "R8F8.1"
					( objectStatus "a" )
				)
				( pin "R8F8.2"
					( objectStatus "b" )
				)
			)
			( gate "R8F7"
				( objectStatus "@baseboard_fab2_lib.baseboard_fab2(sch_1):page153_i167" )
				( pin "R8F7.1"
					( objectStatus "a" )
				)
				( pin "R8F7.2"
					( objectStatus "b" )
				)
			)
			( gate "R7F28"
				( objectStatus "@baseboard_fab2_lib.baseboard_fab2(sch_1):page153_i168" )
				( pin "R7F28.1"
					( objectStatus "a" )
				)
				( pin "R7F28.2"
					( objectStatus "b" )
				)
			)
			( gate "R7F30"
				( objectStatus "@baseboard_fab2_lib.baseboard_fab2(sch_1):page153_i170" )
				( pin "R7F30.1"
					( objectStatus "a" )
				)
				( pin "R7F30.2"
					( objectStatus "b" )
				)
			)
			( gate "R3T4"
				( objectStatus "@baseboard_fab2_lib.baseboard_fab2(sch_1):page153_i174" )
				( pin "R3T4.1"
					( objectStatus "a" )
				)
				( pin "R3T4.2"
					( objectStatus "b" )
				)
			)
			( gate "R3T12"
				( objectStatus "@baseboard_fab2_lib.baseboard_fab2(sch_1):page153_i178" )
				( pin "R3T12.1"
					( objectStatus "a" )
				)
				( pin "R3T12.2"
					( objectStatus "b" )
				)
			)
			( gate "R3T9"
				( objectStatus "@baseboard_fab2_lib.baseboard_fab2(sch_1):page153_i179" )
				( pin "R3T9.1"
					( objectStatus "a" )
				)
				( pin "R3T9.2"
					( objectStatus "b" )
				)
			)
			( gate "R7F29"
				( objectStatus "@baseboard_fab2_lib.baseboard_fab2(sch_1):page153_i181" )
				( pin "R7F29.1"
					( objectStatus "a" )
				)
				( pin "R7F29.2"
					( objectStatus "b" )
				)
			)
			( gate "R3T10"
				( objectStatus "@baseboard_fab2_lib.baseboard_fab2(sch_1):page153_i184" )
				( pin "R3T10.1"
					( objectStatus "a" )
				)
				( pin "R3T10.2"
					( objectStatus "b" )
				)
			)
			( gate "C8E18"
				( objectStatus "@baseboard_fab2_lib.baseboard_fab2(sch_1):page154_i14" )
				( pin "C8E18.1"
					( objectStatus "a" )
				)
				( pin "C8E18.2"
					( objectStatus "b" )
				)
			)
			( gate "R2T9"
				( objectStatus "@baseboard_fab2_lib.baseboard_fab2(sch_1):page154_i62" )
				( pin "R2T9.1"
					( objectStatus "a" )
				)
				( pin "R2T9.2"
					( objectStatus "b" )
				)
			)
			( gate "U8F1"
				( objectStatus "@baseboard_fab2_lib.baseboard_fab2(sch_1):page154_i74" )
				( pin "U8F1.15"
					( objectStatus "en" )
				)
				( pin "U8F1.8"
					( objectStatus "gnd" )
				)
				( pin "U8F1.2"
					( objectStatus "ia0" )
				)
				( pin "U8F1.3"
					( objectStatus "ia1" )
				)
				( pin "U8F1.5"
					( objectStatus "ib0" )
				)
				( pin "U8F1.6"
					( objectStatus "ib1" )
				)
				( pin "U8F1.11"
					( objectStatus "ic0" )
				)
				( pin "U8F1.10"
					( objectStatus "ic1" )
				)
				( pin "U8F1.14"
					( objectStatus "id0" )
				)
				( pin "U8F1.13"
					( objectStatus "id1" )
				)
				( pin "U8F1.1"
					( objectStatus "s" )
				)
				( pin "U8F1.16"
					( objectStatus "vcc" )
				)
				( pin "U8F1.4"
					( objectStatus "ya" )
				)
				( pin "U8F1.7"
					( objectStatus "yb" )
				)
				( pin "U8F1.9"
					( objectStatus "yc" )
				)
				( pin "U8F1.12"
					( objectStatus "yd" )
				)
			)
			( gate "U2T1"
				( objectStatus "@baseboard_fab2_lib.baseboard_fab2(sch_1):page154_i75" )
				( pin "U2T1.15"
					( objectStatus "en" )
				)
				( pin "U2T1.8"
					( objectStatus "gnd" )
				)
				( pin "U2T1.2"
					( objectStatus "ia0" )
				)
				( pin "U2T1.3"
					( objectStatus "ia1" )
				)
				( pin "U2T1.5"
					( objectStatus "ib0" )
				)
				( pin "U2T1.6"
					( objectStatus "ib1" )
				)
				( pin "U2T1.11"
					( objectStatus "ic0" )
				)
				( pin "U2T1.10"
					( objectStatus "ic1" )
				)
				( pin "U2T1.14"
					( objectStatus "id0" )
				)
				( pin "U2T1.13"
					( objectStatus "id1" )
				)
				( pin "U2T1.1"
					( objectStatus "s" )
				)
				( pin "U2T1.16"
					( objectStatus "vcc" )
				)
				( pin "U2T1.4"
					( objectStatus "ya" )
				)
				( pin "U2T1.7"
					( objectStatus "yb" )
				)
				( pin "U2T1.9"
					( objectStatus "yc" )
				)
				( pin "U2T1.12"
					( objectStatus "yd" )
				)
			)
			( gate "R2T2"
				( objectStatus "@baseboard_fab2_lib.baseboard_fab2(sch_1):page154_i92" )
				( pin "R2T2.1"
					( objectStatus "a" )
				)
				( pin "R2T2.2"
					( objectStatus "b" )
				)
			)
			( gate "R2R12"
				( objectStatus "@baseboard_fab2_lib.baseboard_fab2(sch_1):page154_i93" )
				( pin "R2R12.1"
					( objectStatus "a" )
				)
				( pin "R2R12.2"
					( objectStatus "b" )
				)
			)
			( gate "C2T1"
				( objectStatus "@baseboard_fab2_lib.baseboard_fab2(sch_1):page154_i94" )
				( pin "C2T1.1"
					( objectStatus "a" )
				)
				( pin "C2T1.2"
					( objectStatus "b" )
				)
			)
			( gate "U2T3"
				( objectStatus "@baseboard_fab2_lib.baseboard_fab2(sch_1):page154_i99" )
				( pin "U2T3.1"
					( objectStatus "a" )
				)
				( pin "U2T3.2"
					( objectStatus "b" )
				)
				( pin "U2T3.4"
					( objectStatus "y" )
				)
			)
			( gate "U2T2"
				( objectStatus "@baseboard_fab2_lib.baseboard_fab2(sch_1):page154_i100" )
				( pin "U2T2.1"
					( objectStatus "a" )
				)
				( pin "U2T2.2"
					( objectStatus "b" )
				)
				( pin "U2T2.4"
					( objectStatus "y" )
				)
			)
			( gate "R2T13"
				( objectStatus "@baseboard_fab2_lib.baseboard_fab2(sch_1):page154_i101" )
				( pin "R2T13.1"
					( objectStatus "a" )
				)
				( pin "R2T13.2"
					( objectStatus "b" )
				)
			)
			( gate "R2T11"
				( objectStatus "@baseboard_fab2_lib.baseboard_fab2(sch_1):page154_i105" )
				( pin "R2T11.1"
					( objectStatus "a" )
				)
				( pin "R2T11.2"
					( objectStatus "b" )
				)
			)
			( gate "R2T8"
				( objectStatus "@baseboard_fab2_lib.baseboard_fab2(sch_1):page154_i106" )
				( pin "R2T8.1"
					( objectStatus "a" )
				)
				( pin "R2T8.2"
					( objectStatus "b" )
				)
			)
			( gate "R8F6"
				( objectStatus "@baseboard_fab2_lib.baseboard_fab2(sch_1):page154_i119" )
				( pin "R8F6.1"
					( objectStatus "a" )
				)
				( pin "R8F6.2"
					( objectStatus "b" )
				)
			)
			( gate "Q8F1"
				( objectStatus "@baseboard_fab2_lib.baseboard_fab2(sch_1):page154_i126" )
				( pin "Q8F1.3"
					( objectStatus "drn" )
				)
				( pin "Q8F1.1"
					( objectStatus "gate" )
				)
				( pin "Q8F1.2"
					( objectStatus "src" )
				)
			)
			( gate "R2T6"
				( objectStatus "@baseboard_fab2_lib.baseboard_fab2(sch_1):page154_i127" )
				( pin "R2T6.1"
					( objectStatus "a" )
				)
				( pin "R2T6.2"
					( objectStatus "b" )
				)
			)
			( gate "R1U6"
				( objectStatus "@baseboard_fab2_lib.baseboard_fab2(sch_1):page154_i128" )
				( pin "R1U6.1"
					( objectStatus "a" )
				)
				( pin "R1U6.2"
					( objectStatus "b" )
				)
			)
			( gate "C2T12"
				( objectStatus "@baseboard_fab2_lib.baseboard_fab2(sch_1):page154_i132" )
				( pin "C2T12.1"
					( objectStatus "a" )
				)
				( pin "C2T12.2"
					( objectStatus "b" )
				)
			)
			( gate "C2T8"
				( objectStatus "@baseboard_fab2_lib.baseboard_fab2(sch_1):page154_i135" )
				( pin "C2T8.1"
					( objectStatus "a" )
				)
				( pin "C2T8.2"
					( objectStatus "b" )
				)
			)
			( gate "R9A8"
				( objectStatus "@baseboard_fab2_lib.baseboard_fab2(sch_1):page155_i53" )
				( pin "R9A8.1"
					( objectStatus "a" )
				)
				( pin "R9A8.2"
					( objectStatus "b" )
				)
			)
			( gate "R1L32"
				( objectStatus "@baseboard_fab2_lib.baseboard_fab2(sch_1):page155_i65" )
				( pin "R1L32.1"
					( objectStatus "a" )
				)
				( pin "R1L32.2"
					( objectStatus "b" )
				)
			)
			( gate "R1L30"
				( objectStatus "@baseboard_fab2_lib.baseboard_fab2(sch_1):page155_i66" )
				( pin "R1L30.1"
					( objectStatus "a" )
				)
				( pin "R1L30.2"
					( objectStatus "b" )
				)
			)
			( gate "R1L25"
				( objectStatus "@baseboard_fab2_lib.baseboard_fab2(sch_1):page155_i67" )
				( pin "R1L25.1"
					( objectStatus "a" )
				)
				( pin "R1L25.2"
					( objectStatus "b" )
				)
			)
			( gate "R1L24"
				( objectStatus "@baseboard_fab2_lib.baseboard_fab2(sch_1):page155_i68" )
				( pin "R1L24.1"
					( objectStatus "a" )
				)
				( pin "R1L24.2"
					( objectStatus "b" )
				)
			)
			( gate "R1L20"
				( objectStatus "@baseboard_fab2_lib.baseboard_fab2(sch_1):page155_i73" )
				( pin "R1L20.1"
					( objectStatus "a" )
				)
				( pin "R1L20.2"
					( objectStatus "b" )
				)
			)
			( gate "R1L18"
				( objectStatus "@baseboard_fab2_lib.baseboard_fab2(sch_1):page155_i74" )
				( pin "R1L18.1"
					( objectStatus "a" )
				)
				( pin "R1L18.2"
					( objectStatus "b" )
				)
			)
			( gate "R1L14"
				( objectStatus "@baseboard_fab2_lib.baseboard_fab2(sch_1):page155_i75" )
				( pin "R1L14.1"
					( objectStatus "a" )
				)
				( pin "R1L14.2"
					( objectStatus "b" )
				)
			)
			( gate "R1L11"
				( objectStatus "@baseboard_fab2_lib.baseboard_fab2(sch_1):page155_i76" )
				( pin "R1L11.1"
					( objectStatus "a" )
				)
				( pin "R1L11.2"
					( objectStatus "b" )
				)
			)
			( gate "R9A7"
				( objectStatus "@baseboard_fab2_lib.baseboard_fab2(sch_1):page155_i80" )
				( pin "R9A7.1"
					( objectStatus "a" )
				)
				( pin "R9A7.2"
					( objectStatus "b" )
				)
			)
			( gate "C9A1"
				( objectStatus "@baseboard_fab2_lib.baseboard_fab2(sch_1):page155_i127" )
				( pin "C9A1.1"
					( objectStatus "a" )
				)
				( pin "C9A1.2"
					( objectStatus "b" )
				)
			)
			( gate "F1L1"
				( objectStatus "@baseboard_fab2_lib.baseboard_fab2(sch_1):page155_i129" )
				( pin "F1L1.1"
					( objectStatus "a(0)" )
				)
				( pin "F1L1.2"
					( objectStatus "b(0)" )
				)
			)
			( gate "R1L9"
				( objectStatus "@baseboard_fab2_lib.baseboard_fab2(sch_1):page155_i130" )
				( pin "R1L9.1"
					( objectStatus "a" )
				)
				( pin "R1L9.2"
					( objectStatus "b" )
				)
			)
			( gate "R9A5"
				( objectStatus "@baseboard_fab2_lib.baseboard_fab2(sch_1):page155_i136" )
				( pin "R9A5.1"
					( objectStatus "a" )
				)
				( pin "R9A5.2"
					( objectStatus "b" )
				)
			)
			( gate "J9A2"
				( objectStatus "@baseboard_fab2_lib.baseboard_fab2(sch_1):page155_i171" )
				( pin "J9A2.1"
					( objectStatus "io1" )
				)
				( pin "J9A2.2"
					( objectStatus "io2" )
				)
				( pin "J9A2.3"
					( objectStatus "io3" )
				)
				( pin "J9A2.4"
					( objectStatus "io4" )
				)
				( pin "J9A2.5"
					( objectStatus "io5" )
				)
				( pin "J9A2.6"
					( objectStatus "io6" )
				)
				( pin "J9A2.7"
					( objectStatus "io7" )
				)
				( pin "J9A2.8"
					( objectStatus "io8" )
				)
				( pin "J9A2.9"
					( objectStatus "io9" )
				)
				( pin "J9A2.10"
					( objectStatus "io10" )
				)
				( pin "J9A2.11"
					( objectStatus "io11" )
				)
				( pin "J9A2.12"
					( objectStatus "io12" )
				)
				( pin "J9A2.13"
					( objectStatus "io13" )
				)
				( pin "J9A2.14"
					( objectStatus "io14" )
				)
			)
			( gate "U9A1"
				( objectStatus "@baseboard_fab2_lib.baseboard_fab2(sch_1):page155_i178" )
				( pin "U9A1.2"
					( objectStatus "a" )
				)
				( pin "U9A1.4"
					( objectStatus "y" )
				)
			)
			( gate "C9F7"
				( objectStatus "@baseboard_fab2_lib.baseboard_fab2(sch_1):page155_i184" )
				( pin "C9F7.1"
					( objectStatus "a" )
				)
				( pin "C9F7.2"
					( objectStatus "b" )
				)
			)
			( gate "R1L2"
				( objectStatus "@baseboard_fab2_lib.baseboard_fab2(sch_1):page155_i186" )
				( pin "R1L2.1"
					( objectStatus "a" )
				)
				( pin "R1L2.2"
					( objectStatus "b" )
				)
			)
			( gate "Q1L2"
				( objectStatus "@baseboard_fab2_lib.baseboard_fab2(sch_1):page155_i187" )
				( pin "Q1L2.3"
					( objectStatus "drain(0)" )
				)
				( pin "Q1L2.5"
					( objectStatus "gate(0)" )
				)
				( pin "Q1L2.4"
					( objectStatus "source(0)" )
				)
			)
			( gate "Q1L2"
				( objectStatus "@baseboard_fab2_lib.baseboard_fab2(sch_1):page155_i188" )
				( pin "Q1L2.6"
					( objectStatus "drain(0)" )
				)
				( pin "Q1L2.2"
					( objectStatus "gate(0)" )
				)
				( pin "Q1L2.1"
					( objectStatus "source(0)" )
				)
			)
			( gate "R9A6"
				( objectStatus "@baseboard_fab2_lib.baseboard_fab2(sch_1):page155_i191" )
				( pin "R9A6.1"
					( objectStatus "a" )
				)
				( pin "R9A6.2"
					( objectStatus "b" )
				)
			)
			( gate "U8F3"
				( objectStatus "@baseboard_fab2_lib.baseboard_fab2(sch_1):page156_i201" )
				( pin "U8F3.1"
					( objectStatus "\1a\" )
				)
				( pin "U8F3.6"
					( objectStatus "\1y\" )
				)
				( pin "U8F3.3"
					( objectStatus "\2a\" )
				)
				( pin "U8F3.4"
					( objectStatus "\2y\" )
				)
			)
			( gate "R2T34"
				( objectStatus "@baseboard_fab2_lib.baseboard_fab2(sch_1):page156_i206" )
				( pin "R2T34.1"
					( objectStatus "a" )
				)
				( pin "R2T34.2"
					( objectStatus "b" )
				)
			)
			( gate "R2T35"
				( objectStatus "@baseboard_fab2_lib.baseboard_fab2(sch_1):page156_i207" )
				( pin "R2T35.1"
					( objectStatus "a" )
				)
				( pin "R2T35.2"
					( objectStatus "b" )
				)
			)
			( gate "R2T22"
				( objectStatus "@baseboard_fab2_lib.baseboard_fab2(sch_1):page156_i210" )
				( pin "R2T22.1"
					( objectStatus "a" )
				)
				( pin "R2T22.2"
					( objectStatus "b" )
				)
			)
			( gate "R8F26"
				( objectStatus "@baseboard_fab2_lib.baseboard_fab2(sch_1):page156_i211" )
				( pin "R8F26.1"
					( objectStatus "a" )
				)
				( pin "R8F26.2"
					( objectStatus "b" )
				)
			)
			( gate "R8E24"
				( objectStatus "@baseboard_fab2_lib.baseboard_fab2(sch_1):page156_i214" )
				( pin "R8E24.1"
					( objectStatus "a" )
				)
				( pin "R8E24.2"
					( objectStatus "b" )
				)
			)
			( gate "R8E22"
				( objectStatus "@baseboard_fab2_lib.baseboard_fab2(sch_1):page156_i215" )
				( pin "R8E22.1"
					( objectStatus "a" )
				)
				( pin "R8E22.2"
					( objectStatus "b" )
				)
			)
			( gate "R2U2"
				( objectStatus "@baseboard_fab2_lib.baseboard_fab2(sch_1):page156_i265" )
				( pin "R2U2.1"
					( objectStatus "a" )
				)
				( pin "R2U2.2"
					( objectStatus "b" )
				)
			)
			( gate "R8G2"
				( objectStatus "@baseboard_fab2_lib.baseboard_fab2(sch_1):page156_i267" )
				( pin "R8G2.1"
					( objectStatus "a" )
				)
				( pin "R8G2.2"
					( objectStatus "b" )
				)
			)
			( gate "U8G1"
				( objectStatus "@baseboard_fab2_lib.baseboard_fab2(sch_1):page156_i269" )
				( pin "U8G1.1"
					( objectStatus "\1a\" )
				)
				( pin "U8G1.6"
					( objectStatus "\1y\" )
				)
				( pin "U8G1.3"
					( objectStatus "\2a\" )
				)
				( pin "U8G1.4"
					( objectStatus "\2y\" )
				)
			)
			( gate "C2T35"
				( objectStatus "@baseboard_fab2_lib.baseboard_fab2(sch_1):page156_i273" )
				( pin "C2T35.1"
					( objectStatus "a" )
				)
				( pin "C2T35.2"
					( objectStatus "b" )
				)
			)
			( gate "C8F16"
				( objectStatus "@baseboard_fab2_lib.baseboard_fab2(sch_1):page156_i275" )
				( pin "C8F16.1"
					( objectStatus "a" )
				)
				( pin "C8F16.2"
					( objectStatus "b" )
				)
			)
			( gate "R8E11"
				( objectStatus "@baseboard_fab2_lib.baseboard_fab2(sch_1):page156_i279" )
				( pin "R8E11.1"
					( objectStatus "a" )
				)
				( pin "R8E11.2"
					( objectStatus "b" )
				)
			)
			( gate "J9B2"
				( objectStatus "@baseboard_fab2_lib.baseboard_fab2(sch_1):page156_i281" )
				( pin "J9B2.1"
					( objectStatus "io1" )
				)
				( pin "J9B2.2"
					( objectStatus "io2" )
				)
				( pin "J9B2.3"
					( objectStatus "io3" )
				)
			)
			( gate "J8C1"
				( objectStatus "@baseboard_fab2_lib.baseboard_fab2(sch_1):page156_i285" )
				( pin "J8C1.1"
					( objectStatus "io1" )
				)
				( pin "J8C1.2"
					( objectStatus "io2" )
				)
				( pin "J8C1.3"
					( objectStatus "io3" )
				)
			)
			( gate "R2T18"
				( objectStatus "@baseboard_fab2_lib.baseboard_fab2(sch_1):page156_i288" )
				( pin "R2T18.1"
					( objectStatus "a" )
				)
				( pin "R2T18.2"
					( objectStatus "b" )
				)
			)
			( gate "R2T28"
				( objectStatus "@baseboard_fab2_lib.baseboard_fab2(sch_1):page156_i289" )
				( pin "R2T28.1"
					( objectStatus "a" )
				)
				( pin "R2T28.2"
					( objectStatus "b" )
				)
			)
			( gate "Q5"
				( objectStatus "@baseboard_fab2_lib.baseboard_fab2(sch_1):page156_i290" )
				( pin "Q5.3"
					( objectStatus "drain(0)" )
				)
				( pin "Q5.5"
					( objectStatus "gate(0)" )
				)
				( pin "Q5.4"
					( objectStatus "source(0)" )
				)
			)
			( gate "Q5"
				( objectStatus "@baseboard_fab2_lib.baseboard_fab2(sch_1):page156_i291" )
				( pin "Q5.6"
					( objectStatus "drain(0)" )
				)
				( pin "Q5.2"
					( objectStatus "gate(0)" )
				)
				( pin "Q5.1"
					( objectStatus "source(0)" )
				)
			)
			( gate "R140"
				( objectStatus "@baseboard_fab2_lib.baseboard_fab2(sch_1):page156_i294" )
				( pin "R140.1"
					( objectStatus "a" )
				)
				( pin "R140.2"
					( objectStatus "b" )
				)
			)
			( gate "R141"
				( objectStatus "@baseboard_fab2_lib.baseboard_fab2(sch_1):page156_i299" )
				( pin "R141.1"
					( objectStatus "a" )
				)
				( pin "R141.2"
					( objectStatus "b" )
				)
			)
			( gate "R142"
				( objectStatus "@baseboard_fab2_lib.baseboard_fab2(sch_1):page156_i300" )
				( pin "R142.1"
					( objectStatus "a" )
				)
				( pin "R142.2"
					( objectStatus "b" )
				)
			)
			( gate "R146"
				( objectStatus "@baseboard_fab2_lib.baseboard_fab2(sch_1):page156_i302" )
				( pin "R146.1"
					( objectStatus "a" )
				)
				( pin "R146.2"
					( objectStatus "b" )
				)
			)
			( gate "R147"
				( objectStatus "@baseboard_fab2_lib.baseboard_fab2(sch_1):page156_i303" )
				( pin "R147.1"
					( objectStatus "a" )
				)
				( pin "R147.2"
					( objectStatus "b" )
				)
			)
			( gate "R148"
				( objectStatus "@baseboard_fab2_lib.baseboard_fab2(sch_1):page156_i304" )
				( pin "R148.1"
					( objectStatus "a" )
				)
				( pin "R148.2"
					( objectStatus "b" )
				)
			)
			( gate "R154"
				( objectStatus "@baseboard_fab2_lib.baseboard_fab2(sch_1):page156_i312" )
				( pin "R154.1"
					( objectStatus "a" )
				)
				( pin "R154.2"
					( objectStatus "b" )
				)
			)
			( gate "R153"
				( objectStatus "@baseboard_fab2_lib.baseboard_fab2(sch_1):page156_i313" )
				( pin "R153.1"
					( objectStatus "a" )
				)
				( pin "R153.2"
					( objectStatus "b" )
				)
			)
			( gate "R152"
				( objectStatus "@baseboard_fab2_lib.baseboard_fab2(sch_1):page156_i320" )
				( pin "R152.1"
					( objectStatus "a" )
				)
				( pin "R152.2"
					( objectStatus "b" )
				)
			)
			( gate "R149"
				( objectStatus "@baseboard_fab2_lib.baseboard_fab2(sch_1):page156_i321" )
				( pin "R149.1"
					( objectStatus "a" )
				)
				( pin "R149.2"
					( objectStatus "b" )
				)
			)
			( gate "R143"
				( objectStatus "@baseboard_fab2_lib.baseboard_fab2(sch_1):page156_i322" )
				( pin "R143.1"
					( objectStatus "a" )
				)
				( pin "R143.2"
					( objectStatus "b" )
				)
			)
			( gate "R150"
				( objectStatus "@baseboard_fab2_lib.baseboard_fab2(sch_1):page156_i323" )
				( pin "R150.1"
					( objectStatus "a" )
				)
				( pin "R150.2"
					( objectStatus "b" )
				)
			)
			( gate "R144"
				( objectStatus "@baseboard_fab2_lib.baseboard_fab2(sch_1):page156_i324" )
				( pin "R144.1"
					( objectStatus "a" )
				)
				( pin "R144.2"
					( objectStatus "b" )
				)
			)
			( gate "R145"
				( objectStatus "@baseboard_fab2_lib.baseboard_fab2(sch_1):page156_i331" )
				( pin "R145.1"
					( objectStatus "a" )
				)
				( pin "R145.2"
					( objectStatus "b" )
				)
			)
			( gate "R162"
				( objectStatus "@baseboard_fab2_lib.baseboard_fab2(sch_1):page156_i333" )
				( pin "R162.1"
					( objectStatus "a" )
				)
				( pin "R162.2"
					( objectStatus "b" )
				)
			)
			( gate "R151"
				( objectStatus "@baseboard_fab2_lib.baseboard_fab2(sch_1):page156_i336" )
				( pin "R151.1"
					( objectStatus "a" )
				)
				( pin "R151.2"
					( objectStatus "b" )
				)
			)
			( gate "R163"
				( objectStatus "@baseboard_fab2_lib.baseboard_fab2(sch_1):page156_i337" )
				( pin "R163.1"
					( objectStatus "a" )
				)
				( pin "R163.2"
					( objectStatus "b" )
				)
			)
			( gate "R161"
				( objectStatus "@baseboard_fab2_lib.baseboard_fab2(sch_1):page156_i340" )
				( pin "R161.1"
					( objectStatus "a" )
				)
				( pin "R161.2"
					( objectStatus "b" )
				)
			)
			( gate "R2N27"
				( objectStatus "@baseboard_fab2_lib.baseboard_fab2(sch_1):page157_i97" )
				( pin "R2N27.1"
					( objectStatus "a" )
				)
				( pin "R2N27.2"
					( objectStatus "b" )
				)
			)
			( gate "R8F23"
				( objectStatus "@baseboard_fab2_lib.baseboard_fab2(sch_1):page157_i296" )
				( pin "R8F23.1"
					( objectStatus "a" )
				)
				( pin "R8F23.2"
					( objectStatus "b" )
				)
			)
			( gate "R2T29"
				( objectStatus "@baseboard_fab2_lib.baseboard_fab2(sch_1):page157_i298" )
				( pin "R2T29.1"
					( objectStatus "a" )
				)
				( pin "R2T29.2"
					( objectStatus "b" )
				)
			)
			( gate "R2N25"
				( objectStatus "@baseboard_fab2_lib.baseboard_fab2(sch_1):page157_i302" )
				( pin "R2N25.1"
					( objectStatus "a" )
				)
				( pin "R2N25.2"
					( objectStatus "b" )
				)
			)
			( gate "R8F24"
				( objectStatus "@baseboard_fab2_lib.baseboard_fab2(sch_1):page157_i316" )
				( pin "R8F24.1"
					( objectStatus "a" )
				)
				( pin "R8F24.2"
					( objectStatus "b" )
				)
			)
			( gate "R2T5"
				( objectStatus "@baseboard_fab2_lib.baseboard_fab2(sch_1):page157_i326" )
				( pin "R2T5.1"
					( objectStatus "a" )
				)
				( pin "R2T5.2"
					( objectStatus "b" )
				)
			)
			( gate "R2T7"
				( objectStatus "@baseboard_fab2_lib.baseboard_fab2(sch_1):page157_i327" )
				( pin "R2T7.1"
					( objectStatus "a" )
				)
				( pin "R2T7.2"
					( objectStatus "b" )
				)
			)
			( gate "Q2T1"
				( objectStatus "@baseboard_fab2_lib.baseboard_fab2(sch_1):page157_i330" )
				( pin "Q2T1.1"
					( objectStatus "b" )
				)
				( pin "Q2T1.3"
					( objectStatus "c" )
				)
				( pin "Q2T1.2"
					( objectStatus "e" )
				)
			)
			( gate "R8D25"
				( objectStatus "@baseboard_fab2_lib.baseboard_fab2(sch_1):page157_i335" )
				( pin "R8D25.1"
					( objectStatus "a" )
				)
				( pin "R8D25.2"
					( objectStatus "b" )
				)
			)
			( gate "Q2T2"
				( objectStatus "@baseboard_fab2_lib.baseboard_fab2(sch_1):page157_i340" )
				( pin "Q2T2.3"
					( objectStatus "drn" )
				)
				( pin "Q2T2.1"
					( objectStatus "gate" )
				)
				( pin "Q2T2.2"
					( objectStatus "src" )
				)
			)
			( gate "R3N12"
				( objectStatus "@baseboard_fab2_lib.baseboard_fab2(sch_1):page157_i342" )
				( pin "R3N12.1"
					( objectStatus "a" )
				)
				( pin "R3N12.2"
					( objectStatus "b" )
				)
			)
			( gate "R3N11"
				( objectStatus "@baseboard_fab2_lib.baseboard_fab2(sch_1):page157_i344" )
				( pin "R3N11.1"
					( objectStatus "a" )
				)
				( pin "R3N11.2"
					( objectStatus "b" )
				)
			)
			( gate "R2M2"
				( objectStatus "@baseboard_fab2_lib.baseboard_fab2(sch_1):page157_i346" )
				( pin "R2M2.1"
					( objectStatus "a" )
				)
				( pin "R2M2.2"
					( objectStatus "b" )
				)
			)
			( gate "R2M5"
				( objectStatus "@baseboard_fab2_lib.baseboard_fab2(sch_1):page157_i348" )
				( pin "R2M5.1"
					( objectStatus "a" )
				)
				( pin "R2M5.2"
					( objectStatus "b" )
				)
			)
			( gate "S8E1"
				( objectStatus "@baseboard_fab2_lib.baseboard_fab2(sch_1):page157_i351" )
				( pin "S8E1.1"
					( objectStatus "a" )
				)
				( pin "S8E1.2"
					( objectStatus "b" )
				)
			)
			( gate "R2R9"
				( objectStatus "@baseboard_fab2_lib.baseboard_fab2(sch_1):page157_i352" )
				( pin "R2R9.1"
					( objectStatus "a" )
				)
				( pin "R2R9.2"
					( objectStatus "b" )
				)
			)
			( gate "C2R12"
				( objectStatus "@baseboard_fab2_lib.baseboard_fab2(sch_1):page157_i353" )
				( pin "C2R12.1"
					( objectStatus "a" )
				)
				( pin "C2R12.2"
					( objectStatus "b" )
				)
			)
			( gate "U2R1"
				( objectStatus "@baseboard_fab2_lib.baseboard_fab2(sch_1):page157_i356" )
				( pin "U2R1.3"
					( objectStatus "a(0)" )
				)
				( pin "U2R1.4"
					( objectStatus "y(0)" )
				)
			)
			( gate "U2R1"
				( objectStatus "@baseboard_fab2_lib.baseboard_fab2(sch_1):page157_i357" )
				( pin "U2R1.1"
					( objectStatus "a(0)" )
				)
				( pin "U2R1.6"
					( objectStatus "y(0)" )
				)
			)
			( gate "R2R10"
				( objectStatus "@baseboard_fab2_lib.baseboard_fab2(sch_1):page157_i358" )
				( pin "R2R10.1"
					( objectStatus "a" )
				)
				( pin "R2R10.2"
					( objectStatus "b" )
				)
			)
			( gate "R8E19"
				( objectStatus "@baseboard_fab2_lib.baseboard_fab2(sch_1):page157_i361" )
				( pin "R8E19.1"
					( objectStatus "a" )
				)
				( pin "R8E19.2"
					( objectStatus "b" )
				)
			)
			( gate "R2U4"
				( objectStatus "@baseboard_fab2_lib.baseboard_fab2(sch_1):page157_i367" )
				( pin "R2U4.1"
					( objectStatus "a" )
				)
				( pin "R2U4.2"
					( objectStatus "b" )
				)
			)
			( gate "R4R1"
				( objectStatus "@baseboard_fab2_lib.baseboard_fab2(sch_1):page157_i368" )
				( pin "R4R1.1"
					( objectStatus "a" )
				)
				( pin "R4R1.2"
					( objectStatus "b" )
				)
			)
			( gate "C2T3"
				( objectStatus "@baseboard_fab2_lib.baseboard_fab2(sch_1):page157_i370" )
				( pin "C2T3.1"
					( objectStatus "a" )
				)
				( pin "C2T3.2"
					( objectStatus "b" )
				)
			)
			( gate "U8D2"
				( objectStatus "@baseboard_fab2_lib.baseboard_fab2(sch_1):page157_i374" )
				( pin "U8D2.2"
					( objectStatus "a" )
				)
				( pin "U8D2.4"
					( objectStatus "y" )
				)
			)
			( gate "C8D1"
				( objectStatus "@baseboard_fab2_lib.baseboard_fab2(sch_1):page157_i376" )
				( pin "C8D1.1"
					( objectStatus "a" )
				)
				( pin "C8D1.2"
					( objectStatus "b" )
				)
			)
			( gate "R9E14"
				( objectStatus "@baseboard_fab2_lib.baseboard_fab2(sch_1):page157_i379" )
				( pin "R9E14.1"
					( objectStatus "a" )
				)
				( pin "R9E14.2"
					( objectStatus "b" )
				)
			)
			( gate "R1L7"
				( objectStatus "@baseboard_fab2_lib.baseboard_fab2(sch_1):page157_i382" )
				( pin "R1L7.1"
					( objectStatus "a" )
				)
				( pin "R1L7.2"
					( objectStatus "b" )
				)
			)
			( gate "R8E32"
				( objectStatus "@baseboard_fab2_lib.baseboard_fab2(sch_1):page157_i385" )
				( pin "R8E32.1"
					( objectStatus "a" )
				)
				( pin "R8E32.2"
					( objectStatus "b" )
				)
			)
			( gate "R8D22"
				( objectStatus "@baseboard_fab2_lib.baseboard_fab2(sch_1):page157_i386" )
				( pin "R8D22.1"
					( objectStatus "a" )
				)
				( pin "R8D22.2"
					( objectStatus "b" )
				)
			)
			( gate "R111"
				( objectStatus "@baseboard_fab2_lib.baseboard_fab2(sch_1):page157_i388" )
				( pin "R111.1"
					( objectStatus "a" )
				)
				( pin "R111.2"
					( objectStatus "b" )
				)
			)
			( gate "C1T10"
				( objectStatus "@baseboard_fab2_lib.baseboard_fab2(sch_1):page158_i70" )
				( pin "C1T10.1"
					( objectStatus "a" )
				)
				( pin "C1T10.2"
					( objectStatus "b" )
				)
			)
			( gate "U9F2"
				( objectStatus "@baseboard_fab2_lib.baseboard_fab2(sch_1):page158_i74" )
				( pin "U9F2.7"
					( objectStatus "a" )
				)
				( pin "U9F2.1"
					( objectStatus "b0" )
				)
				( pin "U9F2.2"
					( objectStatus "b1" )
				)
				( pin "U9F2.3"
					( objectStatus "b2" )
				)
				( pin "U9F2.4"
					( objectStatus "gnd" )
				)
				( pin "U9F2.6"
					( objectStatus "s1" )
				)
				( pin "U9F2.5"
					( objectStatus "s2" )
				)
				( pin "U9F2.8"
					( objectStatus "vcc" )
				)
			)
			( gate "U9F1"
				( objectStatus "@baseboard_fab2_lib.baseboard_fab2(sch_1):page158_i75" )
				( pin "U9F1.7"
					( objectStatus "a" )
				)
				( pin "U9F1.1"
					( objectStatus "b0" )
				)
				( pin "U9F1.2"
					( objectStatus "b1" )
				)
				( pin "U9F1.3"
					( objectStatus "b2" )
				)
				( pin "U9F1.4"
					( objectStatus "gnd" )
				)
				( pin "U9F1.6"
					( objectStatus "s1" )
				)
				( pin "U9F1.5"
					( objectStatus "s2" )
				)
				( pin "U9F1.8"
					( objectStatus "vcc" )
				)
			)
			( gate "R9F25"
				( objectStatus "@baseboard_fab2_lib.baseboard_fab2(sch_1):page158_i86" )
				( pin "R9F25.1"
					( objectStatus "a" )
				)
				( pin "R9F25.2"
					( objectStatus "b" )
				)
			)
			( gate "R9F27"
				( objectStatus "@baseboard_fab2_lib.baseboard_fab2(sch_1):page158_i91" )
				( pin "R9F27.1"
					( objectStatus "a" )
				)
				( pin "R9F27.2"
					( objectStatus "b" )
				)
			)
			( gate "C1T11"
				( objectStatus "@baseboard_fab2_lib.baseboard_fab2(sch_1):page158_i97" )
				( pin "C1T11.1"
					( objectStatus "a" )
				)
				( pin "C1T11.2"
					( objectStatus "b" )
				)
			)
			( gate "R9F26"
				( objectStatus "@baseboard_fab2_lib.baseboard_fab2(sch_1):page158_i99" )
				( pin "R9F26.1"
					( objectStatus "a" )
				)
				( pin "R9F26.2"
					( objectStatus "b" )
				)
			)
			( gate "R9F24"
				( objectStatus "@baseboard_fab2_lib.baseboard_fab2(sch_1):page158_i100" )
				( pin "R9F24.1"
					( objectStatus "a" )
				)
				( pin "R9F24.2"
					( objectStatus "b" )
				)
			)
			( gate "DS9A4"
				( objectStatus "@baseboard_fab2_lib.baseboard_fab2(sch_1):page158_i130" )
				( pin "DS9A4.1"
					( objectStatus "a" )
				)
				( pin "DS9A4.2"
					( objectStatus "c" )
				)
			)
			( gate "R1L43"
				( objectStatus "@baseboard_fab2_lib.baseboard_fab2(sch_1):page158_i131" )
				( pin "R1L43.1"
					( objectStatus "a" )
				)
				( pin "R1L43.2"
					( objectStatus "b" )
				)
			)
			( gate "DS9A7"
				( objectStatus "@baseboard_fab2_lib.baseboard_fab2(sch_1):page158_i134" )
				( pin "DS9A7.1"
					( objectStatus "a" )
				)
				( pin "DS9A7.2"
					( objectStatus "c" )
				)
			)
			( gate "R1L44"
				( objectStatus "@baseboard_fab2_lib.baseboard_fab2(sch_1):page158_i136" )
				( pin "R1L44.1"
					( objectStatus "a" )
				)
				( pin "R1L44.2"
					( objectStatus "b" )
				)
			)
			( gate "R8G3"
				( objectStatus "@baseboard_fab2_lib.baseboard_fab2(sch_1):page159_i210" )
				( pin "R8G3.1"
					( objectStatus "a" )
				)
				( pin "R8G3.2"
					( objectStatus "b" )
				)
			)
			( gate "R8G6"
				( objectStatus "@baseboard_fab2_lib.baseboard_fab2(sch_1):page159_i212" )
				( pin "R8G6.1"
					( objectStatus "a" )
				)
				( pin "R8G6.2"
					( objectStatus "b" )
				)
			)
			( gate "R2U5"
				( objectStatus "@baseboard_fab2_lib.baseboard_fab2(sch_1):page159_i214" )
				( pin "R2U5.1"
					( objectStatus "a" )
				)
				( pin "R2U5.2"
					( objectStatus "b" )
				)
			)
			( gate "R2U13"
				( objectStatus "@baseboard_fab2_lib.baseboard_fab2(sch_1):page159_i216" )
				( pin "R2U13.1"
					( objectStatus "a" )
				)
				( pin "R2U13.2"
					( objectStatus "b" )
				)
			)
			( gate "R2U1"
				( objectStatus "@baseboard_fab2_lib.baseboard_fab2(sch_1):page159_i218" )
				( pin "R2U1.1"
					( objectStatus "a" )
				)
				( pin "R2U1.2"
					( objectStatus "b" )
				)
			)
			( gate "R2T49"
				( objectStatus "@baseboard_fab2_lib.baseboard_fab2(sch_1):page159_i219" )
				( pin "R2T49.1"
					( objectStatus "a" )
				)
				( pin "R2T49.2"
					( objectStatus "b" )
				)
			)
			( gate "R2U7"
				( objectStatus "@baseboard_fab2_lib.baseboard_fab2(sch_1):page159_i220" )
				( pin "R2U7.1"
					( objectStatus "a" )
				)
				( pin "R2U7.2"
					( objectStatus "b" )
				)
			)
			( gate "R2U10"
				( objectStatus "@baseboard_fab2_lib.baseboard_fab2(sch_1):page159_i221" )
				( pin "R2U10.1"
					( objectStatus "a" )
				)
				( pin "R2U10.2"
					( objectStatus "b" )
				)
			)
			( gate "R1U11"
				( objectStatus "@baseboard_fab2_lib.baseboard_fab2(sch_1):page159_i222" )
				( pin "R1U11.1"
					( objectStatus "a" )
				)
				( pin "R1U11.2"
					( objectStatus "b" )
				)
			)
			( gate "R1U8"
				( objectStatus "@baseboard_fab2_lib.baseboard_fab2(sch_1):page159_i223" )
				( pin "R1U8.1"
					( objectStatus "a" )
				)
				( pin "R1U8.2"
					( objectStatus "b" )
				)
			)
			( gate "R9G12"
				( objectStatus "@baseboard_fab2_lib.baseboard_fab2(sch_1):page159_i224" )
				( pin "R9G12.1"
					( objectStatus "a" )
				)
				( pin "R9G12.2"
					( objectStatus "b" )
				)
			)
			( gate "R1U20"
				( objectStatus "@baseboard_fab2_lib.baseboard_fab2(sch_1):page159_i225" )
				( pin "R1U20.1"
					( objectStatus "a" )
				)
				( pin "R1U20.2"
					( objectStatus "b" )
				)
			)
			( gate "R1U19"
				( objectStatus "@baseboard_fab2_lib.baseboard_fab2(sch_1):page159_i226" )
				( pin "R1U19.1"
					( objectStatus "a" )
				)
				( pin "R1U19.2"
					( objectStatus "b" )
				)
			)
			( gate "R9G13"
				( objectStatus "@baseboard_fab2_lib.baseboard_fab2(sch_1):page159_i227" )
				( pin "R9G13.1"
					( objectStatus "a" )
				)
				( pin "R9G13.2"
					( objectStatus "b" )
				)
			)
			( gate "R8G5"
				( objectStatus "@baseboard_fab2_lib.baseboard_fab2(sch_1):page159_i228" )
				( pin "R8G5.1"
					( objectStatus "a" )
				)
				( pin "R8G5.2"
					( objectStatus "b" )
				)
			)
			( gate "R8G4"
				( objectStatus "@baseboard_fab2_lib.baseboard_fab2(sch_1):page159_i229" )
				( pin "R8G4.1"
					( objectStatus "a" )
				)
				( pin "R8G4.2"
					( objectStatus "b" )
				)
			)
			( gate "R2U34"
				( objectStatus "@baseboard_fab2_lib.baseboard_fab2(sch_1):page159_i230" )
				( pin "R2U34.1"
					( objectStatus "a" )
				)
				( pin "R2U34.2"
					( objectStatus "b" )
				)
			)
			( gate "R2U33"
				( objectStatus "@baseboard_fab2_lib.baseboard_fab2(sch_1):page159_i231" )
				( pin "R2U33.1"
					( objectStatus "a" )
				)
				( pin "R2U33.2"
					( objectStatus "b" )
				)
			)
			( gate "R1U9"
				( objectStatus "@baseboard_fab2_lib.baseboard_fab2(sch_1):page159_i232" )
				( pin "R1U9.1"
					( objectStatus "a" )
				)
				( pin "R1U9.2"
					( objectStatus "b" )
				)
			)
			( gate "R1U10"
				( objectStatus "@baseboard_fab2_lib.baseboard_fab2(sch_1):page159_i233" )
				( pin "R1U10.1"
					( objectStatus "a" )
				)
				( pin "R1U10.2"
					( objectStatus "b" )
				)
			)
			( gate "R1T8"
				( objectStatus "@baseboard_fab2_lib.baseboard_fab2(sch_1):page160_i4" )
				( pin "R1T8.1"
					( objectStatus "a" )
				)
				( pin "R1T8.2"
					( objectStatus "b" )
				)
			)
			( gate "R1T3"
				( objectStatus "@baseboard_fab2_lib.baseboard_fab2(sch_1):page160_i46" )
				( pin "R1T3.1"
					( objectStatus "a" )
				)
				( pin "R1T3.2"
					( objectStatus "b" )
				)
			)
			( gate "R1T2"
				( objectStatus "@baseboard_fab2_lib.baseboard_fab2(sch_1):page160_i49" )
				( pin "R1T2.1"
					( objectStatus "a" )
				)
				( pin "R1T2.2"
					( objectStatus "b" )
				)
			)
			( gate "R1T7"
				( objectStatus "@baseboard_fab2_lib.baseboard_fab2(sch_1):page160_i50" )
				( pin "R1T7.1"
					( objectStatus "a" )
				)
				( pin "R1T7.2"
					( objectStatus "b" )
				)
			)
			( gate "R9F23"
				( objectStatus "@baseboard_fab2_lib.baseboard_fab2(sch_1):page160_i51" )
				( pin "R9F23.1"
					( objectStatus "a" )
				)
				( pin "R9F23.2"
					( objectStatus "b" )
				)
			)
			( gate "R9F22"
				( objectStatus "@baseboard_fab2_lib.baseboard_fab2(sch_1):page160_i52" )
				( pin "R9F22.1"
					( objectStatus "a" )
				)
				( pin "R9F22.2"
					( objectStatus "b" )
				)
			)
			( gate "J1F2"
				( objectStatus "@baseboard_fab2_lib.baseboard_fab2(sch_1):page161_i1" )
				( pin "J1F2.1"
					( objectStatus "io1" )
				)
				( pin "J1F2.2"
					( objectStatus "io2" )
				)
				( pin "J1F2.3"
					( objectStatus "io3" )
				)
				( pin "J1F2.4"
					( objectStatus "io4" )
				)
				( pin "J1F2.5"
					( objectStatus "io5" )
				)
				( pin "J1F2.6"
					( objectStatus "io6" )
				)
			)
			( gate "C1E21"
				( objectStatus "@baseboard_fab2_lib.baseboard_fab2(sch_1):page161_i3" )
				( pin "C1E21.1"
					( objectStatus "a" )
				)
				( pin "C1E21.2"
					( objectStatus "b" )
				)
			)
			( gate "C1E20"
				( objectStatus "@baseboard_fab2_lib.baseboard_fab2(sch_1):page161_i4" )
				( pin "C1E20.1"
					( objectStatus "a" )
				)
				( pin "C1E20.2"
					( objectStatus "b" )
				)
			)
			( gate "C9M5"
				( objectStatus "@baseboard_fab2_lib.baseboard_fab2(sch_1):page161_i26" )
				( pin "C9M5.1"
					( objectStatus "a" )
				)
				( pin "C9M5.2"
					( objectStatus "b" )
				)
			)
			( gate "C9M4"
				( objectStatus "@baseboard_fab2_lib.baseboard_fab2(sch_1):page161_i27" )
				( pin "C9M4.1"
					( objectStatus "a" )
				)
				( pin "C9M4.2"
					( objectStatus "b" )
				)
			)
			( gate "J1B2"
				( objectStatus "@baseboard_fab2_lib.baseboard_fab2(sch_1):page161_i32" )
				( pin "J1B2.1"
					( objectStatus "io1" )
				)
				( pin "J1B2.2"
					( objectStatus "io2" )
				)
				( pin "J1B2.3"
					( objectStatus "io3" )
				)
				( pin "J1B2.4"
					( objectStatus "io4" )
				)
				( pin "J1B2.5"
					( objectStatus "io5" )
				)
				( pin "J1B2.6"
					( objectStatus "io6" )
				)
			)
			( gate "CR1F1"
				( objectStatus "@baseboard_fab2_lib.baseboard_fab2(sch_1):page161_i42" )
				( pin "CR1F1.2"
					( objectStatus "a" )
				)
				( pin "CR1F1.1"
					( objectStatus "c" )
				)
			)
			( gate "R1F2"
				( objectStatus "@baseboard_fab2_lib.baseboard_fab2(sch_1):page161_i43" )
				( pin "R1F2.1"
					( objectStatus "a" )
				)
				( pin "R1F2.2"
					( objectStatus "b" )
				)
			)
			( gate "R1F1"
				( objectStatus "@baseboard_fab2_lib.baseboard_fab2(sch_1):page161_i45" )
				( pin "R1F1.1"
					( objectStatus "a" )
				)
				( pin "R1F1.2"
					( objectStatus "b" )
				)
			)
			( gate "C1F9"
				( objectStatus "@baseboard_fab2_lib.baseboard_fab2(sch_1):page161_i46" )
				( pin "C1F9.1"
					( objectStatus "a" )
				)
				( pin "C1F9.2"
					( objectStatus "b" )
				)
			)
			( gate "CR1E1"
				( objectStatus "@baseboard_fab2_lib.baseboard_fab2(sch_1):page161_i50" )
				( pin "CR1E1.2"
					( objectStatus "a" )
				)
				( pin "CR1E1.1"
					( objectStatus "c" )
				)
			)
			( gate "R1E12"
				( objectStatus "@baseboard_fab2_lib.baseboard_fab2(sch_1):page161_i51" )
				( pin "R1E12.1"
					( objectStatus "a" )
				)
				( pin "R1E12.2"
					( objectStatus "b" )
				)
			)
			( gate "CR1B2"
				( objectStatus "@baseboard_fab2_lib.baseboard_fab2(sch_1):page161_i62" )
				( pin "CR1B2.2"
					( objectStatus "a" )
				)
				( pin "CR1B2.1"
					( objectStatus "c" )
				)
			)
			( gate "CR1B1"
				( objectStatus "@baseboard_fab2_lib.baseboard_fab2(sch_1):page161_i64" )
				( pin "CR1B1.2"
					( objectStatus "a" )
				)
				( pin "CR1B1.1"
					( objectStatus "c" )
				)
			)
			( gate "R7F33"
				( objectStatus "@baseboard_fab2_lib.baseboard_fab2(sch_1):page161_i65" )
				( pin "R7F33.1"
					( objectStatus "a" )
				)
				( pin "R7F33.2"
					( objectStatus "b" )
				)
			)
			( gate "R1B22"
				( objectStatus "@baseboard_fab2_lib.baseboard_fab2(sch_1):page161_i67" )
				( pin "R1B22.1"
					( objectStatus "a" )
				)
				( pin "R1B22.2"
					( objectStatus "b" )
				)
			)
			( gate "C1B15"
				( objectStatus "@baseboard_fab2_lib.baseboard_fab2(sch_1):page161_i68" )
				( pin "C1B15.1"
					( objectStatus "a" )
				)
				( pin "C1B15.2"
					( objectStatus "b" )
				)
			)
			( gate "R1B21"
				( objectStatus "@baseboard_fab2_lib.baseboard_fab2(sch_1):page161_i70" )
				( pin "R1B21.1"
					( objectStatus "a" )
				)
				( pin "R1B21.2"
					( objectStatus "b" )
				)
			)
			( gate "U8G2"
				( objectStatus "@baseboard_fab2_lib.baseboard_fab2(sch_1):page161_i88" )
				( pin "U8G2.2"
					( objectStatus "a" )
				)
				( pin "U8G2.4"
					( objectStatus "y" )
				)
			)
			( gate "C2U27"
				( objectStatus "@baseboard_fab2_lib.baseboard_fab2(sch_1):page161_i90" )
				( pin "C2U27.1"
					( objectStatus "a" )
				)
				( pin "C2U27.2"
					( objectStatus "b" )
				)
			)
			( gate "U8G3"
				( objectStatus "@baseboard_fab2_lib.baseboard_fab2(sch_1):page161_i92" )
				( pin "U8G3.2"
					( objectStatus "a" )
				)
				( pin "U8G3.4"
					( objectStatus "y" )
				)
			)
			( gate "C2U28"
				( objectStatus "@baseboard_fab2_lib.baseboard_fab2(sch_1):page161_i93" )
				( pin "C2U28.1"
					( objectStatus "a" )
				)
				( pin "C2U28.2"
					( objectStatus "b" )
				)
			)
			( gate "R2U42"
				( objectStatus "@baseboard_fab2_lib.baseboard_fab2(sch_1):page161_i99" )
				( pin "R2U42.1"
					( objectStatus "a" )
				)
				( pin "R2U42.2"
					( objectStatus "b" )
				)
			)
			( gate "R2U44"
				( objectStatus "@baseboard_fab2_lib.baseboard_fab2(sch_1):page161_i102" )
				( pin "R2U44.1"
					( objectStatus "a" )
				)
				( pin "R2U44.2"
					( objectStatus "b" )
				)
			)
			( gate "C1E22"
				( objectStatus "@baseboard_fab2_lib.baseboard_fab2(sch_1):page161_i113" )
				( pin "C1E22.1"
					( objectStatus "a" )
				)
				( pin "C1E22.2"
					( objectStatus "b" )
				)
			)
			( gate "R1E11"
				( objectStatus "@baseboard_fab2_lib.baseboard_fab2(sch_1):page161_i120" )
				( pin "R1E11.1"
					( objectStatus "a" )
				)
				( pin "R1E11.2"
					( objectStatus "b" )
				)
			)
			( gate "U1E2"
				( objectStatus "@baseboard_fab2_lib.baseboard_fab2(sch_1):page161_i121" )
				( pin "U1E2.1"
					( objectStatus "a(0)" )
				)
				( pin "U1E2.2"
					( objectStatus "b(0)" )
				)
				( pin "U1E2.4"
					( objectStatus "y(0)" )
				)
			)
			( gate "CR1B3"
				( objectStatus "@baseboard_fab2_lib.baseboard_fab2(sch_1):page161_i123" )
				( pin "CR1B3.2"
					( objectStatus "a" )
				)
				( pin "CR1B3.1"
					( objectStatus "c" )
				)
			)
			( gate "R1B23"
				( objectStatus "@baseboard_fab2_lib.baseboard_fab2(sch_1):page161_i124" )
				( pin "R1B23.1"
					( objectStatus "a" )
				)
				( pin "R1B23.2"
					( objectStatus "b" )
				)
			)
			( gate "R1B24"
				( objectStatus "@baseboard_fab2_lib.baseboard_fab2(sch_1):page161_i126" )
				( pin "R1B24.1"
					( objectStatus "a" )
				)
				( pin "R1B24.2"
					( objectStatus "b" )
				)
			)
			( gate "C1B17"
				( objectStatus "@baseboard_fab2_lib.baseboard_fab2(sch_1):page161_i128" )
				( pin "C1B17.1"
					( objectStatus "a" )
				)
				( pin "C1B17.2"
					( objectStatus "b" )
				)
			)
			( gate "CR1F2"
				( objectStatus "@baseboard_fab2_lib.baseboard_fab2(sch_1):page161_i133" )
				( pin "CR1F2.2"
					( objectStatus "a" )
				)
				( pin "CR1F2.1"
					( objectStatus "c" )
				)
			)
			( gate "R9T7"
				( objectStatus "@baseboard_fab2_lib.baseboard_fab2(sch_1):page161_i134" )
				( pin "R9T7.1"
					( objectStatus "a" )
				)
				( pin "R9T7.2"
					( objectStatus "b" )
				)
			)
			( gate "R9T5"
				( objectStatus "@baseboard_fab2_lib.baseboard_fab2(sch_1):page161_i135" )
				( pin "R9T5.1"
					( objectStatus "a" )
				)
				( pin "R9T5.2"
					( objectStatus "b" )
				)
			)
			( gate "C9T1"
				( objectStatus "@baseboard_fab2_lib.baseboard_fab2(sch_1):page161_i137" )
				( pin "C9T1.1"
					( objectStatus "a" )
				)
				( pin "C9T1.2"
					( objectStatus "b" )
				)
			)
			( gate "R8F16"
				( objectStatus "@baseboard_fab2_lib.baseboard_fab2(sch_1):page162_i8" )
				( pin "R8F16.1"
					( objectStatus "a" )
				)
				( pin "R8F16.2"
					( objectStatus "b" )
				)
			)
			( gate "R8F14"
				( objectStatus "@baseboard_fab2_lib.baseboard_fab2(sch_1):page162_i9" )
				( pin "R8F14.1"
					( objectStatus "a" )
				)
				( pin "R8F14.2"
					( objectStatus "b" )
				)
			)
			( gate "R8F12"
				( objectStatus "@baseboard_fab2_lib.baseboard_fab2(sch_1):page162_i13" )
				( pin "R8F12.1"
					( objectStatus "a" )
				)
				( pin "R8F12.2"
					( objectStatus "b" )
				)
			)
			( gate "R8F34"
				( objectStatus "@baseboard_fab2_lib.baseboard_fab2(sch_1):page162_i22" )
				( pin "R8F34.1"
					( objectStatus "a" )
				)
				( pin "R8F34.2"
					( objectStatus "b" )
				)
			)
			( gate "R8F13"
				( objectStatus "@baseboard_fab2_lib.baseboard_fab2(sch_1):page162_i23" )
				( pin "R8F13.1"
					( objectStatus "a" )
				)
				( pin "R8F13.2"
					( objectStatus "b" )
				)
			)
			( gate "R8F35"
				( objectStatus "@baseboard_fab2_lib.baseboard_fab2(sch_1):page162_i24" )
				( pin "R8F35.1"
					( objectStatus "a" )
				)
				( pin "R8F35.2"
					( objectStatus "b" )
				)
			)
			( gate "C8F5"
				( objectStatus "@baseboard_fab2_lib.baseboard_fab2(sch_1):page162_i28" )
				( pin "C8F5.1"
					( objectStatus "a" )
				)
				( pin "C8F5.2"
					( objectStatus "b" )
				)
			)
			( gate "C8F4"
				( objectStatus "@baseboard_fab2_lib.baseboard_fab2(sch_1):page162_i30" )
				( pin "C8F4.1"
					( objectStatus "a" )
				)
				( pin "C8F4.2"
					( objectStatus "b" )
				)
			)
			( gate "U8F2"
				( objectStatus "@baseboard_fab2_lib.baseboard_fab2(sch_1):page162_i32" )
				( pin "U8F2.16"
					( objectStatus "clk" )
				)
				( pin "U8F2.7"
					( objectStatus "cs_n" )
				)
				( pin "U8F2.15"
					( objectStatus "di_io(0)" )
				)
				( pin "U8F2.8"
					( objectStatus "do_io(1)" )
				)
				( pin "U8F2.10"
					( objectStatus "gnd" )
				)
				( pin "U8F2.1"
					( objectStatus "hold_n_io(3)" )
				)
				( pin "U8F2.4"
					( objectStatus "nc(0)" )
				)
				( pin "U8F2.5"
					( objectStatus "nc(1)" )
				)
				( pin "U8F2.6"
					( objectStatus "nc(2)" )
				)
				( pin "U8F2.11"
					( objectStatus "nc(3)" )
				)
				( pin "U8F2.12"
					( objectStatus "nc(4)" )
				)
				( pin "U8F2.13"
					( objectStatus "nc(5)" )
				)
				( pin "U8F2.14"
					( objectStatus "nc(6)" )
				)
				( pin "U8F2.3"
					( objectStatus "reset_n" )
				)
				( pin "U8F2.2"
					( objectStatus "vcc" )
				)
				( pin "U8F2.9"
					( objectStatus "wp_n_io(2)" )
				)
			)
			( gate "U1B2"
				( objectStatus "@baseboard_fab2_lib.baseboard_fab2(sch_1):page163_i1" )
				( pin "U1B2.5"
					( objectStatus "en" )
				)
				( pin "U1B2.2"
					( objectStatus "scla" )
				)
				( pin "U1B2.7"
					( objectStatus "sclb" )
				)
				( pin "U1B2.3"
					( objectStatus "sdaa" )
				)
				( pin "U1B2.6"
					( objectStatus "sdab" )
				)
				( pin "U1B2.1"
					( objectStatus "vcca" )
				)
				( pin "U1B2.8"
					( objectStatus "vccb" )
				)
			)
			( gate "R6N8"
				( objectStatus "@baseboard_fab2_lib.baseboard_fab2(sch_1):page163_i2" )
				( pin "R6N8.1"
					( objectStatus "a" )
				)
				( pin "R6N8.2"
					( objectStatus "b" )
				)
			)
			( gate "R6N9"
				( objectStatus "@baseboard_fab2_lib.baseboard_fab2(sch_1):page163_i3" )
				( pin "R6N9.1"
					( objectStatus "a" )
				)
				( pin "R6N9.2"
					( objectStatus "b" )
				)
			)
			( gate "R9M18"
				( objectStatus "@baseboard_fab2_lib.baseboard_fab2(sch_1):page163_i6" )
				( pin "R9M18.1"
					( objectStatus "a" )
				)
				( pin "R9M18.2"
					( objectStatus "b" )
				)
			)
			( gate "R9M19"
				( objectStatus "@baseboard_fab2_lib.baseboard_fab2(sch_1):page163_i7" )
				( pin "R9M19.1"
					( objectStatus "a" )
				)
				( pin "R9M19.2"
					( objectStatus "b" )
				)
			)
			( gate "C9M8"
				( objectStatus "@baseboard_fab2_lib.baseboard_fab2(sch_1):page163_i10" )
				( pin "C9M8.1"
					( objectStatus "a" )
				)
				( pin "C9M8.2"
					( objectStatus "b" )
				)
			)
			( gate "C9M7"
				( objectStatus "@baseboard_fab2_lib.baseboard_fab2(sch_1):page163_i12" )
				( pin "C9M7.1"
					( objectStatus "a" )
				)
				( pin "C9M7.2"
					( objectStatus "b" )
				)
			)
			( gate "R9M17"
				( objectStatus "@baseboard_fab2_lib.baseboard_fab2(sch_1):page163_i15" )
				( pin "R9M17.1"
					( objectStatus "a" )
				)
				( pin "R9M17.2"
					( objectStatus "b" )
				)
			)
			( gate "R9M16"
				( objectStatus "@baseboard_fab2_lib.baseboard_fab2(sch_1):page163_i16" )
				( pin "R9M16.1"
					( objectStatus "a" )
				)
				( pin "R9M16.2"
					( objectStatus "b" )
				)
			)
			( gate "R9M14"
				( objectStatus "@baseboard_fab2_lib.baseboard_fab2(sch_1):page163_i20" )
				( pin "R9M14.1"
					( objectStatus "a" )
				)
				( pin "R9M14.2"
					( objectStatus "b" )
				)
			)
			( gate "R9M13"
				( objectStatus "@baseboard_fab2_lib.baseboard_fab2(sch_1):page163_i21" )
				( pin "R9M13.1"
					( objectStatus "a" )
				)
				( pin "R9M13.2"
					( objectStatus "b" )
				)
			)
			( gate "R9M12"
				( objectStatus "@baseboard_fab2_lib.baseboard_fab2(sch_1):page163_i24" )
				( pin "R9M12.1"
					( objectStatus "a" )
				)
				( pin "R9M12.2"
					( objectStatus "b" )
				)
			)
			( gate "R9M15"
				( objectStatus "@baseboard_fab2_lib.baseboard_fab2(sch_1):page163_i25" )
				( pin "R9M15.1"
					( objectStatus "a" )
				)
				( pin "R9M15.2"
					( objectStatus "b" )
				)
			)
			( gate "R1T10"
				( objectStatus "@baseboard_fab2_lib.baseboard_fab2(sch_1):page164_i5" )
				( pin "R1T10.1"
					( objectStatus "a" )
				)
				( pin "R1T10.2"
					( objectStatus "b" )
				)
			)
			( gate "R1T12"
				( objectStatus "@baseboard_fab2_lib.baseboard_fab2(sch_1):page164_i6" )
				( pin "R1T12.1"
					( objectStatus "a" )
				)
				( pin "R1T12.2"
					( objectStatus "b" )
				)
			)
			( gate "R1T11"
				( objectStatus "@baseboard_fab2_lib.baseboard_fab2(sch_1):page164_i7" )
				( pin "R1T11.1"
					( objectStatus "a" )
				)
				( pin "R1T11.2"
					( objectStatus "b" )
				)
			)
			( gate "R1T5"
				( objectStatus "@baseboard_fab2_lib.baseboard_fab2(sch_1):page164_i11" )
				( pin "R1T5.1"
					( objectStatus "a" )
				)
				( pin "R1T5.2"
					( objectStatus "b" )
				)
			)
			( gate "R1T6"
				( objectStatus "@baseboard_fab2_lib.baseboard_fab2(sch_1):page164_i13" )
				( pin "R1T6.1"
					( objectStatus "a" )
				)
				( pin "R1T6.2"
					( objectStatus "b" )
				)
			)
			( gate "R1T4"
				( objectStatus "@baseboard_fab2_lib.baseboard_fab2(sch_1):page164_i14" )
				( pin "R1T4.1"
					( objectStatus "a" )
				)
				( pin "R1T4.2"
					( objectStatus "b" )
				)
			)
			( gate "R1U18"
				( objectStatus "@baseboard_fab2_lib.baseboard_fab2(sch_1):page164_i19" )
				( pin "R1U18.1"
					( objectStatus "a" )
				)
				( pin "R1U18.2"
					( objectStatus "b" )
				)
			)
			( gate "R1U16"
				( objectStatus "@baseboard_fab2_lib.baseboard_fab2(sch_1):page164_i20" )
				( pin "R1U16.1"
					( objectStatus "a" )
				)
				( pin "R1U16.2"
					( objectStatus "b" )
				)
			)
			( gate "R1U17"
				( objectStatus "@baseboard_fab2_lib.baseboard_fab2(sch_1):page164_i21" )
				( pin "R1U17.1"
					( objectStatus "a" )
				)
				( pin "R1U17.2"
					( objectStatus "b" )
				)
			)
			( gate "R1U15"
				( objectStatus "@baseboard_fab2_lib.baseboard_fab2(sch_1):page164_i22" )
				( pin "R1U15.1"
					( objectStatus "a" )
				)
				( pin "R1U15.2"
					( objectStatus "b" )
				)
			)
			( gate "R1U21"
				( objectStatus "@baseboard_fab2_lib.baseboard_fab2(sch_1):page164_i24" )
				( pin "R1U21.1"
					( objectStatus "a" )
				)
				( pin "R1U21.2"
					( objectStatus "b" )
				)
			)
			( gate "R1U24"
				( objectStatus "@baseboard_fab2_lib.baseboard_fab2(sch_1):page164_i25" )
				( pin "R1U24.1"
					( objectStatus "a" )
				)
				( pin "R1U24.2"
					( objectStatus "b" )
				)
			)
			( gate "R1U22"
				( objectStatus "@baseboard_fab2_lib.baseboard_fab2(sch_1):page164_i27" )
				( pin "R1U22.1"
					( objectStatus "a" )
				)
				( pin "R1U22.2"
					( objectStatus "b" )
				)
			)
			( gate "R1U23"
				( objectStatus "@baseboard_fab2_lib.baseboard_fab2(sch_1):page164_i28" )
				( pin "R1U23.1"
					( objectStatus "a" )
				)
				( pin "R1U23.2"
					( objectStatus "b" )
				)
			)
			( gate "R2N17"
				( objectStatus "@baseboard_fab2_lib.baseboard_fab2(sch_1):page164_i29" )
				( pin "R2N17.1"
					( objectStatus "a" )
				)
				( pin "R2N17.2"
					( objectStatus "b" )
				)
			)
			( gate "R2N18"
				( objectStatus "@baseboard_fab2_lib.baseboard_fab2(sch_1):page164_i32" )
				( pin "R2N18.1"
					( objectStatus "a" )
				)
				( pin "R2N18.2"
					( objectStatus "b" )
				)
			)
			( gate "EU9G1"
				( objectStatus "@baseboard_fab2_lib.baseboard_fab2(sch_1):page165_i52" )
				( pin "EU9G1.7"
					( objectStatus "a0" )
				)
				( pin "EU9G1.8"
					( objectStatus "a1" )
				)
				( pin "EU9G1.4"
					( objectStatus "gnd" )
				)
				( pin "EU9G1.16"
					( objectStatus "in0" )
				)
				( pin "EU9G1.15"
					( objectStatus "in1" )
				)
				( pin "EU9G1.14"
					( objectStatus "in2" )
				)
				( pin "EU9G1.13"
					( objectStatus "in3" )
				)
				( pin "EU9G1.12"
					( objectStatus "in4" )
				)
				( pin "EU9G1.11"
					( objectStatus "in5" )
				)
				( pin "EU9G1.10"
					( objectStatus "in6" )
				)
				( pin "EU9G1.9"
					( objectStatus "in7" )
				)
				( pin "EU9G1.6"
					( objectStatus "int_n" )
				)
				( pin "EU9G1.3"
					( objectStatus "scl" )
				)
				( pin "EU9G1.2"
					( objectStatus "sda" )
				)
				( pin "EU9G1.5"
					( objectStatus "vp" )
				)
				( pin "EU9G1.1"
					( objectStatus "vref" )
				)
			)
			( gate "R1U45"
				( objectStatus "@baseboard_fab2_lib.baseboard_fab2(sch_1):page165_i55" )
				( pin "R1U45.1"
					( objectStatus "a" )
				)
				( pin "R1U45.2"
					( objectStatus "b" )
				)
			)
			( gate "R1U48"
				( objectStatus "@baseboard_fab2_lib.baseboard_fab2(sch_1):page165_i56" )
				( pin "R1U48.1"
					( objectStatus "a" )
				)
				( pin "R1U48.2"
					( objectStatus "b" )
				)
			)
			( gate "R9G23"
				( objectStatus "@baseboard_fab2_lib.baseboard_fab2(sch_1):page165_i57" )
				( pin "R9G23.1"
					( objectStatus "a" )
				)
				( pin "R9G23.2"
					( objectStatus "b" )
				)
			)
			( gate "R9G25"
				( objectStatus "@baseboard_fab2_lib.baseboard_fab2(sch_1):page165_i58" )
				( pin "R9G25.1"
					( objectStatus "a" )
				)
				( pin "R9G25.2"
					( objectStatus "b" )
				)
			)
			( gate "C9G19"
				( objectStatus "@baseboard_fab2_lib.baseboard_fab2(sch_1):page165_i61" )
				( pin "C9G19.1"
					( objectStatus "a" )
				)
				( pin "C9G19.2"
					( objectStatus "b" )
				)
			)
			( gate "C1U20"
				( objectStatus "@baseboard_fab2_lib.baseboard_fab2(sch_1):page165_i67" )
				( pin "C1U20.1"
					( objectStatus "a" )
				)
				( pin "C1U20.2"
					( objectStatus "b" )
				)
			)
			( gate "R9G21"
				( objectStatus "@baseboard_fab2_lib.baseboard_fab2(sch_1):page165_i69" )
				( pin "R9G21.1"
					( objectStatus "a" )
				)
				( pin "R9G21.2"
					( objectStatus "b" )
				)
			)
			( gate "FB1U2"
				( objectStatus "@baseboard_fab2_lib.baseboard_fab2(sch_1):page165_i79" )
				( pin "FB1U2.1"
					( objectStatus "a" )
				)
				( pin "FB1U2.2"
					( objectStatus "b" )
				)
			)
			( gate "R1U40"
				( objectStatus "@baseboard_fab2_lib.baseboard_fab2(sch_1):page165_i81" )
				( pin "R1U40.1"
					( objectStatus "a" )
				)
				( pin "R1U40.2"
					( objectStatus "b" )
				)
			)
			( gate "R7C18"
				( objectStatus "@baseboard_fab2_lib.baseboard_fab2(sch_1):page166_i11" )
				( pin "R7C18.1"
					( objectStatus "a" )
				)
				( pin "R7C18.2"
					( objectStatus "b" )
				)
			)
			( gate "R7C22"
				( objectStatus "@baseboard_fab2_lib.baseboard_fab2(sch_1):page166_i14" )
				( pin "R7C22.1"
					( objectStatus "a" )
				)
				( pin "R7C22.2"
					( objectStatus "b" )
				)
			)
			( gate "R7C19"
				( objectStatus "@baseboard_fab2_lib.baseboard_fab2(sch_1):page166_i15" )
				( pin "R7C19.1"
					( objectStatus "a" )
				)
				( pin "R7C19.2"
					( objectStatus "b" )
				)
			)
			( gate "R7C17"
				( objectStatus "@baseboard_fab2_lib.baseboard_fab2(sch_1):page166_i28" )
				( pin "R7C17.1"
					( objectStatus "a" )
				)
				( pin "R7C17.2"
					( objectStatus "b" )
				)
			)
			( gate "R7D15"
				( objectStatus "@baseboard_fab2_lib.baseboard_fab2(sch_1):page166_i32" )
				( pin "R7D15.1"
					( objectStatus "a" )
				)
				( pin "R7D15.2"
					( objectStatus "b" )
				)
			)
			( gate "U9B4"
				( objectStatus "@baseboard_fab2_lib.baseboard_fab2(sch_1):page167_i1" )
				( pin "U9B4.4"
					( objectStatus "a(0)" )
				)
				( pin "U9B4.3"
					( objectStatus "a(1)" )
				)
				( pin "U9B4.2"
					( objectStatus "dxn" )
				)
				( pin "U9B4.1"
					( objectStatus "dxp" )
				)
				( pin "U9B4.5"
					( objectStatus "gnd" )
				)
				( pin "U9B4.7"
					( objectStatus "scl" )
				)
				( pin "U9B4.6"
					( objectStatus "sda" )
				)
				( pin "U9B4.8"
					( objectStatus "vp" )
				)
			)
			( gate "Q9B1"
				( objectStatus "@baseboard_fab2_lib.baseboard_fab2(sch_1):page167_i3" )
				( pin "Q9B1.1"
					( objectStatus "b" )
				)
				( pin "Q9B1.3"
					( objectStatus "c" )
				)
				( pin "Q9B1.2"
					( objectStatus "e" )
				)
			)
			( gate "R9B5"
				( objectStatus "@baseboard_fab2_lib.baseboard_fab2(sch_1):page167_i5" )
				( pin "R9B5.1"
					( objectStatus "a" )
				)
				( pin "R9B5.2"
					( objectStatus "b" )
				)
			)
			( gate "R9B4"
				( objectStatus "@baseboard_fab2_lib.baseboard_fab2(sch_1):page167_i6" )
				( pin "R9B4.1"
					( objectStatus "a" )
				)
				( pin "R9B4.2"
					( objectStatus "b" )
				)
			)
			( gate "C1M4"
				( objectStatus "@baseboard_fab2_lib.baseboard_fab2(sch_1):page167_i7" )
				( pin "C1M4.1"
					( objectStatus "a" )
				)
				( pin "C1M4.2"
					( objectStatus "b" )
				)
			)
			( gate "R1M9"
				( objectStatus "@baseboard_fab2_lib.baseboard_fab2(sch_1):page167_i8" )
				( pin "R1M9.1"
					( objectStatus "a" )
				)
				( pin "R1M9.2"
					( objectStatus "b" )
				)
			)
			( gate "R9B8"
				( objectStatus "@baseboard_fab2_lib.baseboard_fab2(sch_1):page167_i10" )
				( pin "R9B8.1"
					( objectStatus "a" )
				)
				( pin "R9B8.2"
					( objectStatus "b" )
				)
			)
			( gate "C1E19"
				( objectStatus "@baseboard_fab2_lib.baseboard_fab2(sch_1):page167_i24" )
				( pin "C1E19.1"
					( objectStatus "a" )
				)
				( pin "C1E19.2"
					( objectStatus "b" )
				)
			)
			( gate "R9R5"
				( objectStatus "@baseboard_fab2_lib.baseboard_fab2(sch_1):page167_i25" )
				( pin "R9R5.1"
					( objectStatus "a" )
				)
				( pin "R9R5.2"
					( objectStatus "b" )
				)
			)
			( gate "R9R6"
				( objectStatus "@baseboard_fab2_lib.baseboard_fab2(sch_1):page167_i26" )
				( pin "R9R6.1"
					( objectStatus "a" )
				)
				( pin "R9R6.2"
					( objectStatus "b" )
				)
			)
			( gate "Q1E1"
				( objectStatus "@baseboard_fab2_lib.baseboard_fab2(sch_1):page167_i27" )
				( pin "Q1E1.1"
					( objectStatus "b" )
				)
				( pin "Q1E1.3"
					( objectStatus "c" )
				)
				( pin "Q1E1.2"
					( objectStatus "e" )
				)
			)
			( gate "U1E1"
				( objectStatus "@baseboard_fab2_lib.baseboard_fab2(sch_1):page167_i30" )
				( pin "U1E1.4"
					( objectStatus "a(0)" )
				)
				( pin "U1E1.3"
					( objectStatus "a(1)" )
				)
				( pin "U1E1.2"
					( objectStatus "dxn" )
				)
				( pin "U1E1.1"
					( objectStatus "dxp" )
				)
				( pin "U1E1.5"
					( objectStatus "gnd" )
				)
				( pin "U1E1.7"
					( objectStatus "scl" )
				)
				( pin "U1E1.6"
					( objectStatus "sda" )
				)
				( pin "U1E1.8"
					( objectStatus "vp" )
				)
			)
			( gate "R1E9"
				( objectStatus "@baseboard_fab2_lib.baseboard_fab2(sch_1):page167_i34" )
				( pin "R1E9.1"
					( objectStatus "a" )
				)
				( pin "R1E9.2"
					( objectStatus "b" )
				)
			)
			( gate "R9B6"
				( objectStatus "@baseboard_fab2_lib.baseboard_fab2(sch_1):page167_i35" )
				( pin "R9B6.1"
					( objectStatus "a" )
				)
				( pin "R9B6.2"
					( objectStatus "b" )
				)
			)
			( gate "R1E10"
				( objectStatus "@baseboard_fab2_lib.baseboard_fab2(sch_1):page167_i38" )
				( pin "R1E10.1"
					( objectStatus "a" )
				)
				( pin "R1E10.2"
					( objectStatus "b" )
				)
			)
			( gate "C9B7"
				( objectStatus "@baseboard_fab2_lib.baseboard_fab2(sch_1):page167_i39" )
				( pin "C9B7.1"
					( objectStatus "a" )
				)
				( pin "C9B7.2"
					( objectStatus "b" )
				)
			)
			( gate "C9R14"
				( objectStatus "@baseboard_fab2_lib.baseboard_fab2(sch_1):page167_i41" )
				( pin "C9R14.1"
					( objectStatus "a" )
				)
				( pin "C9R14.2"
					( objectStatus "b" )
				)
			)
			( gate "C9R13"
				( objectStatus "@baseboard_fab2_lib.baseboard_fab2(sch_1):page167_i42" )
				( pin "C9R13.1"
					( objectStatus "a" )
				)
				( pin "C9R13.2"
					( objectStatus "b" )
				)
			)
			( gate "U8D4"
				( objectStatus "@baseboard_fab2_lib.baseboard_fab2(sch_1):page167_i49" )
				( pin "U8D4.1"
					( objectStatus "a0" )
				)
				( pin "U8D4.2"
					( objectStatus "a1" )
				)
				( pin "U8D4.3"
					( objectStatus "a2" )
				)
				( pin "U8D4.6"
					( objectStatus "scl" )
				)
				( pin "U8D4.5"
					( objectStatus "sda" )
				)
				( pin "U8D4.7"
					( objectStatus "wp" )
				)
			)
			( gate "R8D27"
				( objectStatus "@baseboard_fab2_lib.baseboard_fab2(sch_1):page167_i50" )
				( pin "R8D27.1"
					( objectStatus "a" )
				)
				( pin "R8D27.2"
					( objectStatus "b" )
				)
			)
			( gate "R9G15"
				( objectStatus "@baseboard_fab2_lib.baseboard_fab2(sch_1):page167_i58" )
				( pin "R9G15.1"
					( objectStatus "a" )
				)
				( pin "R9G15.2"
					( objectStatus "b" )
				)
			)
			( gate "R8D28"
				( objectStatus "@baseboard_fab2_lib.baseboard_fab2(sch_1):page167_i70" )
				( pin "R8D28.1"
					( objectStatus "a" )
				)
				( pin "R8D28.2"
					( objectStatus "b" )
				)
			)
			( gate "R1M8"
				( objectStatus "@baseboard_fab2_lib.baseboard_fab2(sch_1):page167_i74" )
				( pin "R1M8.1"
					( objectStatus "a" )
				)
				( pin "R1M8.2"
					( objectStatus "b" )
				)
			)
			( gate "R9R7"
				( objectStatus "@baseboard_fab2_lib.baseboard_fab2(sch_1):page167_i75" )
				( pin "R9R7.1"
					( objectStatus "a" )
				)
				( pin "R9R7.2"
					( objectStatus "b" )
				)
			)
			( gate "R9R8"
				( objectStatus "@baseboard_fab2_lib.baseboard_fab2(sch_1):page167_i76" )
				( pin "R9R8.1"
					( objectStatus "a" )
				)
				( pin "R9R8.2"
					( objectStatus "b" )
				)
			)
			( gate "R9G14"
				( objectStatus "@baseboard_fab2_lib.baseboard_fab2(sch_1):page167_i77" )
				( pin "R9G14.1"
					( objectStatus "a" )
				)
				( pin "R9G14.2"
					( objectStatus "b" )
				)
			)
			( gate "R1U31"
				( objectStatus "@baseboard_fab2_lib.baseboard_fab2(sch_1):page167_i78" )
				( pin "R1U31.1"
					( objectStatus "a" )
				)
				( pin "R1U31.2"
					( objectStatus "b" )
				)
			)
			( gate "R1U25"
				( objectStatus "@baseboard_fab2_lib.baseboard_fab2(sch_1):page167_i79" )
				( pin "R1U25.1"
					( objectStatus "a" )
				)
				( pin "R1U25.2"
					( objectStatus "b" )
				)
			)
			( gate "R2U38"
				( objectStatus "@baseboard_fab2_lib.baseboard_fab2(sch_1):page167_i80" )
				( pin "R2U38.1"
					( objectStatus "a" )
				)
				( pin "R2U38.2"
					( objectStatus "b" )
				)
			)
			( gate "R2U39"
				( objectStatus "@baseboard_fab2_lib.baseboard_fab2(sch_1):page167_i83" )
				( pin "R2U39.1"
					( objectStatus "a" )
				)
				( pin "R2U39.2"
					( objectStatus "b" )
				)
			)
			( gate "R8D24"
				( objectStatus "@baseboard_fab2_lib.baseboard_fab2(sch_1):page167_i84" )
				( pin "R8D24.1"
					( objectStatus "a" )
				)
				( pin "R8D24.2"
					( objectStatus "b" )
				)
			)
			( gate "R8D23"
				( objectStatus "@baseboard_fab2_lib.baseboard_fab2(sch_1):page167_i85" )
				( pin "R8D23.1"
					( objectStatus "a" )
				)
				( pin "R8D23.2"
					( objectStatus "b" )
				)
			)
			( gate "CR1L1"
				( objectStatus "@baseboard_fab2_lib.baseboard_fab2(sch_1):page168_i2" )
				( pin "CR1L1.2"
					( objectStatus "a" )
				)
				( pin "CR1L1.1"
					( objectStatus "c" )
				)
			)
			( gate "CR1L2"
				( objectStatus "@baseboard_fab2_lib.baseboard_fab2(sch_1):page168_i3" )
				( pin "CR1L2.2"
					( objectStatus "a" )
				)
				( pin "CR1L2.1"
					( objectStatus "c" )
				)
			)
			( gate "CR1L3"
				( objectStatus "@baseboard_fab2_lib.baseboard_fab2(sch_1):page168_i4" )
				( pin "CR1L3.2"
					( objectStatus "a" )
				)
				( pin "CR1L3.1"
					( objectStatus "c" )
				)
			)
			( gate "CR1L4"
				( objectStatus "@baseboard_fab2_lib.baseboard_fab2(sch_1):page168_i5" )
				( pin "CR1L4.2"
					( objectStatus "a" )
				)
				( pin "CR1L4.1"
					( objectStatus "c" )
				)
			)
			( gate "R1L6"
				( objectStatus "@baseboard_fab2_lib.baseboard_fab2(sch_1):page168_i6" )
				( pin "R1L6.1"
					( objectStatus "a" )
				)
				( pin "R1L6.2"
					( objectStatus "b" )
				)
			)
			( gate "R1L4"
				( objectStatus "@baseboard_fab2_lib.baseboard_fab2(sch_1):page168_i7" )
				( pin "R1L4.1"
					( objectStatus "a" )
				)
				( pin "R1L4.2"
					( objectStatus "b" )
				)
			)
			( gate "Q1L3"
				( objectStatus "@baseboard_fab2_lib.baseboard_fab2(sch_1):page168_i8" )
				( pin "Q1L3.1"
					( objectStatus "b" )
				)
				( pin "Q1L3.3"
					( objectStatus "c" )
				)
				( pin "Q1L3.2"
					( objectStatus "e" )
				)
			)
			( gate "Q1L1"
				( objectStatus "@baseboard_fab2_lib.baseboard_fab2(sch_1):page168_i9" )
				( pin "Q1L1.1"
					( objectStatus "b" )
				)
				( pin "Q1L1.3"
					( objectStatus "c" )
				)
				( pin "Q1L1.2"
					( objectStatus "e" )
				)
			)
			( gate "R1L5"
				( objectStatus "@baseboard_fab2_lib.baseboard_fab2(sch_1):page168_i10" )
				( pin "R1L5.1"
					( objectStatus "a" )
				)
				( pin "R1L5.2"
					( objectStatus "b" )
				)
			)
			( gate "R1L36"
				( objectStatus "@baseboard_fab2_lib.baseboard_fab2(sch_1):page168_i11" )
				( pin "R1L36.1"
					( objectStatus "a" )
				)
				( pin "R1L36.2"
					( objectStatus "b" )
				)
			)
			( gate "Q1L4"
				( objectStatus "@baseboard_fab2_lib.baseboard_fab2(sch_1):page168_i18" )
				( pin "Q1L4.3"
					( objectStatus "drain(0)" )
				)
				( pin "Q1L4.5"
					( objectStatus "gate(0)" )
				)
				( pin "Q1L4.4"
					( objectStatus "source(0)" )
				)
			)
			( gate "Q1L4"
				( objectStatus "@baseboard_fab2_lib.baseboard_fab2(sch_1):page168_i19" )
				( pin "Q1L4.6"
					( objectStatus "drain(0)" )
				)
				( pin "Q1L4.2"
					( objectStatus "gate(0)" )
				)
				( pin "Q1L4.1"
					( objectStatus "source(0)" )
				)
			)
			( gate "R1L38"
				( objectStatus "@baseboard_fab2_lib.baseboard_fab2(sch_1):page168_i22" )
				( pin "R1L38.1"
					( objectStatus "a" )
				)
				( pin "R1L38.2"
					( objectStatus "b" )
				)
			)
			( gate "C1U21"
				( objectStatus "@baseboard_fab2_lib.baseboard_fab2(sch_1):page169_i56" )
				( pin "C1U21.1"
					( objectStatus "a" )
				)
				( pin "C1U21.2"
					( objectStatus "b" )
				)
			)
			( gate "FB1U3"
				( objectStatus "@baseboard_fab2_lib.baseboard_fab2(sch_1):page169_i57" )
				( pin "FB1U3.1"
					( objectStatus "a" )
				)
				( pin "FB1U3.2"
					( objectStatus "b" )
				)
			)
			( gate "C9G21"
				( objectStatus "@baseboard_fab2_lib.baseboard_fab2(sch_1):page169_i68" )
				( pin "C9G21.1"
					( objectStatus "a" )
				)
				( pin "C9G21.2"
					( objectStatus "b" )
				)
			)
			( gate "C9G17"
				( objectStatus "@baseboard_fab2_lib.baseboard_fab2(sch_1):page169_i80" )
				( pin "C9G17.1"
					( objectStatus "a" )
				)
				( pin "C9G17.2"
					( objectStatus "b" )
				)
			)
			( gate "R1U32"
				( objectStatus "@baseboard_fab2_lib.baseboard_fab2(sch_1):page169_i82" )
				( pin "R1U32.1"
					( objectStatus "a" )
				)
				( pin "R1U32.2"
					( objectStatus "b" )
				)
			)
			( gate "R1U33"
				( objectStatus "@baseboard_fab2_lib.baseboard_fab2(sch_1):page169_i83" )
				( pin "R1U33.1"
					( objectStatus "a" )
				)
				( pin "R1U33.2"
					( objectStatus "b" )
				)
			)
			( gate "C9G20"
				( objectStatus "@baseboard_fab2_lib.baseboard_fab2(sch_1):page169_i86" )
				( pin "C9G20.1"
					( objectStatus "a" )
				)
				( pin "C9G20.2"
					( objectStatus "b" )
				)
			)
			( gate "R1U39"
				( objectStatus "@baseboard_fab2_lib.baseboard_fab2(sch_1):page169_i88" )
				( pin "R1U39.1"
					( objectStatus "a" )
				)
				( pin "R1U39.2"
					( objectStatus "b" )
				)
			)
			( gate "R9G26"
				( objectStatus "@baseboard_fab2_lib.baseboard_fab2(sch_1):page169_i106" )
				( pin "R9G26.1"
					( objectStatus "a" )
				)
				( pin "R9G26.2"
					( objectStatus "b" )
				)
			)
			( gate "C9G22"
				( objectStatus "@baseboard_fab2_lib.baseboard_fab2(sch_1):page169_i108" )
				( pin "C9G22.1"
					( objectStatus "a" )
				)
				( pin "C9G22.2"
					( objectStatus "b" )
				)
			)
			( gate "R1U38"
				( objectStatus "@baseboard_fab2_lib.baseboard_fab2(sch_1):page169_i114" )
				( pin "R1U38.1"
					( objectStatus "a" )
				)
				( pin "R1U38.2"
					( objectStatus "b" )
				)
			)
			( gate "R1U47"
				( objectStatus "@baseboard_fab2_lib.baseboard_fab2(sch_1):page169_i115" )
				( pin "R1U47.1"
					( objectStatus "a" )
				)
				( pin "R1U47.2"
					( objectStatus "b" )
				)
			)
			( gate "R1U44"
				( objectStatus "@baseboard_fab2_lib.baseboard_fab2(sch_1):page169_i116" )
				( pin "R1U44.1"
					( objectStatus "a" )
				)
				( pin "R1U44.2"
					( objectStatus "b" )
				)
			)
			( gate "R1U50"
				( objectStatus "@baseboard_fab2_lib.baseboard_fab2(sch_1):page169_i126" )
				( pin "R1U50.1"
					( objectStatus "a" )
				)
				( pin "R1U50.2"
					( objectStatus "b" )
				)
			)
			( gate "R1U49"
				( objectStatus "@baseboard_fab2_lib.baseboard_fab2(sch_1):page169_i163" )
				( pin "R1U49.1"
					( objectStatus "a" )
				)
				( pin "R1U49.2"
					( objectStatus "b" )
				)
			)
			( gate "C9G15"
				( objectStatus "@baseboard_fab2_lib.baseboard_fab2(sch_1):page169_i139" )
				( pin "C9G15.1"
					( objectStatus "a" )
				)
				( pin "C9G15.2"
					( objectStatus "b" )
				)
			)
			( gate "R1U29"
				( objectStatus "@baseboard_fab2_lib.baseboard_fab2(sch_1):page169_i141" )
				( pin "R1U29.1"
					( objectStatus "a" )
				)
				( pin "R1U29.2"
					( objectStatus "b" )
				)
			)
			( gate "R1U28"
				( objectStatus "@baseboard_fab2_lib.baseboard_fab2(sch_1):page169_i142" )
				( pin "R1U28.1"
					( objectStatus "a" )
				)
				( pin "R1U28.2"
					( objectStatus "b" )
				)
			)
			( gate "C9G14"
				( objectStatus "@baseboard_fab2_lib.baseboard_fab2(sch_1):page169_i146" )
				( pin "C9G14.1"
					( objectStatus "a" )
				)
				( pin "C9G14.2"
					( objectStatus "b" )
				)
			)
			( gate "R1U26"
				( objectStatus "@baseboard_fab2_lib.baseboard_fab2(sch_1):page169_i148" )
				( pin "R1U26.1"
					( objectStatus "a" )
				)
				( pin "R1U26.2"
					( objectStatus "b" )
				)
			)
			( gate "R1U27"
				( objectStatus "@baseboard_fab2_lib.baseboard_fab2(sch_1):page169_i149" )
				( pin "R1U27.1"
					( objectStatus "a" )
				)
				( pin "R1U27.2"
					( objectStatus "b" )
				)
			)
			( gate "C9G18"
				( objectStatus "@baseboard_fab2_lib.baseboard_fab2(sch_1):page169_i153" )
				( pin "C9G18.1"
					( objectStatus "a" )
				)
				( pin "C9G18.2"
					( objectStatus "b" )
				)
			)
			( gate "FB1U4"
				( objectStatus "@baseboard_fab2_lib.baseboard_fab2(sch_1):page169_i155" )
				( pin "FB1U4.1"
					( objectStatus "a" )
				)
				( pin "FB1U4.2"
					( objectStatus "b" )
				)
			)
			( gate "Q9G1"
				( objectStatus "@baseboard_fab2_lib.baseboard_fab2(sch_1):page169_i157" )
				( pin "Q9G1.3"
					( objectStatus "drain(0)" )
				)
				( pin "Q9G1.5"
					( objectStatus "gate(0)" )
				)
				( pin "Q9G1.4"
					( objectStatus "source(0)" )
				)
			)
			( gate "Q9G1"
				( objectStatus "@baseboard_fab2_lib.baseboard_fab2(sch_1):page169_i162" )
				( pin "Q9G1.6"
					( objectStatus "drain(0)" )
				)
				( pin "Q9G1.2"
					( objectStatus "gate(0)" )
				)
				( pin "Q9G1.1"
					( objectStatus "source(0)" )
				)
			)
			( gate "R2P3"
				( objectStatus "@baseboard_fab2_lib.baseboard_fab2(sch_1):page170_i2" )
				( pin "R2P3.1"
					( objectStatus "a" )
				)
				( pin "R2P3.2"
					( objectStatus "b" )
				)
			)
			( gate "U8D3"
				( objectStatus "@baseboard_fab2_lib.baseboard_fab2(sch_1):page170_i4" )
				( pin "U8D3.2"
					( objectStatus "a" )
				)
				( pin "U8D3.4"
					( objectStatus "y" )
				)
			)
			( gate "C2P1"
				( objectStatus "@baseboard_fab2_lib.baseboard_fab2(sch_1):page170_i8" )
				( pin "C2P1.1"
					( objectStatus "a" )
				)
				( pin "C2P1.2"
					( objectStatus "b" )
				)
			)
			( gate "U8E1"
				( objectStatus "@baseboard_fab2_lib.baseboard_fab2(sch_1):page170_i10" )
				( pin "U8E1.1"
					( objectStatus "a(0)" )
				)
				( pin "U8E1.2"
					( objectStatus "b(0)" )
				)
				( pin "U8E1.3"
					( objectStatus "y(0)" )
				)
			)
			( gate "U8E1"
				( objectStatus "@baseboard_fab2_lib.baseboard_fab2(sch_1):page170_i11" )
				( pin "U8E1.4"
					( objectStatus "a(0)" )
				)
				( pin "U8E1.5"
					( objectStatus "b(0)" )
				)
				( pin "U8E1.6"
					( objectStatus "y(0)" )
				)
			)
			( gate "U8E1"
				( objectStatus "@baseboard_fab2_lib.baseboard_fab2(sch_1):page170_i12" )
				( pin "U8E1.12"
					( objectStatus "a(0)" )
				)
				( pin "U8E1.13"
					( objectStatus "b(0)" )
				)
				( pin "U8E1.11"
					( objectStatus "y(0)" )
				)
			)
			( gate "U1R2"
				( objectStatus "@baseboard_fab2_lib.baseboard_fab2(sch_1):page170_i20" )
				( pin "U1R2.2"
					( objectStatus "a" )
				)
				( pin "U1R2.1"
					( objectStatus "oe" )
				)
				( pin "U1R2.4"
					( objectStatus "y" )
				)
			)
			( gate "C1R27"
				( objectStatus "@baseboard_fab2_lib.baseboard_fab2(sch_1):page170_i30" )
				( pin "C1R27.1"
					( objectStatus "a" )
				)
				( pin "C1R27.2"
					( objectStatus "b" )
				)
			)
			( gate "C8D2"
				( objectStatus "@baseboard_fab2_lib.baseboard_fab2(sch_1):page170_i33" )
				( pin "C8D2.1"
					( objectStatus "a" )
				)
				( pin "C8D2.2"
					( objectStatus "b" )
				)
			)
			( gate "U8D5"
				( objectStatus "@baseboard_fab2_lib.baseboard_fab2(sch_1):page170_i38" )
				( pin "U8D5.2"
					( objectStatus "a" )
				)
				( pin "U8D5.1"
					( objectStatus "oe" )
				)
				( pin "U8D5.4"
					( objectStatus "y" )
				)
			)
			( gate "C8E2"
				( objectStatus "@baseboard_fab2_lib.baseboard_fab2(sch_1):page170_i40" )
				( pin "C8E2.1"
					( objectStatus "a" )
				)
				( pin "C8E2.2"
					( objectStatus "b" )
				)
			)
			( gate "C8D3"
				( objectStatus "@baseboard_fab2_lib.baseboard_fab2(sch_1):page170_i42" )
				( pin "C8D3.1"
					( objectStatus "a" )
				)
				( pin "C8D3.2"
					( objectStatus "b" )
				)
			)
			( gate "U1R1"
				( objectStatus "@baseboard_fab2_lib.baseboard_fab2(sch_1):page170_i46" )
				( pin "U1R1.2"
					( objectStatus "a" )
				)
				( pin "U1R1.4"
					( objectStatus "y" )
				)
			)
			( gate "C1R28"
				( objectStatus "@baseboard_fab2_lib.baseboard_fab2(sch_1):page170_i49" )
				( pin "C1R28.1"
					( objectStatus "a" )
				)
				( pin "C1R28.2"
					( objectStatus "b" )
				)
			)
			( gate "R1R8"
				( objectStatus "@baseboard_fab2_lib.baseboard_fab2(sch_1):page170_i51" )
				( pin "R1R8.1"
					( objectStatus "a" )
				)
				( pin "R1R8.2"
					( objectStatus "b" )
				)
			)
			( gate "R2P8"
				( objectStatus "@baseboard_fab2_lib.baseboard_fab2(sch_1):page170_i52" )
				( pin "R2P8.1"
					( objectStatus "a" )
				)
				( pin "R2P8.2"
					( objectStatus "b" )
				)
			)
			( gate "R2T3"
				( objectStatus "@baseboard_fab2_lib.baseboard_fab2(sch_1):page170_i54" )
				( pin "R2T3.1"
					( objectStatus "a" )
				)
				( pin "R2T3.2"
					( objectStatus "b" )
				)
			)
			( gate "R2P5"
				( objectStatus "@baseboard_fab2_lib.baseboard_fab2(sch_1):page170_i56" )
				( pin "R2P5.1"
					( objectStatus "a" )
				)
				( pin "R2P5.2"
					( objectStatus "b" )
				)
			)
			( gate "Q2P1"
				( objectStatus "@baseboard_fab2_lib.baseboard_fab2(sch_1):page170_i58" )
				( pin "Q2P1.3"
					( objectStatus "drn" )
				)
				( pin "Q2P1.1"
					( objectStatus "gate" )
				)
				( pin "Q2P1.2"
					( objectStatus "src" )
				)
			)
			( gate "R2P13"
				( objectStatus "@baseboard_fab2_lib.baseboard_fab2(sch_1):page170_i61" )
				( pin "R2P13.1"
					( objectStatus "a" )
				)
				( pin "R2P13.2"
					( objectStatus "b" )
				)
			)
			( gate "R2P11"
				( objectStatus "@baseboard_fab2_lib.baseboard_fab2(sch_1):page170_i63" )
				( pin "R2P11.1"
					( objectStatus "a" )
				)
				( pin "R2P11.2"
					( objectStatus "b" )
				)
			)
			( gate "R9F3"
				( objectStatus "@baseboard_fab2_lib.baseboard_fab2(sch_1):page170_i65" )
				( pin "R9F3.1"
					( objectStatus "a" )
				)
				( pin "R9F3.2"
					( objectStatus "b" )
				)
			)
			( gate "Q8F2"
				( objectStatus "@baseboard_fab2_lib.baseboard_fab2(sch_1):page170_i67" )
				( pin "Q8F2.3"
					( objectStatus "drn" )
				)
				( pin "Q8F2.1"
					( objectStatus "gate" )
				)
				( pin "Q8F2.2"
					( objectStatus "src" )
				)
			)
			( gate "R8D26"
				( objectStatus "@baseboard_fab2_lib.baseboard_fab2(sch_1):page170_i71" )
				( pin "R8D26.1"
					( objectStatus "a" )
				)
				( pin "R8D26.2"
					( objectStatus "b" )
				)
			)
			( gate "R1R5"
				( objectStatus "@baseboard_fab2_lib.baseboard_fab2(sch_1):page170_i73" )
				( pin "R1R5.1"
					( objectStatus "a" )
				)
				( pin "R1R5.2"
					( objectStatus "b" )
				)
			)
			( gate "R2P4"
				( objectStatus "@baseboard_fab2_lib.baseboard_fab2(sch_1):page170_i74" )
				( pin "R2P4.1"
					( objectStatus "a" )
				)
				( pin "R2P4.2"
					( objectStatus "b" )
				)
			)
			( gate "C2L49"
				( objectStatus "@baseboard_fab2_lib.baseboard_fab2(sch_1):page172_i5" )
				( pin "C2L49.1"
					( objectStatus "a" )
				)
				( pin "C2L49.2"
					( objectStatus "b" )
				)
			)
			( gate "C2L52"
				( objectStatus "@baseboard_fab2_lib.baseboard_fab2(sch_1):page172_i6" )
				( pin "C2L52.1"
					( objectStatus "a" )
				)
				( pin "C2L52.2"
					( objectStatus "b" )
				)
			)
			( gate "C2L50"
				( objectStatus "@baseboard_fab2_lib.baseboard_fab2(sch_1):page172_i7" )
				( pin "C2L50.1"
					( objectStatus "a" )
				)
				( pin "C2L50.2"
					( objectStatus "b" )
				)
			)
			( gate "C2L51"
				( objectStatus "@baseboard_fab2_lib.baseboard_fab2(sch_1):page172_i8" )
				( pin "C2L51.1"
					( objectStatus "a" )
				)
				( pin "C2L51.2"
					( objectStatus "b" )
				)
			)
			( gate "J8A3"
				( objectStatus "@baseboard_fab2_lib.baseboard_fab2(sch_1):page172_i17" )
				( pin "J8A3.7"
					( objectStatus "gnd(0)" )
				)
				( pin "J8A3.4"
					( objectStatus "gnd(1)" )
				)
				( pin "J8A3.1"
					( objectStatus "gnd(2)" )
				)
				( pin "J8A3.MH1"
					( objectStatus "mh1" )
				)
				( pin "J8A3.MH2"
					( objectStatus "mh2" )
				)
				( pin "J8A3.5"
					( objectStatus "sata_rxn" )
				)
				( pin "J8A3.6"
					( objectStatus "sata_rxp" )
				)
				( pin "J8A3.3"
					( objectStatus "sata_txn" )
				)
				( pin "J8A3.2"
					( objectStatus "sata_txp" )
				)
			)
			( gate "J8A4"
				( objectStatus "@baseboard_fab2_lib.baseboard_fab2(sch_1):page172_i25" )
				( pin "J8A4.1"
					( objectStatus "io1" )
				)
				( pin "J8A4.2"
					( objectStatus "io2" )
				)
				( pin "J8A4.3"
					( objectStatus "io3" )
				)
				( pin "J8A4.4"
					( objectStatus "io4" )
				)
			)
			( gate "C9B2"
				( objectStatus "@baseboard_fab2_lib.baseboard_fab2(sch_1):page172_i36" )
				( pin "C9B2.1"
					( objectStatus "a" )
				)
				( pin "C9B2.2"
					( objectStatus "b" )
				)
			)
			( gate "F9B1"
				( objectStatus "@baseboard_fab2_lib.baseboard_fab2(sch_1):page172_i38" )
				( pin "F9B1.1"
					( objectStatus "a(0)" )
				)
				( pin "F9B1.2"
					( objectStatus "b(0)" )
				)
			)
			( gate "C9B1"
				( objectStatus "@baseboard_fab2_lib.baseboard_fab2(sch_1):page172_i39" )
				( pin "C9B1.1"
					( objectStatus "a" )
				)
				( pin "C9B1.2"
					( objectStatus "b" )
				)
			)
			( gate "F8B1"
				( objectStatus "@baseboard_fab2_lib.baseboard_fab2(sch_1):page172_i41" )
				( pin "F8B1.1"
					( objectStatus "a(0)" )
				)
				( pin "F8B1.2"
					( objectStatus "b(0)" )
				)
			)
			( gate "J2M1"
				( objectStatus "@baseboard_fab2_lib.baseboard_fab2(sch_1):page172_i52" )
				( pin "J2M1.7"
					( objectStatus "gnd(0)" )
				)
				( pin "J2M1.4"
					( objectStatus "gnd(1)" )
				)
				( pin "J2M1.1"
					( objectStatus "gnd(2)" )
				)
				( pin "J2M1.MH1"
					( objectStatus "mh1" )
				)
				( pin "J2M1.MH2"
					( objectStatus "mh2" )
				)
				( pin "J2M1.5"
					( objectStatus "sata_rxn" )
				)
				( pin "J2M1.6"
					( objectStatus "sata_rxp" )
				)
				( pin "J2M1.3"
					( objectStatus "sata_txn" )
				)
				( pin "J2M1.2"
					( objectStatus "sata_txp" )
				)
			)
			( gate "J2L1"
				( objectStatus "@baseboard_fab2_lib.baseboard_fab2(sch_1):page172_i53" )
				( pin "J2L1.1"
					( objectStatus "io1" )
				)
				( pin "J2L1.2"
					( objectStatus "io2" )
				)
				( pin "J2L1.3"
					( objectStatus "io3" )
				)
				( pin "J2L1.4"
					( objectStatus "io4" )
				)
			)
			( gate "J8A1"
				( objectStatus "@baseboard_fab2_lib.baseboard_fab2(sch_1):page173_i163" )
				( pin "J8A1.2D9"
					( objectStatus "gnd(0)" )
				)
				( pin "J8A1.2D6"
					( objectStatus "gnd(1)" )
				)
				( pin "J8A1.2D3"
					( objectStatus "gnd(2)" )
				)
				( pin "J8A1.2C9"
					( objectStatus "gnd(3)" )
				)
				( pin "J8A1.2C6"
					( objectStatus "gnd(4)" )
				)
				( pin "J8A1.2C3"
					( objectStatus "gnd(5)" )
				)
				( pin "J8A1.2B9"
					( objectStatus "gnd(6)" )
				)
				( pin "J8A1.2B6"
					( objectStatus "gnd(7)" )
				)
				( pin "J8A1.2B3"
					( objectStatus "gnd(8)" )
				)
				( pin "J8A1.2A9"
					( objectStatus "gnd(9)" )
				)
				( pin "J8A1.2A6"
					( objectStatus "gnd(10)" )
				)
				( pin "J8A1.2A3"
					( objectStatus "gnd(11)" )
				)
				( pin "J8A1.1D9"
					( objectStatus "gnd(12)" )
				)
				( pin "J8A1.1D6"
					( objectStatus "gnd(13)" )
				)
				( pin "J8A1.1D3"
					( objectStatus "gnd(14)" )
				)
				( pin "J8A1.1C9"
					( objectStatus "gnd(15)" )
				)
				( pin "J8A1.1C6"
					( objectStatus "gnd(16)" )
				)
				( pin "J8A1.1C3"
					( objectStatus "gnd(17)" )
				)
				( pin "J8A1.1B9"
					( objectStatus "gnd(18)" )
				)
				( pin "J8A1.1B6"
					( objectStatus "gnd(19)" )
				)
				( pin "J8A1.1B3"
					( objectStatus "gnd(20)" )
				)
				( pin "J8A1.1A9"
					( objectStatus "gnd(21)" )
				)
				( pin "J8A1.1A6"
					( objectStatus "gnd(22)" )
				)
				( pin "J8A1.1A3"
					( objectStatus "gnd(23)" )
				)
				( pin "J8A1.1B5"
					( objectStatus "rxa0_dn" )
				)
				( pin "J8A1.1B4"
					( objectStatus "rxa0_dp" )
				)
				( pin "J8A1.1A5"
					( objectStatus "rxa1_dn" )
				)
				( pin "J8A1.1A4"
					( objectStatus "rxa1_dp" )
				)
				( pin "J8A1.1B8"
					( objectStatus "rxa2_dn" )
				)
				( pin "J8A1.1B7"
					( objectStatus "rxa2_dp" )
				)
				( pin "J8A1.1A8"
					( objectStatus "rxa3_dn" )
				)
				( pin "J8A1.1A7"
					( objectStatus "rxa3_dp" )
				)
				( pin "J8A1.2B5"
					( objectStatus "rxb0_dn" )
				)
				( pin "J8A1.2B4"
					( objectStatus "rxb0_dp" )
				)
				( pin "J8A1.2A5"
					( objectStatus "rxb1_dn" )
				)
				( pin "J8A1.2A4"
					( objectStatus "rxb1_dp" )
				)
				( pin "J8A1.2B8"
					( objectStatus "rxb2_dn" )
				)
				( pin "J8A1.2B7"
					( objectStatus "rxb2_dp" )
				)
				( pin "J8A1.2A8"
					( objectStatus "rxb3_dn" )
				)
				( pin "J8A1.2A7"
					( objectStatus "rxb3_dp" )
				)
				( pin "J8A1.1A2"
					( objectStatus "sidebanda_0" )
				)
				( pin "J8A1.1B2"
					( objectStatus "sidebanda_1" )
				)
				( pin "J8A1.1C2"
					( objectStatus "sidebanda_2" )
				)
				( pin "J8A1.1B1"
					( objectStatus "sidebanda_3" )
				)
				( pin "J8A1.1C1"
					( objectStatus "sidebanda_4" )
				)
				( pin "J8A1.1D1"
					( objectStatus "sidebanda_5" )
				)
				( pin "J8A1.1D2"
					( objectStatus "sidebanda_6" )
				)
				( pin "J8A1.1A1"
					( objectStatus "sidebanda_7" )
				)
				( pin "J8A1.2A2"
					( objectStatus "sidebandb_0" )
				)
				( pin "J8A1.2B2"
					( objectStatus "sidebandb_1" )
				)
				( pin "J8A1.2C2"
					( objectStatus "sidebandb_2" )
				)
				( pin "J8A1.2B1"
					( objectStatus "sidebandb_3" )
				)
				( pin "J8A1.2C1"
					( objectStatus "sidebandb_4" )
				)
				( pin "J8A1.2D1"
					( objectStatus "sidebandb_5" )
				)
				( pin "J8A1.2D2"
					( objectStatus "sidebandb_6" )
				)
				( pin "J8A1.2A1"
					( objectStatus "sidebandb_7" )
				)
				( pin "J8A1.1D5"
					( objectStatus "txa0_dn" )
				)
				( pin "J8A1.1D4"
					( objectStatus "txa0_dp" )
				)
				( pin "J8A1.1C5"
					( objectStatus "txa1_dn" )
				)
				( pin "J8A1.1C4"
					( objectStatus "txa1_dp" )
				)
				( pin "J8A1.1D8"
					( objectStatus "txa2_dn" )
				)
				( pin "J8A1.1D7"
					( objectStatus "txa2_dp" )
				)
				( pin "J8A1.1C8"
					( objectStatus "txa3_dn" )
				)
				( pin "J8A1.1C7"
					( objectStatus "txa3_dp" )
				)
				( pin "J8A1.2D5"
					( objectStatus "txb0_dn" )
				)
				( pin "J8A1.2D4"
					( objectStatus "txb0_dp" )
				)
				( pin "J8A1.2C5"
					( objectStatus "txb1_dn" )
				)
				( pin "J8A1.2C4"
					( objectStatus "txb1_dp" )
				)
				( pin "J8A1.2D8"
					( objectStatus "txb2_dn" )
				)
				( pin "J8A1.2D7"
					( objectStatus "txb2_dp" )
				)
				( pin "J8A1.2C8"
					( objectStatus "txb3_dn" )
				)
				( pin "J8A1.2C7"
					( objectStatus "txb3_dp" )
				)
			)
			( gate "C2L13"
				( objectStatus "@baseboard_fab2_lib.baseboard_fab2(sch_1):page173_i165" )
				( pin "C2L13.1"
					( objectStatus "a" )
				)
				( pin "C2L13.2"
					( objectStatus "b" )
				)
			)
			( gate "C2L6"
				( objectStatus "@baseboard_fab2_lib.baseboard_fab2(sch_1):page173_i166" )
				( pin "C2L6.1"
					( objectStatus "a" )
				)
				( pin "C2L6.2"
					( objectStatus "b" )
				)
			)
			( gate "C2L19"
				( objectStatus "@baseboard_fab2_lib.baseboard_fab2(sch_1):page173_i172" )
				( pin "C2L19.1"
					( objectStatus "a" )
				)
				( pin "C2L19.2"
					( objectStatus "b" )
				)
			)
			( gate "C2L10"
				( objectStatus "@baseboard_fab2_lib.baseboard_fab2(sch_1):page173_i173" )
				( pin "C2L10.1"
					( objectStatus "a" )
				)
				( pin "C2L10.2"
					( objectStatus "b" )
				)
			)
			( gate "C2L17"
				( objectStatus "@baseboard_fab2_lib.baseboard_fab2(sch_1):page173_i174" )
				( pin "C2L17.1"
					( objectStatus "a" )
				)
				( pin "C2L17.2"
					( objectStatus "b" )
				)
			)
			( gate "C2L15"
				( objectStatus "@baseboard_fab2_lib.baseboard_fab2(sch_1):page173_i191" )
				( pin "C2L15.1"
					( objectStatus "a" )
				)
				( pin "C2L15.2"
					( objectStatus "b" )
				)
			)
			( gate "C2L4"
				( objectStatus "@baseboard_fab2_lib.baseboard_fab2(sch_1):page173_i192" )
				( pin "C2L4.1"
					( objectStatus "a" )
				)
				( pin "C2L4.2"
					( objectStatus "b" )
				)
			)
			( gate "C2L3"
				( objectStatus "@baseboard_fab2_lib.baseboard_fab2(sch_1):page173_i194" )
				( pin "C2L3.1"
					( objectStatus "a" )
				)
				( pin "C2L3.2"
					( objectStatus "b" )
				)
			)
			( gate "C2L20"
				( objectStatus "@baseboard_fab2_lib.baseboard_fab2(sch_1):page173_i195" )
				( pin "C2L20.1"
					( objectStatus "a" )
				)
				( pin "C2L20.2"
					( objectStatus "b" )
				)
			)
			( gate "C2L12"
				( objectStatus "@baseboard_fab2_lib.baseboard_fab2(sch_1):page173_i196" )
				( pin "C2L12.1"
					( objectStatus "a" )
				)
				( pin "C2L12.2"
					( objectStatus "b" )
				)
			)
			( gate "C2L18"
				( objectStatus "@baseboard_fab2_lib.baseboard_fab2(sch_1):page173_i197" )
				( pin "C2L18.1"
					( objectStatus "a" )
				)
				( pin "C2L18.2"
					( objectStatus "b" )
				)
			)
			( gate "C2L16"
				( objectStatus "@baseboard_fab2_lib.baseboard_fab2(sch_1):page173_i205" )
				( pin "C2L16.1"
					( objectStatus "a" )
				)
				( pin "C2L16.2"
					( objectStatus "b" )
				)
			)
			( gate "C2L7"
				( objectStatus "@baseboard_fab2_lib.baseboard_fab2(sch_1):page173_i206" )
				( pin "C2L7.1"
					( objectStatus "a" )
				)
				( pin "C2L7.2"
					( objectStatus "b" )
				)
			)
			( gate "C2L9"
				( objectStatus "@baseboard_fab2_lib.baseboard_fab2(sch_1):page173_i207" )
				( pin "C2L9.1"
					( objectStatus "a" )
				)
				( pin "C2L9.2"
					( objectStatus "b" )
				)
			)
			( gate "C2L14"
				( objectStatus "@baseboard_fab2_lib.baseboard_fab2(sch_1):page173_i208" )
				( pin "C2L14.1"
					( objectStatus "a" )
				)
				( pin "C2L14.2"
					( objectStatus "b" )
				)
			)
			( gate "C2L5"
				( objectStatus "@baseboard_fab2_lib.baseboard_fab2(sch_1):page173_i209" )
				( pin "C2L5.1"
					( objectStatus "a" )
				)
				( pin "C2L5.2"
					( objectStatus "b" )
				)
			)
			( gate "C2L40"
				( objectStatus "@baseboard_fab2_lib.baseboard_fab2(sch_1):page173_i220" )
				( pin "C2L40.1"
					( objectStatus "a" )
				)
				( pin "C2L40.2"
					( objectStatus "b" )
				)
			)
			( gate "C2L39"
				( objectStatus "@baseboard_fab2_lib.baseboard_fab2(sch_1):page173_i221" )
				( pin "C2L39.1"
					( objectStatus "a" )
				)
				( pin "C2L39.2"
					( objectStatus "b" )
				)
			)
			( gate "C2L43"
				( objectStatus "@baseboard_fab2_lib.baseboard_fab2(sch_1):page173_i222" )
				( pin "C2L43.1"
					( objectStatus "a" )
				)
				( pin "C2L43.2"
					( objectStatus "b" )
				)
			)
			( gate "C2L44"
				( objectStatus "@baseboard_fab2_lib.baseboard_fab2(sch_1):page173_i228" )
				( pin "C2L44.1"
					( objectStatus "a" )
				)
				( pin "C2L44.2"
					( objectStatus "b" )
				)
			)
			( gate "C2L42"
				( objectStatus "@baseboard_fab2_lib.baseboard_fab2(sch_1):page173_i233" )
				( pin "C2L42.1"
					( objectStatus "a" )
				)
				( pin "C2L42.2"
					( objectStatus "b" )
				)
			)
			( gate "C2L22"
				( objectStatus "@baseboard_fab2_lib.baseboard_fab2(sch_1):page173_i234" )
				( pin "C2L22.1"
					( objectStatus "a" )
				)
				( pin "C2L22.2"
					( objectStatus "b" )
				)
			)
			( gate "C2L37"
				( objectStatus "@baseboard_fab2_lib.baseboard_fab2(sch_1):page173_i238" )
				( pin "C2L37.1"
					( objectStatus "a" )
				)
				( pin "C2L37.2"
					( objectStatus "b" )
				)
			)
			( gate "C2L47"
				( objectStatus "@baseboard_fab2_lib.baseboard_fab2(sch_1):page173_i239" )
				( pin "C2L47.1"
					( objectStatus "a" )
				)
				( pin "C2L47.2"
					( objectStatus "b" )
				)
			)
			( gate "C2L27"
				( objectStatus "@baseboard_fab2_lib.baseboard_fab2(sch_1):page173_i240" )
				( pin "C2L27.1"
					( objectStatus "a" )
				)
				( pin "C2L27.2"
					( objectStatus "b" )
				)
			)
			( gate "C2L23"
				( objectStatus "@baseboard_fab2_lib.baseboard_fab2(sch_1):page173_i241" )
				( pin "C2L23.1"
					( objectStatus "a" )
				)
				( pin "C2L23.2"
					( objectStatus "b" )
				)
			)
			( gate "C2L41"
				( objectStatus "@baseboard_fab2_lib.baseboard_fab2(sch_1):page173_i242" )
				( pin "C2L41.1"
					( objectStatus "a" )
				)
				( pin "C2L41.2"
					( objectStatus "b" )
				)
			)
			( gate "C2L26"
				( objectStatus "@baseboard_fab2_lib.baseboard_fab2(sch_1):page173_i255" )
				( pin "C2L26.1"
					( objectStatus "a" )
				)
				( pin "C2L26.2"
					( objectStatus "b" )
				)
			)
			( gate "C2L38"
				( objectStatus "@baseboard_fab2_lib.baseboard_fab2(sch_1):page173_i256" )
				( pin "C2L38.1"
					( objectStatus "a" )
				)
				( pin "C2L38.2"
					( objectStatus "b" )
				)
			)
			( gate "C2L48"
				( objectStatus "@baseboard_fab2_lib.baseboard_fab2(sch_1):page173_i257" )
				( pin "C2L48.1"
					( objectStatus "a" )
				)
				( pin "C2L48.2"
					( objectStatus "b" )
				)
			)
			( gate "C2L24"
				( objectStatus "@baseboard_fab2_lib.baseboard_fab2(sch_1):page173_i258" )
				( pin "C2L24.1"
					( objectStatus "a" )
				)
				( pin "C2L24.2"
					( objectStatus "b" )
				)
			)
			( gate "C2L21"
				( objectStatus "@baseboard_fab2_lib.baseboard_fab2(sch_1):page173_i259" )
				( pin "C2L21.1"
					( objectStatus "a" )
				)
				( pin "C2L21.2"
					( objectStatus "b" )
				)
			)
			( gate "R2L23"
				( objectStatus "@baseboard_fab2_lib.baseboard_fab2(sch_1):page173_i261" )
				( pin "R2L23.1"
					( objectStatus "a" )
				)
				( pin "R2L23.2"
					( objectStatus "b" )
				)
			)
			( gate "R2L21"
				( objectStatus "@baseboard_fab2_lib.baseboard_fab2(sch_1):page173_i263" )
				( pin "R2L21.1"
					( objectStatus "a" )
				)
				( pin "R2L21.2"
					( objectStatus "b" )
				)
			)
			( gate "R2L22"
				( objectStatus "@baseboard_fab2_lib.baseboard_fab2(sch_1):page173_i264" )
				( pin "R2L22.1"
					( objectStatus "a" )
				)
				( pin "R2L22.2"
					( objectStatus "b" )
				)
			)
			( gate "R2L18"
				( objectStatus "@baseboard_fab2_lib.baseboard_fab2(sch_1):page173_i266" )
				( pin "R2L18.1"
					( objectStatus "a" )
				)
				( pin "R2L18.2"
					( objectStatus "b" )
				)
			)
			( gate "R1L3"
				( objectStatus "@baseboard_fab2_lib.baseboard_fab2(sch_1):page174_i5" )
				( pin "R1L3.1"
					( objectStatus "a" )
				)
				( pin "R1L3.2"
					( objectStatus "b" )
				)
			)
			( gate "C1L3"
				( objectStatus "@baseboard_fab2_lib.baseboard_fab2(sch_1):page174_i8" )
				( pin "C1L3.1"
					( objectStatus "a" )
				)
				( pin "C1L3.2"
					( objectStatus "b" )
				)
			)
			( gate "C1L2"
				( objectStatus "@baseboard_fab2_lib.baseboard_fab2(sch_1):page174_i9" )
				( pin "C1L2.1"
					( objectStatus "a" )
				)
				( pin "C1L2.2"
					( objectStatus "b" )
				)
			)
			( gate "C1L7"
				( objectStatus "@baseboard_fab2_lib.baseboard_fab2(sch_1):page174_i12" )
				( pin "C1L7.1"
					( objectStatus "a" )
				)
				( pin "C1L7.2"
					( objectStatus "b" )
				)
			)
			( gate "C1L6"
				( objectStatus "@baseboard_fab2_lib.baseboard_fab2(sch_1):page174_i13" )
				( pin "C1L6.1"
					( objectStatus "a" )
				)
				( pin "C1L6.2"
					( objectStatus "b" )
				)
			)
			( gate "C1L13"
				( objectStatus "@baseboard_fab2_lib.baseboard_fab2(sch_1):page174_i14" )
				( pin "C1L13.1"
					( objectStatus "a" )
				)
				( pin "C1L13.2"
					( objectStatus "b" )
				)
			)
			( gate "C1L15"
				( objectStatus "@baseboard_fab2_lib.baseboard_fab2(sch_1):page174_i18" )
				( pin "C1L15.1"
					( objectStatus "a" )
				)
				( pin "C1L15.2"
					( objectStatus "b" )
				)
			)
			( gate "C1L12"
				( objectStatus "@baseboard_fab2_lib.baseboard_fab2(sch_1):page174_i19" )
				( pin "C1L12.1"
					( objectStatus "a" )
				)
				( pin "C1L12.2"
					( objectStatus "b" )
				)
			)
			( gate "C1L14"
				( objectStatus "@baseboard_fab2_lib.baseboard_fab2(sch_1):page174_i20" )
				( pin "C1L14.1"
					( objectStatus "a" )
				)
				( pin "C1L14.2"
					( objectStatus "b" )
				)
			)
			( gate "R1L1"
				( objectStatus "@baseboard_fab2_lib.baseboard_fab2(sch_1):page174_i25" )
				( pin "R1L1.1"
					( objectStatus "a" )
				)
				( pin "R1L1.2"
					( objectStatus "b" )
				)
			)
			( gate "J8A2"
				( objectStatus "@baseboard_fab2_lib.baseboard_fab2(sch_1):page174_i26" )
				( pin "J8A2.A3"
					( objectStatus "gnd1" )
				)
				( pin "J8A2.A6"
					( objectStatus "gnd2" )
				)
				( pin "J8A2.A9"
					( objectStatus "gnd3" )
				)
				( pin "J8A2.B3"
					( objectStatus "gnd4" )
				)
				( pin "J8A2.B6"
					( objectStatus "gnd5" )
				)
				( pin "J8A2.B9"
					( objectStatus "gnd6" )
				)
				( pin "J8A2.C3"
					( objectStatus "gnd7" )
				)
				( pin "J8A2.C6"
					( objectStatus "gnd8" )
				)
				( pin "J8A2.C9"
					( objectStatus "gnd9" )
				)
				( pin "J8A2.D3"
					( objectStatus "gnd10" )
				)
				( pin "J8A2.D6"
					( objectStatus "gnd11" )
				)
				( pin "J8A2.D9"
					( objectStatus "gnd12" )
				)
				( pin "J8A2.B5"
					( objectStatus "rxa0_dn" )
				)
				( pin "J8A2.B4"
					( objectStatus "rxa0_dp" )
				)
				( pin "J8A2.A5"
					( objectStatus "rxa1_dn" )
				)
				( pin "J8A2.A4"
					( objectStatus "rxa1_dp" )
				)
				( pin "J8A2.B8"
					( objectStatus "rxa2_dn" )
				)
				( pin "J8A2.B7"
					( objectStatus "rxa2_dp" )
				)
				( pin "J8A2.A8"
					( objectStatus "rxa3_dn" )
				)
				( pin "J8A2.A7"
					( objectStatus "rxa3_dp" )
				)
				( pin "J8A2.A2"
					( objectStatus "sideband0" )
				)
				( pin "J8A2.B2"
					( objectStatus "sideband1" )
				)
				( pin "J8A2.C2"
					( objectStatus "sideband2" )
				)
				( pin "J8A2.B1"
					( objectStatus "sideband3" )
				)
				( pin "J8A2.C1"
					( objectStatus "sideband4" )
				)
				( pin "J8A2.D1"
					( objectStatus "sideband5" )
				)
				( pin "J8A2.D2"
					( objectStatus "sideband6" )
				)
				( pin "J8A2.A1"
					( objectStatus "sideband7" )
				)
				( pin "J8A2.D5"
					( objectStatus "txa0_dn" )
				)
				( pin "J8A2.D4"
					( objectStatus "txa0_dp" )
				)
				( pin "J8A2.C5"
					( objectStatus "txa1_dn" )
				)
				( pin "J8A2.C4"
					( objectStatus "txa1_dp" )
				)
				( pin "J8A2.D8"
					( objectStatus "txa2_dn" )
				)
				( pin "J8A2.D7"
					( objectStatus "txa2_dp" )
				)
				( pin "J8A2.C8"
					( objectStatus "txa3_dn" )
				)
				( pin "J8A2.C7"
					( objectStatus "txa3_dp" )
				)
			)
			( gate "C2L30"
				( objectStatus "@baseboard_fab2_lib.baseboard_fab2(sch_1):page174_i28" )
				( pin "C2L30.1"
					( objectStatus "a" )
				)
				( pin "C2L30.2"
					( objectStatus "b" )
				)
			)
			( gate "C2L31"
				( objectStatus "@baseboard_fab2_lib.baseboard_fab2(sch_1):page174_i29" )
				( pin "C2L31.1"
					( objectStatus "a" )
				)
				( pin "C2L31.2"
					( objectStatus "b" )
				)
			)
			( gate "C2L28"
				( objectStatus "@baseboard_fab2_lib.baseboard_fab2(sch_1):page174_i30" )
				( pin "C2L28.1"
					( objectStatus "a" )
				)
				( pin "C2L28.2"
					( objectStatus "b" )
				)
			)
			( gate "C2L35"
				( objectStatus "@baseboard_fab2_lib.baseboard_fab2(sch_1):page174_i31" )
				( pin "C2L35.1"
					( objectStatus "a" )
				)
				( pin "C2L35.2"
					( objectStatus "b" )
				)
			)
			( gate "C2L29"
				( objectStatus "@baseboard_fab2_lib.baseboard_fab2(sch_1):page174_i32" )
				( pin "C2L29.1"
					( objectStatus "a" )
				)
				( pin "C2L29.2"
					( objectStatus "b" )
				)
			)
			( gate "C2L36"
				( objectStatus "@baseboard_fab2_lib.baseboard_fab2(sch_1):page174_i39" )
				( pin "C2L36.1"
					( objectStatus "a" )
				)
				( pin "C2L36.2"
					( objectStatus "b" )
				)
			)
			( gate "C2L33"
				( objectStatus "@baseboard_fab2_lib.baseboard_fab2(sch_1):page174_i40" )
				( pin "C2L33.1"
					( objectStatus "a" )
				)
				( pin "C2L33.2"
					( objectStatus "b" )
				)
			)
			( gate "C2L34"
				( objectStatus "@baseboard_fab2_lib.baseboard_fab2(sch_1):page174_i41" )
				( pin "C2L34.1"
					( objectStatus "a" )
				)
				( pin "C2L34.2"
					( objectStatus "b" )
				)
			)
			( gate "R1L31"
				( objectStatus "@baseboard_fab2_lib.baseboard_fab2(sch_1):page175_i4" )
				( pin "R1L31.1"
					( objectStatus "a" )
				)
				( pin "R1L31.2"
					( objectStatus "b" )
				)
			)
			( gate "R1L27"
				( objectStatus "@baseboard_fab2_lib.baseboard_fab2(sch_1):page175_i5" )
				( pin "R1L27.1"
					( objectStatus "a" )
				)
				( pin "R1L27.2"
					( objectStatus "b" )
				)
			)
			( gate "U9A4"
				( objectStatus "@baseboard_fab2_lib.baseboard_fab2(sch_1):page175_i9" )
				( pin "U9A4.1"
					( objectStatus "a(0)" )
				)
				( pin "U9A4.6"
					( objectStatus "y(0)" )
				)
			)
			( gate "U9A4"
				( objectStatus "@baseboard_fab2_lib.baseboard_fab2(sch_1):page175_i10" )
				( pin "U9A4.3"
					( objectStatus "a(0)" )
				)
				( pin "U9A4.4"
					( objectStatus "y(0)" )
				)
			)
			( gate "C1L18"
				( objectStatus "@baseboard_fab2_lib.baseboard_fab2(sch_1):page175_i11" )
				( pin "C1L18.1"
					( objectStatus "a" )
				)
				( pin "C1L18.2"
					( objectStatus "b" )
				)
			)
			( gate "R1L26"
				( objectStatus "@baseboard_fab2_lib.baseboard_fab2(sch_1):page175_i13" )
				( pin "R1L26.1"
					( objectStatus "a" )
				)
				( pin "R1L26.2"
					( objectStatus "b" )
				)
			)
			( gate "U9A3"
				( objectStatus "@baseboard_fab2_lib.baseboard_fab2(sch_1):page175_i15" )
				( pin "U9A3.3"
					( objectStatus "a(0)" )
				)
				( pin "U9A3.4"
					( objectStatus "y(0)" )
				)
			)
			( gate "U9A3"
				( objectStatus "@baseboard_fab2_lib.baseboard_fab2(sch_1):page175_i18" )
				( pin "U9A3.1"
					( objectStatus "a(0)" )
				)
				( pin "U9A3.6"
					( objectStatus "y(0)" )
				)
			)
			( gate "C1L10"
				( objectStatus "@baseboard_fab2_lib.baseboard_fab2(sch_1):page175_i19" )
				( pin "C1L10.1"
					( objectStatus "a" )
				)
				( pin "C1L10.2"
					( objectStatus "b" )
				)
			)
			( gate "R1L22"
				( objectStatus "@baseboard_fab2_lib.baseboard_fab2(sch_1):page175_i22" )
				( pin "R1L22.1"
					( objectStatus "a" )
				)
				( pin "R1L22.2"
					( objectStatus "b" )
				)
			)
			( gate "R1L19"
				( objectStatus "@baseboard_fab2_lib.baseboard_fab2(sch_1):page175_i24" )
				( pin "R1L19.1"
					( objectStatus "a" )
				)
				( pin "R1L19.2"
					( objectStatus "b" )
				)
			)
			( gate "R9A9"
				( objectStatus "@baseboard_fab2_lib.baseboard_fab2(sch_1):page175_i35" )
				( pin "R9A9.1"
					( objectStatus "a" )
				)
				( pin "R9A9.2"
					( objectStatus "b" )
				)
			)
			( gate "C1L17"
				( objectStatus "@baseboard_fab2_lib.baseboard_fab2(sch_1):page175_i37" )
				( pin "C1L17.1"
					( objectStatus "a" )
				)
				( pin "C1L17.2"
					( objectStatus "b" )
				)
			)
			( gate "C1L9"
				( objectStatus "@baseboard_fab2_lib.baseboard_fab2(sch_1):page175_i38" )
				( pin "C1L9.1"
					( objectStatus "a" )
				)
				( pin "C1L9.2"
					( objectStatus "b" )
				)
			)
			( gate "C9A3"
				( objectStatus "@baseboard_fab2_lib.baseboard_fab2(sch_1):page175_i40" )
				( pin "C9A3.1"
					( objectStatus "a" )
				)
				( pin "C9A3.2"
					( objectStatus "b" )
				)
			)
			( gate "R1L33"
				( objectStatus "@baseboard_fab2_lib.baseboard_fab2(sch_1):page175_i45" )
				( pin "R1L33.1"
					( objectStatus "a" )
				)
				( pin "R1L33.2"
					( objectStatus "b" )
				)
			)
			( gate "Q9A3"
				( objectStatus "@baseboard_fab2_lib.baseboard_fab2(sch_1):page175_i49" )
				( pin "Q9A3.3"
					( objectStatus "drn" )
				)
				( pin "Q9A3.1"
					( objectStatus "gate" )
				)
				( pin "Q9A3.2"
					( objectStatus "src" )
				)
			)
			( gate "DS9A1"
				( objectStatus "@baseboard_fab2_lib.baseboard_fab2(sch_1):page175_i50" )
				( pin "DS9A1.2"
					( objectStatus "a" )
				)
				( pin "DS9A1.1"
					( objectStatus "c" )
				)
			)
			( gate "U1L2"
				( objectStatus "@baseboard_fab2_lib.baseboard_fab2(sch_1):page175_i57" )
				( pin "U1L2.1"
					( objectStatus "a" )
				)
				( pin "U1L2.2"
					( objectStatus "b" )
				)
				( pin "U1L2.4"
					( objectStatus "y" )
				)
			)
			( gate "R1L8"
				( objectStatus "@baseboard_fab2_lib.baseboard_fab2(sch_1):page175_i58" )
				( pin "R1L8.1"
					( objectStatus "a" )
				)
				( pin "R1L8.2"
					( objectStatus "b" )
				)
			)
			( gate "R1L12"
				( objectStatus "@baseboard_fab2_lib.baseboard_fab2(sch_1):page175_i63" )
				( pin "R1L12.1"
					( objectStatus "a" )
				)
				( pin "R1L12.2"
					( objectStatus "b" )
				)
			)
			( gate "C1L4"
				( objectStatus "@baseboard_fab2_lib.baseboard_fab2(sch_1):page175_i64" )
				( pin "C1L4.1"
					( objectStatus "a" )
				)
				( pin "C1L4.2"
					( objectStatus "b" )
				)
			)
			( gate "DS9A3"
				( objectStatus "@baseboard_fab2_lib.baseboard_fab2(sch_1):page175_i67" )
				( pin "DS9A3.2"
					( objectStatus "a" )
				)
				( pin "DS9A3.1"
					( objectStatus "c" )
				)
			)
			( gate "S9A1"
				( objectStatus "@baseboard_fab2_lib.baseboard_fab2(sch_1):page175_i78" )
				( pin "S9A1.1"
					( objectStatus "pin1" )
				)
				( pin "S9A1.2"
					( objectStatus "pin2" )
				)
				( pin "S9A1.3"
					( objectStatus "pin3" )
				)
				( pin "S9A1.4"
					( objectStatus "pin4" )
				)
			)
			( gate "S9A2"
				( objectStatus "@baseboard_fab2_lib.baseboard_fab2(sch_1):page175_i84" )
				( pin "S9A2.1"
					( objectStatus "io1" )
				)
				( pin "S9A2.2"
					( objectStatus "io2" )
				)
				( pin "S9A2.3"
					( objectStatus "io3" )
				)
				( pin "S9A2.4"
					( objectStatus "io4" )
				)
			)
			( gate "R1M5"
				( objectStatus "@baseboard_fab2_lib.baseboard_fab2(sch_1):page176_i16" )
				( pin "R1M5.1"
					( objectStatus "a" )
				)
				( pin "R1M5.2"
					( objectStatus "b" )
				)
			)
			( gate "L1M2"
				( objectStatus "@baseboard_fab2_lib.baseboard_fab2(sch_1):page176_i30" )
				( pin "L1M2.1"
					( objectStatus "a1" )
				)
				( pin "L1M2.2"
					( objectStatus "a2" )
				)
				( pin "L1M2.3"
					( objectStatus "b1" )
				)
				( pin "L1M2.4"
					( objectStatus "b2" )
				)
			)
			( gate "R1M6"
				( objectStatus "@baseboard_fab2_lib.baseboard_fab2(sch_1):page176_i31" )
				( pin "R1M6.1"
					( objectStatus "a" )
				)
				( pin "R1M6.2"
					( objectStatus "b" )
				)
			)
			( gate "L1L1"
				( objectStatus "@baseboard_fab2_lib.baseboard_fab2(sch_1):page176_i51" )
				( pin "L1L1.1"
					( objectStatus "\1\" )
				)
				( pin "L1L1.2"
					( objectStatus "\2\" )
				)
				( pin "L1L1.3"
					( objectStatus "\3\" )
				)
				( pin "L1L1.4"
					( objectStatus "\4\" )
				)
			)
			( gate "CR1M1"
				( objectStatus "@baseboard_fab2_lib.baseboard_fab2(sch_1):page176_i52" )
				( pin "CR1M1.1"
					( objectStatus "ac0" )
				)
				( pin "CR1M1.2"
					( objectStatus "ac1" )
				)
				( pin "CR1M1.4"
					( objectStatus "ac2" )
				)
				( pin "CR1M1.5"
					( objectStatus "ac3" )
				)
				( pin "CR1M1.3"
					( objectStatus "gnd(0)" )
				)
				( pin "CR1M1.9"
					( objectStatus "out0" )
				)
				( pin "CR1M1.8"
					( objectStatus "out1" )
				)
				( pin "CR1M1.7"
					( objectStatus "out2" )
				)
				( pin "CR1M1.6"
					( objectStatus "out3" )
				)
			)
			( gate "R1L42"
				( objectStatus "@baseboard_fab2_lib.baseboard_fab2(sch_1):page176_i58" )
				( pin "R1L42.1"
					( objectStatus "a" )
				)
				( pin "R1L42.2"
					( objectStatus "b" )
				)
			)
			( gate "R1L40"
				( objectStatus "@baseboard_fab2_lib.baseboard_fab2(sch_1):page176_i59" )
				( pin "R1L40.1"
					( objectStatus "a" )
				)
				( pin "R1L40.2"
					( objectStatus "b" )
				)
			)
			( gate "R1M2"
				( objectStatus "@baseboard_fab2_lib.baseboard_fab2(sch_1):page176_i60" )
				( pin "R1M2.1"
					( objectStatus "a" )
				)
				( pin "R1M2.2"
					( objectStatus "b" )
				)
			)
			( gate "R1M1"
				( objectStatus "@baseboard_fab2_lib.baseboard_fab2(sch_1):page176_i61" )
				( pin "R1M1.1"
					( objectStatus "a" )
				)
				( pin "R1M1.2"
					( objectStatus "b" )
				)
			)
			( gate "L1M1"
				( objectStatus "@baseboard_fab2_lib.baseboard_fab2(sch_1):page176_i62" )
				( pin "L1M1.1"
					( objectStatus "\1\" )
				)
				( pin "L1M1.2"
					( objectStatus "\2\" )
				)
				( pin "L1M1.3"
					( objectStatus "\3\" )
				)
				( pin "L1M1.4"
					( objectStatus "\4\" )
				)
			)
			( gate "C1M2"
				( objectStatus "@baseboard_fab2_lib.baseboard_fab2(sch_1):page176_i63" )
				( pin "C1M2.1"
					( objectStatus "a" )
				)
				( pin "C1M2.2"
					( objectStatus "b" )
				)
			)
			( gate "C1M1"
				( objectStatus "@baseboard_fab2_lib.baseboard_fab2(sch_1):page176_i64" )
				( pin "C1M1.1"
					( objectStatus "a" )
				)
				( pin "C1M1.2"
					( objectStatus "b" )
				)
			)
			( gate "J9B1"
				( objectStatus "@baseboard_fab2_lib.baseboard_fab2(sch_1):page176_i69" )
				( pin "J9B1.2"
					( objectStatus "dn" )
				)
				( pin "J9B1.3"
					( objectStatus "dp" )
				)
				( pin "J9B1.4"
					( objectStatus "gnd" )
				)
				( pin "J9B1.7"
					( objectStatus "gnd_drain" )
				)
				( pin "J9B1.MH1"
					( objectStatus "mh1" )
				)
				( pin "J9B1.MH2"
					( objectStatus "mh2" )
				)
				( pin "J9B1.MH3"
					( objectStatus "mh3" )
				)
				( pin "J9B1.MH4"
					( objectStatus "mh4" )
				)
				( pin "J9B1.5"
					( objectStatus "stda_ssrxn" )
				)
				( pin "J9B1.6"
					( objectStatus "stda_ssrxp" )
				)
				( pin "J9B1.8"
					( objectStatus "stda_sstxn" )
				)
				( pin "J9B1.9"
					( objectStatus "stda_sstxp" )
				)
				( pin "J9B1.1"
					( objectStatus "vbus" )
				)
			)
			( gate "CR1M2"
				( objectStatus "@baseboard_fab2_lib.baseboard_fab2(sch_1):page176_i98" )
				( pin "CR1M2.1"
					( objectStatus "ac0" )
				)
				( pin "CR1M2.2"
					( objectStatus "ac1" )
				)
				( pin "CR1M2.4"
					( objectStatus "ac2" )
				)
				( pin "CR1M2.5"
					( objectStatus "ac3" )
				)
				( pin "CR1M2.3"
					( objectStatus "gnd(0)" )
				)
				( pin "CR1M2.9"
					( objectStatus "out0" )
				)
				( pin "CR1M2.8"
					( objectStatus "out1" )
				)
				( pin "CR1M2.7"
					( objectStatus "out2" )
				)
				( pin "CR1M2.6"
					( objectStatus "out3" )
				)
			)
			( gate "U9B1"
				( objectStatus "@baseboard_fab2_lib.baseboard_fab2(sch_1):page176_i100" )
				( pin "U9B1.4"
					( objectStatus "en_n" )
				)
				( pin "U9B1.2"
					( objectStatus "gnd" )
				)
				( pin "U9B1.5"
					( objectStatus "\in\" )
				)
				( pin "U9B1.3"
					( objectStatus "oc_n" )
				)
				( pin "U9B1.1"
					( objectStatus "\out\" )
				)
			)
			( gate "R9B1"
				( objectStatus "@baseboard_fab2_lib.baseboard_fab2(sch_1):page176_i105" )
				( pin "R9B1.1"
					( objectStatus "a" )
				)
				( pin "R9B1.2"
					( objectStatus "b" )
				)
			)
			( gate "C9B5"
				( objectStatus "@baseboard_fab2_lib.baseboard_fab2(sch_1):page176_i108" )
				( pin "C9B5.1"
					( objectStatus "a" )
				)
				( pin "C9B5.2"
					( objectStatus "b" )
				)
			)
			( gate "R113"
				( objectStatus "@baseboard_fab2_lib.baseboard_fab2(sch_1):page176_i111" )
				( pin "R113.1"
					( objectStatus "a" )
				)
				( pin "R113.2"
					( objectStatus "b" )
				)
			)
			( gate "C41"
				( objectStatus "@baseboard_fab2_lib.baseboard_fab2(sch_1):page176_i113" )
				( pin "C41.1"
					( objectStatus "a" )
				)
				( pin "C41.2"
					( objectStatus "b" )
				)
			)
			( gate "R1M13"
				( objectStatus "@baseboard_fab2_lib.baseboard_fab2(sch_1):page177_i3" )
				( pin "R1M13.1"
					( objectStatus "a" )
				)
				( pin "R1M13.2"
					( objectStatus "b" )
				)
			)
			( gate "R1M10"
				( objectStatus "@baseboard_fab2_lib.baseboard_fab2(sch_1):page177_i6" )
				( pin "R1M10.1"
					( objectStatus "a" )
				)
				( pin "R1M10.2"
					( objectStatus "b" )
				)
			)
			( gate "R1M12"
				( objectStatus "@baseboard_fab2_lib.baseboard_fab2(sch_1):page177_i8" )
				( pin "R1M12.1"
					( objectStatus "a" )
				)
				( pin "R1M12.2"
					( objectStatus "b" )
				)
			)
			( gate "R1M11"
				( objectStatus "@baseboard_fab2_lib.baseboard_fab2(sch_1):page177_i9" )
				( pin "R1M11.1"
					( objectStatus "a" )
				)
				( pin "R1M11.2"
					( objectStatus "b" )
				)
			)
			( gate "C1M3"
				( objectStatus "@baseboard_fab2_lib.baseboard_fab2(sch_1):page177_i20" )
				( pin "C1M3.1"
					( objectStatus "a" )
				)
				( pin "C1M3.2"
					( objectStatus "b" )
				)
			)
			( gate "DS9A6"
				( objectStatus "@baseboard_fab2_lib.baseboard_fab2(sch_1):page177_i31" )
				( pin "DS9A6.1"
					( objectStatus "a" )
				)
				( pin "DS9A6.2"
					( objectStatus "c" )
				)
			)
			( gate "R1L37"
				( objectStatus "@baseboard_fab2_lib.baseboard_fab2(sch_1):page177_i33" )
				( pin "R1L37.1"
					( objectStatus "a" )
				)
				( pin "R1L37.2"
					( objectStatus "b" )
				)
			)
			( gate "DS9A2"
				( objectStatus "@baseboard_fab2_lib.baseboard_fab2(sch_1):page177_i42" )
				( pin "DS9A2.2"
					( objectStatus "a" )
				)
				( pin "DS9A2.1"
					( objectStatus "c" )
				)
			)
			( gate "R1L21"
				( objectStatus "@baseboard_fab2_lib.baseboard_fab2(sch_1):page177_i43" )
				( pin "R1L21.1"
					( objectStatus "a" )
				)
				( pin "R1L21.2"
					( objectStatus "b" )
				)
			)
			( gate "U1M1"
				( objectStatus "@baseboard_fab2_lib.baseboard_fab2(sch_1):page177_i70" )
				( pin "U1M1.1"
					( objectStatus "a(0)" )
				)
				( pin "U1M1.2"
					( objectStatus "b(0)" )
				)
				( pin "U1M1.4"
					( objectStatus "y(0)" )
				)
			)
			( gate "DS9F1"
				( objectStatus "@baseboard_fab2_lib.baseboard_fab2(sch_1):page177_i71" )
				( pin "DS9F1.1"
					( objectStatus "a" )
				)
				( pin "DS9F1.2"
					( objectStatus "c" )
				)
			)
			( gate "R9F28"
				( objectStatus "@baseboard_fab2_lib.baseboard_fab2(sch_1):page177_i72" )
				( pin "R9F28.1"
					( objectStatus "a" )
				)
				( pin "R9F28.2"
					( objectStatus "b" )
				)
			)
			( gate "R9F30"
				( objectStatus "@baseboard_fab2_lib.baseboard_fab2(sch_1):page177_i76" )
				( pin "R9F30.1"
					( objectStatus "a" )
				)
				( pin "R9F30.2"
					( objectStatus "b" )
				)
			)
			( gate "Q9F1"
				( objectStatus "@baseboard_fab2_lib.baseboard_fab2(sch_1):page177_i79" )
				( pin "Q9F1.3"
					( objectStatus "drain(0)" )
				)
				( pin "Q9F1.5"
					( objectStatus "gate(0)" )
				)
				( pin "Q9F1.4"
					( objectStatus "source(0)" )
				)
			)
			( gate "Q9F1"
				( objectStatus "@baseboard_fab2_lib.baseboard_fab2(sch_1):page177_i80" )
				( pin "Q9F1.6"
					( objectStatus "drain(0)" )
				)
				( pin "Q9F1.2"
					( objectStatus "gate(0)" )
				)
				( pin "Q9F1.1"
					( objectStatus "source(0)" )
				)
			)
			( gate "R9F52"
				( objectStatus "@baseboard_fab2_lib.baseboard_fab2(sch_1):page177_i82" )
				( pin "R9F52.1"
					( objectStatus "a" )
				)
				( pin "R9F52.2"
					( objectStatus "b" )
				)
			)
			( gate "R8D20"
				( objectStatus "@baseboard_fab2_lib.baseboard_fab2(sch_1):page178_i1" )
				( pin "R8D20.1"
					( objectStatus "a" )
				)
				( pin "R8D20.2"
					( objectStatus "b" )
				)
			)
			( gate "R2L12"
				( objectStatus "@baseboard_fab2_lib.baseboard_fab2(sch_1):page178_i2" )
				( pin "R2L12.1"
					( objectStatus "a" )
				)
				( pin "R2L12.2"
					( objectStatus "b" )
				)
			)
			( gate "R8D19"
				( objectStatus "@baseboard_fab2_lib.baseboard_fab2(sch_1):page178_i8" )
				( pin "R8D19.1"
					( objectStatus "a" )
				)
				( pin "R8D19.2"
					( objectStatus "b" )
				)
			)
			( gate "R3N8"
				( objectStatus "@baseboard_fab2_lib.baseboard_fab2(sch_1):page178_i11" )
				( pin "R3N8.1"
					( objectStatus "a" )
				)
				( pin "R3N8.2"
					( objectStatus "b" )
				)
			)
			( gate "R2L15"
				( objectStatus "@baseboard_fab2_lib.baseboard_fab2(sch_1):page178_i12" )
				( pin "R2L15.1"
					( objectStatus "a" )
				)
				( pin "R2L15.2"
					( objectStatus "b" )
				)
			)
			( gate "R2L11"
				( objectStatus "@baseboard_fab2_lib.baseboard_fab2(sch_1):page178_i13" )
				( pin "R2L11.1"
					( objectStatus "a" )
				)
				( pin "R2L11.2"
					( objectStatus "b" )
				)
			)
			( gate "R2L6"
				( objectStatus "@baseboard_fab2_lib.baseboard_fab2(sch_1):page178_i17" )
				( pin "R2L6.1"
					( objectStatus "a" )
				)
				( pin "R2L6.2"
					( objectStatus "b" )
				)
			)
			( gate "R2L4"
				( objectStatus "@baseboard_fab2_lib.baseboard_fab2(sch_1):page178_i18" )
				( pin "R2L4.1"
					( objectStatus "a" )
				)
				( pin "R2L4.2"
					( objectStatus "b" )
				)
			)
			( gate "R2L5"
				( objectStatus "@baseboard_fab2_lib.baseboard_fab2(sch_1):page178_i20" )
				( pin "R2L5.1"
					( objectStatus "a" )
				)
				( pin "R2L5.2"
					( objectStatus "b" )
				)
			)
			( gate "R8B29"
				( objectStatus "@baseboard_fab2_lib.baseboard_fab2(sch_1):page178_i21" )
				( pin "R8B29.1"
					( objectStatus "a" )
				)
				( pin "R8B29.2"
					( objectStatus "b" )
				)
			)
			( gate "R2N19"
				( objectStatus "@baseboard_fab2_lib.baseboard_fab2(sch_1):page178_i22" )
				( pin "R2N19.1"
					( objectStatus "a" )
				)
				( pin "R2N19.2"
					( objectStatus "b" )
				)
			)
			( gate "R2N22"
				( objectStatus "@baseboard_fab2_lib.baseboard_fab2(sch_1):page178_i23" )
				( pin "R2N22.1"
					( objectStatus "a" )
				)
				( pin "R2N22.2"
					( objectStatus "b" )
				)
			)
			( gate "J1F1"
				( objectStatus "@baseboard_fab2_lib.baseboard_fab2(sch_1):page181_i111" )
				( pin "J1F1.A2"
					( objectStatus "gnda2" )
				)
				( pin "J1F1.A4"
					( objectStatus "gnda4" )
				)
				( pin "J1F1.A6"
					( objectStatus "gnda6" )
				)
				( pin "J1F1.A8"
					( objectStatus "gnda8" )
				)
				( pin "J1F1.C1"
					( objectStatus "gndc1" )
				)
				( pin "J1F1.C3"
					( objectStatus "gndc3" )
				)
				( pin "J1F1.C5"
					( objectStatus "gndc5" )
				)
				( pin "J1F1.C7"
					( objectStatus "gndc7" )
				)
				( pin "J1F1.D2"
					( objectStatus "gndd2" )
				)
				( pin "J1F1.D4"
					( objectStatus "gndd4" )
				)
				( pin "J1F1.D6"
					( objectStatus "gndd6" )
				)
				( pin "J1F1.D8"
					( objectStatus "gndd8" )
				)
				( pin "J1F1.F1"
					( objectStatus "gndf1" )
				)
				( pin "J1F1.F3"
					( objectStatus "gndf3" )
				)
				( pin "J1F1.F5"
					( objectStatus "gndf5" )
				)
				( pin "J1F1.F7"
					( objectStatus "gndf7" )
				)
				( pin "J1F1.G2"
					( objectStatus "gndg2" )
				)
				( pin "J1F1.G4"
					( objectStatus "gndg4" )
				)
				( pin "J1F1.G6"
					( objectStatus "gndg6" )
				)
				( pin "J1F1.G8"
					( objectStatus "gndg8" )
				)
				( pin "J1F1.I1"
					( objectStatus "gndi1" )
				)
				( pin "J1F1.I3"
					( objectStatus "gndi3" )
				)
				( pin "J1F1.I5"
					( objectStatus "gndi5" )
				)
				( pin "J1F1.I7"
					( objectStatus "gndi7" )
				)
				( pin "J1F1.J2"
					( objectStatus "gndj2" )
				)
				( pin "J1F1.J4"
					( objectStatus "gndj4" )
				)
				( pin "J1F1.J6"
					( objectStatus "gndj6" )
				)
				( pin "J1F1.J8"
					( objectStatus "gndj8" )
				)
				( pin "J1F1.A1"
					( objectStatus "ioa1" )
				)
				( pin "J1F1.A3"
					( objectStatus "ioa3" )
				)
				( pin "J1F1.A5"
					( objectStatus "ioa5" )
				)
				( pin "J1F1.A7"
					( objectStatus "ioa7" )
				)
				( pin "J1F1.B1"
					( objectStatus "iob1" )
				)
				( pin "J1F1.B2"
					( objectStatus "iob2" )
				)
				( pin "J1F1.B3"
					( objectStatus "iob3" )
				)
				( pin "J1F1.B4"
					( objectStatus "iob4" )
				)
				( pin "J1F1.B5"
					( objectStatus "iob5" )
				)
				( pin "J1F1.B6"
					( objectStatus "iob6" )
				)
				( pin "J1F1.B7"
					( objectStatus "iob7" )
				)
				( pin "J1F1.B8"
					( objectStatus "iob8" )
				)
				( pin "J1F1.C2"
					( objectStatus "ioc2" )
				)
				( pin "J1F1.C4"
					( objectStatus "ioc4" )
				)
				( pin "J1F1.C6"
					( objectStatus "ioc6" )
				)
				( pin "J1F1.C8"
					( objectStatus "ioc8" )
				)
				( pin "J1F1.D1"
					( objectStatus "iod1" )
				)
				( pin "J1F1.D3"
					( objectStatus "iod3" )
				)
				( pin "J1F1.D5"
					( objectStatus "iod5" )
				)
				( pin "J1F1.D7"
					( objectStatus "iod7" )
				)
				( pin "J1F1.E1"
					( objectStatus "ioe1" )
				)
				( pin "J1F1.E2"
					( objectStatus "ioe2" )
				)
				( pin "J1F1.E3"
					( objectStatus "ioe3" )
				)
				( pin "J1F1.E4"
					( objectStatus "ioe4" )
				)
				( pin "J1F1.E5"
					( objectStatus "ioe5" )
				)
				( pin "J1F1.E6"
					( objectStatus "ioe6" )
				)
				( pin "J1F1.E7"
					( objectStatus "ioe7" )
				)
				( pin "J1F1.E8"
					( objectStatus "ioe8" )
				)
				( pin "J1F1.F2"
					( objectStatus "iof2" )
				)
				( pin "J1F1.F4"
					( objectStatus "iof4" )
				)
				( pin "J1F1.F6"
					( objectStatus "iof6" )
				)
				( pin "J1F1.F8"
					( objectStatus "iof8" )
				)
				( pin "J1F1.G1"
					( objectStatus "iog1" )
				)
				( pin "J1F1.G3"
					( objectStatus "iog3" )
				)
				( pin "J1F1.G5"
					( objectStatus "iog5" )
				)
				( pin "J1F1.G7"
					( objectStatus "iog7" )
				)
				( pin "J1F1.H1"
					( objectStatus "ioh1" )
				)
				( pin "J1F1.H2"
					( objectStatus "ioh2" )
				)
				( pin "J1F1.H3"
					( objectStatus "ioh3" )
				)
				( pin "J1F1.H4"
					( objectStatus "ioh4" )
				)
				( pin "J1F1.H5"
					( objectStatus "ioh5" )
				)
				( pin "J1F1.H6"
					( objectStatus "ioh6" )
				)
				( pin "J1F1.H7"
					( objectStatus "ioh7" )
				)
				( pin "J1F1.H8"
					( objectStatus "ioh8" )
				)
				( pin "J1F1.I2"
					( objectStatus "ioi2" )
				)
				( pin "J1F1.I4"
					( objectStatus "ioi4" )
				)
				( pin "J1F1.I6"
					( objectStatus "ioi6" )
				)
				( pin "J1F1.I8"
					( objectStatus "ioi8" )
				)
			)
			( gate "C1F4"
				( objectStatus "@baseboard_fab2_lib.baseboard_fab2(sch_1):page181_i160" )
				( pin "C1F4.1"
					( objectStatus "a" )
				)
				( pin "C1F4.2"
					( objectStatus "b" )
				)
			)
			( gate "C1F5"
				( objectStatus "@baseboard_fab2_lib.baseboard_fab2(sch_1):page181_i161" )
				( pin "C1F5.1"
					( objectStatus "a" )
				)
				( pin "C1F5.2"
					( objectStatus "b" )
				)
			)
			( gate "C1F2"
				( objectStatus "@baseboard_fab2_lib.baseboard_fab2(sch_1):page181_i162" )
				( pin "C1F2.1"
					( objectStatus "a" )
				)
				( pin "C1F2.2"
					( objectStatus "b" )
				)
			)
			( gate "C1F13"
				( objectStatus "@baseboard_fab2_lib.baseboard_fab2(sch_1):page181_i163" )
				( pin "C1F13.1"
					( objectStatus "a" )
				)
				( pin "C1F13.2"
					( objectStatus "b" )
				)
			)
			( gate "C1F10"
				( objectStatus "@baseboard_fab2_lib.baseboard_fab2(sch_1):page181_i164" )
				( pin "C1F10.1"
					( objectStatus "a" )
				)
				( pin "C1F10.2"
					( objectStatus "b" )
				)
			)
			( gate "C1F6"
				( objectStatus "@baseboard_fab2_lib.baseboard_fab2(sch_1):page181_i165" )
				( pin "C1F6.1"
					( objectStatus "a" )
				)
				( pin "C1F6.2"
					( objectStatus "b" )
				)
			)
			( gate "C1F20"
				( objectStatus "@baseboard_fab2_lib.baseboard_fab2(sch_1):page181_i166" )
				( pin "C1F20.1"
					( objectStatus "a" )
				)
				( pin "C1F20.2"
					( objectStatus "b" )
				)
			)
			( gate "C1F3"
				( objectStatus "@baseboard_fab2_lib.baseboard_fab2(sch_1):page181_i167" )
				( pin "C1F3.1"
					( objectStatus "a" )
				)
				( pin "C1F3.2"
					( objectStatus "b" )
				)
			)
			( gate "C1F12"
				( objectStatus "@baseboard_fab2_lib.baseboard_fab2(sch_1):page181_i168" )
				( pin "C1F12.1"
					( objectStatus "a" )
				)
				( pin "C1F12.2"
					( objectStatus "b" )
				)
			)
			( gate "C1F11"
				( objectStatus "@baseboard_fab2_lib.baseboard_fab2(sch_1):page181_i169" )
				( pin "C1F11.1"
					( objectStatus "a" )
				)
				( pin "C1F11.2"
					( objectStatus "b" )
				)
			)
			( gate "C1F8"
				( objectStatus "@baseboard_fab2_lib.baseboard_fab2(sch_1):page181_i170" )
				( pin "C1F8.1"
					( objectStatus "a" )
				)
				( pin "C1F8.2"
					( objectStatus "b" )
				)
			)
			( gate "C1F18"
				( objectStatus "@baseboard_fab2_lib.baseboard_fab2(sch_1):page181_i171" )
				( pin "C1F18.1"
					( objectStatus "a" )
				)
				( pin "C1F18.2"
					( objectStatus "b" )
				)
			)
			( gate "C1F16"
				( objectStatus "@baseboard_fab2_lib.baseboard_fab2(sch_1):page181_i172" )
				( pin "C1F16.1"
					( objectStatus "a" )
				)
				( pin "C1F16.2"
					( objectStatus "b" )
				)
			)
			( gate "C1F17"
				( objectStatus "@baseboard_fab2_lib.baseboard_fab2(sch_1):page181_i173" )
				( pin "C1F17.1"
					( objectStatus "a" )
				)
				( pin "C1F17.2"
					( objectStatus "b" )
				)
			)
			( gate "C1F15"
				( objectStatus "@baseboard_fab2_lib.baseboard_fab2(sch_1):page181_i174" )
				( pin "C1F15.1"
					( objectStatus "a" )
				)
				( pin "C1F15.2"
					( objectStatus "b" )
				)
			)
			( gate "C1F14"
				( objectStatus "@baseboard_fab2_lib.baseboard_fab2(sch_1):page181_i175" )
				( pin "C1F14.1"
					( objectStatus "a" )
				)
				( pin "C1F14.2"
					( objectStatus "b" )
				)
			)
			( gate "R9T9"
				( objectStatus "@baseboard_fab2_lib.baseboard_fab2(sch_1):page181_i177" )
				( pin "R9T9.1"
					( objectStatus "a" )
				)
				( pin "R9T9.2"
					( objectStatus "b" )
				)
			)
			( gate "CR1F4"
				( objectStatus "@baseboard_fab2_lib.baseboard_fab2(sch_1):page181_i178" )
				( pin "CR1F4.2"
					( objectStatus "a" )
				)
				( pin "CR1F4.1"
					( objectStatus "c" )
				)
			)
			( gate "CR1F3"
				( objectStatus "@baseboard_fab2_lib.baseboard_fab2(sch_1):page181_i180" )
				( pin "CR1F3.2"
					( objectStatus "a" )
				)
				( pin "CR1F3.1"
					( objectStatus "c" )
				)
			)
			( gate "Q9T1"
				( objectStatus "@baseboard_fab2_lib.baseboard_fab2(sch_1):page181_i181" )
				( pin "Q9T1.1"
					( objectStatus "b" )
				)
				( pin "Q9T1.3"
					( objectStatus "c" )
				)
				( pin "Q9T1.2"
					( objectStatus "e" )
				)
			)
			( gate "R9T6"
				( objectStatus "@baseboard_fab2_lib.baseboard_fab2(sch_1):page181_i183" )
				( pin "R9T6.1"
					( objectStatus "a" )
				)
				( pin "R9T6.2"
					( objectStatus "b" )
				)
			)
			( gate "R9T3"
				( objectStatus "@baseboard_fab2_lib.baseboard_fab2(sch_1):page181_i185" )
				( pin "R9T3.1"
					( objectStatus "a" )
				)
				( pin "R9T3.2"
					( objectStatus "b" )
				)
			)
			( gate "J1F3"
				( objectStatus "@baseboard_fab2_lib.baseboard_fab2(sch_1):page181_i189" )
				( pin "J1F3.1"
					( objectStatus "io1" )
				)
				( pin "J1F3.2"
					( objectStatus "io2" )
				)
				( pin "J1F3.3"
					( objectStatus "io3" )
				)
				( pin "J1F3.4"
					( objectStatus "io4" )
				)
				( pin "J1F3.5"
					( objectStatus "io5" )
				)
				( pin "J1F3.6"
					( objectStatus "io6" )
				)
				( pin "J1F3.7"
					( objectStatus "io7" )
				)
				( pin "J1F3.8"
					( objectStatus "io8" )
				)
			)
			( gate "R7D5"
				( objectStatus "@baseboard_fab2_lib.baseboard_fab2(sch_1):page181_i199" )
				( pin "R7D5.1"
					( objectStatus "a" )
				)
				( pin "R7D5.2"
					( objectStatus "b" )
				)
			)
			( gate "R7D9"
				( objectStatus "@baseboard_fab2_lib.baseboard_fab2(sch_1):page181_i200" )
				( pin "R7D9.1"
					( objectStatus "a" )
				)
				( pin "R7D9.2"
					( objectStatus "b" )
				)
			)
			( gate "R7D11"
				( objectStatus "@baseboard_fab2_lib.baseboard_fab2(sch_1):page181_i201" )
				( pin "R7D11.1"
					( objectStatus "a" )
				)
				( pin "R7D11.2"
					( objectStatus "b" )
				)
			)
			( gate "R8E5"
				( objectStatus "@baseboard_fab2_lib.baseboard_fab2(sch_1):page181_i218" )
				( pin "R8E5.1"
					( objectStatus "a" )
				)
				( pin "R8E5.2"
					( objectStatus "b" )
				)
			)
			( gate "C2R6"
				( objectStatus "@baseboard_fab2_lib.baseboard_fab2(sch_1):page181_i224" )
				( pin "C2R6.1"
					( objectStatus "a" )
				)
				( pin "C2R6.2"
					( objectStatus "b" )
				)
			)
			( gate "U8E1"
				( objectStatus "@baseboard_fab2_lib.baseboard_fab2(sch_1):page181_i243" )
				( pin "U8E1.9"
					( objectStatus "a(0)" )
				)
				( pin "U8E1.10"
					( objectStatus "b(0)" )
				)
				( pin "U8E1.8"
					( objectStatus "y(0)" )
				)
			)
			( gate "R9T8"
				( objectStatus "@baseboard_fab2_lib.baseboard_fab2(sch_1):page181_i249" )
				( pin "R9T8.1"
					( objectStatus "a" )
				)
				( pin "R9T8.2"
					( objectStatus "b" )
				)
			)
			( gate "C8E1"
				( objectStatus "@baseboard_fab2_lib.baseboard_fab2(sch_1):page181_i253" )
				( pin "C8E1.1"
					( objectStatus "a" )
				)
				( pin "C8E1.2"
					( objectStatus "b" )
				)
			)
			( gate "R9R9"
				( objectStatus "@baseboard_fab2_lib.baseboard_fab2(sch_1):page181_i254" )
				( pin "R9R9.1"
					( objectStatus "a" )
				)
				( pin "R9R9.2"
					( objectStatus "b" )
				)
			)
			( gate "R9T2"
				( objectStatus "@baseboard_fab2_lib.baseboard_fab2(sch_1):page181_i255" )
				( pin "R9T2.1"
					( objectStatus "a" )
				)
				( pin "R9T2.2"
					( objectStatus "b" )
				)
			)
			( gate "R9R10"
				( objectStatus "@baseboard_fab2_lib.baseboard_fab2(sch_1):page181_i256" )
				( pin "R9R10.1"
					( objectStatus "a" )
				)
				( pin "R9R10.2"
					( objectStatus "b" )
				)
			)
			( gate "R9T1"
				( objectStatus "@baseboard_fab2_lib.baseboard_fab2(sch_1):page181_i261" )
				( pin "R9T1.1"
					( objectStatus "a" )
				)
				( pin "R9T1.2"
					( objectStatus "b" )
				)
			)
			( gate "R1F8"
				( objectStatus "@baseboard_fab2_lib.baseboard_fab2(sch_1):page181_i268" )
				( pin "R1F8.1"
					( objectStatus "a" )
				)
				( pin "R1F8.2"
					( objectStatus "b" )
				)
			)
			( gate "C9N18"
				( objectStatus "@baseboard_fab2_lib.baseboard_fab2(sch_1):page182_i9" )
				( pin "C9N18.1"
					( objectStatus "a" )
				)
				( pin "C9N18.2"
					( objectStatus "b" )
				)
			)
			( gate "C9N17"
				( objectStatus "@baseboard_fab2_lib.baseboard_fab2(sch_1):page182_i12" )
				( pin "C9N17.1"
					( objectStatus "a" )
				)
				( pin "C9N17.2"
					( objectStatus "b" )
				)
			)
			( gate "C9N15"
				( objectStatus "@baseboard_fab2_lib.baseboard_fab2(sch_1):page182_i13" )
				( pin "C9N15.1"
					( objectStatus "a" )
				)
				( pin "C9N15.2"
					( objectStatus "b" )
				)
			)
			( gate "C9N1"
				( objectStatus "@baseboard_fab2_lib.baseboard_fab2(sch_1):page182_i14" )
				( pin "C9N1.1"
					( objectStatus "a" )
				)
				( pin "C9N1.2"
					( objectStatus "b" )
				)
			)
			( gate "C9N2"
				( objectStatus "@baseboard_fab2_lib.baseboard_fab2(sch_1):page182_i15" )
				( pin "C9N2.1"
					( objectStatus "a" )
				)
				( pin "C9N2.2"
					( objectStatus "b" )
				)
			)
			( gate "C9N12"
				( objectStatus "@baseboard_fab2_lib.baseboard_fab2(sch_1):page182_i16" )
				( pin "C9N12.1"
					( objectStatus "a" )
				)
				( pin "C9N12.2"
					( objectStatus "b" )
				)
			)
			( gate "J1C1"
				( objectStatus "@baseboard_fab2_lib.baseboard_fab2(sch_1):page182_i18" )
				( pin "J1C1.A2"
					( objectStatus "gnda2" )
				)
				( pin "J1C1.A4"
					( objectStatus "gnda4" )
				)
				( pin "J1C1.A6"
					( objectStatus "gnda6" )
				)
				( pin "J1C1.A8"
					( objectStatus "gnda8" )
				)
				( pin "J1C1.C1"
					( objectStatus "gndc1" )
				)
				( pin "J1C1.C3"
					( objectStatus "gndc3" )
				)
				( pin "J1C1.C5"
					( objectStatus "gndc5" )
				)
				( pin "J1C1.C7"
					( objectStatus "gndc7" )
				)
				( pin "J1C1.D2"
					( objectStatus "gndd2" )
				)
				( pin "J1C1.D4"
					( objectStatus "gndd4" )
				)
				( pin "J1C1.D6"
					( objectStatus "gndd6" )
				)
				( pin "J1C1.D8"
					( objectStatus "gndd8" )
				)
				( pin "J1C1.F1"
					( objectStatus "gndf1" )
				)
				( pin "J1C1.F3"
					( objectStatus "gndf3" )
				)
				( pin "J1C1.F5"
					( objectStatus "gndf5" )
				)
				( pin "J1C1.F7"
					( objectStatus "gndf7" )
				)
				( pin "J1C1.G2"
					( objectStatus "gndg2" )
				)
				( pin "J1C1.G4"
					( objectStatus "gndg4" )
				)
				( pin "J1C1.G6"
					( objectStatus "gndg6" )
				)
				( pin "J1C1.G8"
					( objectStatus "gndg8" )
				)
				( pin "J1C1.I1"
					( objectStatus "gndi1" )
				)
				( pin "J1C1.I3"
					( objectStatus "gndi3" )
				)
				( pin "J1C1.I5"
					( objectStatus "gndi5" )
				)
				( pin "J1C1.I7"
					( objectStatus "gndi7" )
				)
				( pin "J1C1.J2"
					( objectStatus "gndj2" )
				)
				( pin "J1C1.J4"
					( objectStatus "gndj4" )
				)
				( pin "J1C1.J6"
					( objectStatus "gndj6" )
				)
				( pin "J1C1.J8"
					( objectStatus "gndj8" )
				)
				( pin "J1C1.A1"
					( objectStatus "ioa1" )
				)
				( pin "J1C1.A3"
					( objectStatus "ioa3" )
				)
				( pin "J1C1.A5"
					( objectStatus "ioa5" )
				)
				( pin "J1C1.A7"
					( objectStatus "ioa7" )
				)
				( pin "J1C1.B1"
					( objectStatus "iob1" )
				)
				( pin "J1C1.B2"
					( objectStatus "iob2" )
				)
				( pin "J1C1.B3"
					( objectStatus "iob3" )
				)
				( pin "J1C1.B4"
					( objectStatus "iob4" )
				)
				( pin "J1C1.B5"
					( objectStatus "iob5" )
				)
				( pin "J1C1.B6"
					( objectStatus "iob6" )
				)
				( pin "J1C1.B7"
					( objectStatus "iob7" )
				)
				( pin "J1C1.B8"
					( objectStatus "iob8" )
				)
				( pin "J1C1.C2"
					( objectStatus "ioc2" )
				)
				( pin "J1C1.C4"
					( objectStatus "ioc4" )
				)
				( pin "J1C1.C6"
					( objectStatus "ioc6" )
				)
				( pin "J1C1.C8"
					( objectStatus "ioc8" )
				)
				( pin "J1C1.D1"
					( objectStatus "iod1" )
				)
				( pin "J1C1.D3"
					( objectStatus "iod3" )
				)
				( pin "J1C1.D5"
					( objectStatus "iod5" )
				)
				( pin "J1C1.D7"
					( objectStatus "iod7" )
				)
				( pin "J1C1.E1"
					( objectStatus "ioe1" )
				)
				( pin "J1C1.E2"
					( objectStatus "ioe2" )
				)
				( pin "J1C1.E3"
					( objectStatus "ioe3" )
				)
				( pin "J1C1.E4"
					( objectStatus "ioe4" )
				)
				( pin "J1C1.E5"
					( objectStatus "ioe5" )
				)
				( pin "J1C1.E6"
					( objectStatus "ioe6" )
				)
				( pin "J1C1.E7"
					( objectStatus "ioe7" )
				)
				( pin "J1C1.E8"
					( objectStatus "ioe8" )
				)
				( pin "J1C1.F2"
					( objectStatus "iof2" )
				)
				( pin "J1C1.F4"
					( objectStatus "iof4" )
				)
				( pin "J1C1.F6"
					( objectStatus "iof6" )
				)
				( pin "J1C1.F8"
					( objectStatus "iof8" )
				)
				( pin "J1C1.G1"
					( objectStatus "iog1" )
				)
				( pin "J1C1.G3"
					( objectStatus "iog3" )
				)
				( pin "J1C1.G5"
					( objectStatus "iog5" )
				)
				( pin "J1C1.G7"
					( objectStatus "iog7" )
				)
				( pin "J1C1.H1"
					( objectStatus "ioh1" )
				)
				( pin "J1C1.H2"
					( objectStatus "ioh2" )
				)
				( pin "J1C1.H3"
					( objectStatus "ioh3" )
				)
				( pin "J1C1.H4"
					( objectStatus "ioh4" )
				)
				( pin "J1C1.H5"
					( objectStatus "ioh5" )
				)
				( pin "J1C1.H6"
					( objectStatus "ioh6" )
				)
				( pin "J1C1.H7"
					( objectStatus "ioh7" )
				)
				( pin "J1C1.H8"
					( objectStatus "ioh8" )
				)
				( pin "J1C1.I2"
					( objectStatus "ioi2" )
				)
				( pin "J1C1.I4"
					( objectStatus "ioi4" )
				)
				( pin "J1C1.I6"
					( objectStatus "ioi6" )
				)
				( pin "J1C1.I8"
					( objectStatus "ioi8" )
				)
			)
			( gate "C9N9"
				( objectStatus "@baseboard_fab2_lib.baseboard_fab2(sch_1):page182_i49" )
				( pin "C9N9.1"
					( objectStatus "a" )
				)
				( pin "C9N9.2"
					( objectStatus "b" )
				)
			)
			( gate "C9N8"
				( objectStatus "@baseboard_fab2_lib.baseboard_fab2(sch_1):page182_i50" )
				( pin "C9N8.1"
					( objectStatus "a" )
				)
				( pin "C9N8.2"
					( objectStatus "b" )
				)
			)
			( gate "C9N3"
				( objectStatus "@baseboard_fab2_lib.baseboard_fab2(sch_1):page182_i51" )
				( pin "C9N3.1"
					( objectStatus "a" )
				)
				( pin "C9N3.2"
					( objectStatus "b" )
				)
			)
			( gate "C9N16"
				( objectStatus "@baseboard_fab2_lib.baseboard_fab2(sch_1):page182_i52" )
				( pin "C9N16.1"
					( objectStatus "a" )
				)
				( pin "C9N16.2"
					( objectStatus "b" )
				)
			)
			( gate "C9N10"
				( objectStatus "@baseboard_fab2_lib.baseboard_fab2(sch_1):page182_i53" )
				( pin "C9N10.1"
					( objectStatus "a" )
				)
				( pin "C9N10.2"
					( objectStatus "b" )
				)
			)
			( gate "C9N7"
				( objectStatus "@baseboard_fab2_lib.baseboard_fab2(sch_1):page182_i54" )
				( pin "C9N7.1"
					( objectStatus "a" )
				)
				( pin "C9N7.2"
					( objectStatus "b" )
				)
			)
			( gate "C9N4"
				( objectStatus "@baseboard_fab2_lib.baseboard_fab2(sch_1):page182_i55" )
				( pin "C9N4.1"
					( objectStatus "a" )
				)
				( pin "C9N4.2"
					( objectStatus "b" )
				)
			)
			( gate "C9N14"
				( objectStatus "@baseboard_fab2_lib.baseboard_fab2(sch_1):page182_i56" )
				( pin "C9N14.1"
					( objectStatus "a" )
				)
				( pin "C9N14.2"
					( objectStatus "b" )
				)
			)
			( gate "C9N6"
				( objectStatus "@baseboard_fab2_lib.baseboard_fab2(sch_1):page182_i81" )
				( pin "C9N6.1"
					( objectStatus "a" )
				)
				( pin "C9N6.2"
					( objectStatus "b" )
				)
			)
			( gate "C9N5"
				( objectStatus "@baseboard_fab2_lib.baseboard_fab2(sch_1):page182_i83" )
				( pin "C9N5.1"
					( objectStatus "a" )
				)
				( pin "C9N5.2"
					( objectStatus "b" )
				)
			)
			( gate "R1C11"
				( objectStatus "@baseboard_fab2_lib.baseboard_fab2(sch_1):page182_i97" )
				( pin "R1C11.1"
					( objectStatus "a" )
				)
				( pin "R1C11.2"
					( objectStatus "b" )
				)
			)
			( gate "R1C10"
				( objectStatus "@baseboard_fab2_lib.baseboard_fab2(sch_1):page182_i101" )
				( pin "R1C10.1"
					( objectStatus "a" )
				)
				( pin "R1C10.2"
					( objectStatus "b" )
				)
			)
			( gate "R1C9"
				( objectStatus "@baseboard_fab2_lib.baseboard_fab2(sch_1):page182_i104" )
				( pin "R1C9.1"
					( objectStatus "a" )
				)
				( pin "R1C9.2"
					( objectStatus "b" )
				)
			)
			( gate "R1F9"
				( objectStatus "@baseboard_fab2_lib.baseboard_fab2(sch_1):page182_i107" )
				( pin "R1F9.1"
					( objectStatus "a" )
				)
				( pin "R1F9.2"
					( objectStatus "b" )
				)
			)
			( gate "R1C31"
				( objectStatus "@baseboard_fab2_lib.baseboard_fab2(sch_1):page182_i110" )
				( pin "R1C31.1"
					( objectStatus "a" )
				)
				( pin "R1C31.2"
					( objectStatus "b" )
				)
			)
			( gate "EU9F3"
				( objectStatus "@baseboard_fab2_lib.baseboard_fab2(sch_1):page183_i1" )
				( pin "EU9F3.30"
					( objectStatus "a0_cs_n" )
				)
				( pin "EU9F3.31"
					( objectStatus "a1_s1" )
				)
				( pin "EU9F3.25"
					( objectStatus "ctsa_n" )
				)
				( pin "EU9F3.16"
					( objectStatus "ctsb_n" )
				)
				( pin "EU9F3.19"
					( objectStatus "en485_n" )
				)
				( pin "EU9F3.18"
					( objectStatus "enir_n" )
				)
				( pin "EU9F3.12"
					( objectStatus "gnd" )
				)
				( pin "EU9F3.13"
					( objectStatus "gpio0_dsrb_n" )
				)
				( pin "EU9F3.23"
					( objectStatus "gpio1_dtrb_n" )
				)
				( pin "EU9F3.11"
					( objectStatus "gpio2_cdb_n" )
				)
				( pin "EU9F3.14"
					( objectStatus "gpio3_rib_n" )
				)
				( pin "EU9F3.26"
					( objectStatus "gpio4_dsra_n" )
				)
				( pin "EU9F3.22"
					( objectStatus "gpio5_dtra_n" )
				)
				( pin "EU9F3.27"
					( objectStatus "gpio6_cda_n" )
				)
				( pin "EU9F3.28"
					( objectStatus "gpio7_ria_n" )
				)
				( pin "EU9F3.32"
					( objectStatus "i2c_spi_n" )
				)
				( pin "EU9F3.20"
					( objectStatus "irq_n" )
				)
				( pin "EU9F3.1"
					( objectStatus "nc(0)" )
				)
				( pin "EU9F3.8"
					( objectStatus "nc(1)" )
				)
				( pin "EU9F3.24"
					( objectStatus "reset_n" )
				)
				( pin "EU9F3.21"
					( objectStatus "rtsa_n" )
				)
				( pin "EU9F3.15"
					( objectStatus "rtsb_n" )
				)
				( pin "EU9F3.5"
					( objectStatus "rxa" )
				)
				( pin "EU9F3.4"
					( objectStatus "rxb" )
				)
				( pin "EU9F3.17"
					( objectStatus "scl" )
				)
				( pin "EU9F3.3"
					( objectStatus "sda" )
				)
				( pin "EU9F3.2"
					( objectStatus "so" )
				)
				( pin "EU9F3.33"
					( objectStatus "thpad" )
				)
				( pin "EU9F3.6"
					( objectStatus "txa" )
				)
				( pin "EU9F3.7"
					( objectStatus "txb" )
				)
				( pin "EU9F3.29"
					( objectStatus "vdd" )
				)
				( pin "EU9F3.9"
					( objectStatus "xtal1" )
				)
				( pin "EU9F3.10"
					( objectStatus "xtal2" )
				)
			)
			( gate "R9F47"
				( objectStatus "@baseboard_fab2_lib.baseboard_fab2(sch_1):page183_i4" )
				( pin "R9F47.1"
					( objectStatus "a" )
				)
				( pin "R9F47.2"
					( objectStatus "b" )
				)
			)
			( gate "C9F19"
				( objectStatus "@baseboard_fab2_lib.baseboard_fab2(sch_1):page183_i7" )
				( pin "C9F19.1"
					( objectStatus "a" )
				)
				( pin "C9F19.2"
					( objectStatus "b" )
				)
			)
			( gate "R9F50"
				( objectStatus "@baseboard_fab2_lib.baseboard_fab2(sch_1):page183_i11" )
				( pin "R9F50.1"
					( objectStatus "a" )
				)
				( pin "R9F50.2"
					( objectStatus "b" )
				)
			)
			( gate "R9F51"
				( objectStatus "@baseboard_fab2_lib.baseboard_fab2(sch_1):page183_i12" )
				( pin "R9F51.1"
					( objectStatus "a" )
				)
				( pin "R9F51.2"
					( objectStatus "b" )
				)
			)
			( gate "R9F48"
				( objectStatus "@baseboard_fab2_lib.baseboard_fab2(sch_1):page183_i13" )
				( pin "R9F48.1"
					( objectStatus "a" )
				)
				( pin "R9F48.2"
					( objectStatus "b" )
				)
			)
			( gate "R9F49"
				( objectStatus "@baseboard_fab2_lib.baseboard_fab2(sch_1):page183_i14" )
				( pin "R9F49.1"
					( objectStatus "a" )
				)
				( pin "R9F49.2"
					( objectStatus "b" )
				)
			)
			( gate "Y9F1"
				( objectStatus "@baseboard_fab2_lib.baseboard_fab2(sch_1):page183_i19" )
				( pin "Y9F1.1"
					( objectStatus "a" )
				)
				( pin "Y9F1.2"
					( objectStatus "b" )
				)
			)
			( gate "C9F20"
				( objectStatus "@baseboard_fab2_lib.baseboard_fab2(sch_1):page183_i20" )
				( pin "C9F20.1"
					( objectStatus "a" )
				)
				( pin "C9F20.2"
					( objectStatus "b" )
				)
			)
			( gate "C9F21"
				( objectStatus "@baseboard_fab2_lib.baseboard_fab2(sch_1):page183_i21" )
				( pin "C9F21.1"
					( objectStatus "a" )
				)
				( pin "C9F21.2"
					( objectStatus "b" )
				)
			)
			( gate "R9F58"
				( objectStatus "@baseboard_fab2_lib.baseboard_fab2(sch_1):page183_i24" )
				( pin "R9F58.1"
					( objectStatus "a" )
				)
				( pin "R9F58.2"
					( objectStatus "b" )
				)
			)
			( gate "R9F59"
				( objectStatus "@baseboard_fab2_lib.baseboard_fab2(sch_1):page183_i25" )
				( pin "R9F59.1"
					( objectStatus "a" )
				)
				( pin "R9F59.2"
					( objectStatus "b" )
				)
			)
			( gate "R9F55"
				( objectStatus "@baseboard_fab2_lib.baseboard_fab2(sch_1):page183_i30" )
				( pin "R9F55.1"
					( objectStatus "a" )
				)
				( pin "R9F55.2"
					( objectStatus "b" )
				)
			)
			( gate "R9F57"
				( objectStatus "@baseboard_fab2_lib.baseboard_fab2(sch_1):page183_i48" )
				( pin "R9F57.1"
					( objectStatus "a" )
				)
				( pin "R9F57.2"
					( objectStatus "b" )
				)
			)
			( gate "R9F56"
				( objectStatus "@baseboard_fab2_lib.baseboard_fab2(sch_1):page183_i49" )
				( pin "R9F56.1"
					( objectStatus "a" )
				)
				( pin "R9F56.2"
					( objectStatus "b" )
				)
			)
			( gate "R9F54"
				( objectStatus "@baseboard_fab2_lib.baseboard_fab2(sch_1):page183_i52" )
				( pin "R9F54.1"
					( objectStatus "a" )
				)
				( pin "R9F54.2"
					( objectStatus "b" )
				)
			)
			( gate "R9F53"
				( objectStatus "@baseboard_fab2_lib.baseboard_fab2(sch_1):page183_i53" )
				( pin "R9F53.1"
					( objectStatus "a" )
				)
				( pin "R9F53.2"
					( objectStatus "b" )
				)
			)
			( gate "J8E1"
				( objectStatus "@baseboard_fab2_lib.baseboard_fab2(sch_1):page184_i87" )
				( pin "J8E1.1"
					( objectStatus "io1" )
				)
				( pin "J8E1.2"
					( objectStatus "io2" )
				)
				( pin "J8E1.3"
					( objectStatus "io3" )
				)
				( pin "J8E1.4"
					( objectStatus "io4" )
				)
				( pin "J8E1.5"
					( objectStatus "io5" )
				)
				( pin "J8E1.6"
					( objectStatus "io6" )
				)
				( pin "J8E1.7"
					( objectStatus "io7" )
				)
				( pin "J8E1.8"
					( objectStatus "io8" )
				)
				( pin "J8E1.9"
					( objectStatus "io9" )
				)
				( pin "J8E1.10"
					( objectStatus "io10" )
				)
				( pin "J8E1.11"
					( objectStatus "io11" )
				)
				( pin "J8E1.MP1"
					( objectStatus "mp1" )
				)
				( pin "J8E1.MP2"
					( objectStatus "mp2" )
				)
			)
			( gate "R8E9"
				( objectStatus "@baseboard_fab2_lib.baseboard_fab2(sch_1):page184_i88" )
				( pin "R8E9.1"
					( objectStatus "a" )
				)
				( pin "R8E9.2"
					( objectStatus "b" )
				)
			)
			( gate "R8D35"
				( objectStatus "@baseboard_fab2_lib.baseboard_fab2(sch_1):page184_i92" )
				( pin "R8D35.1"
					( objectStatus "a" )
				)
				( pin "R8D35.2"
					( objectStatus "b" )
				)
			)
			( gate "R8E13"
				( objectStatus "@baseboard_fab2_lib.baseboard_fab2(sch_1):page184_i93" )
				( pin "R8E13.1"
					( objectStatus "a" )
				)
				( pin "R8E13.2"
					( objectStatus "b" )
				)
			)
			( gate "R8E10"
				( objectStatus "@baseboard_fab2_lib.baseboard_fab2(sch_1):page184_i95" )
				( pin "R8E10.1"
					( objectStatus "a" )
				)
				( pin "R8E10.2"
					( objectStatus "b" )
				)
			)
			( gate "R8E1"
				( objectStatus "@baseboard_fab2_lib.baseboard_fab2(sch_1):page184_i99" )
				( pin "R8E1.1"
					( objectStatus "a" )
				)
				( pin "R8E1.2"
					( objectStatus "b" )
				)
			)
			( gate "RM8D1"
				( objectStatus "@baseboard_fab2_lib.baseboard_fab2(sch_1):page184_i104" )
				( pin "RM8D1.1"
					( objectStatus "io1" )
				)
			)
			( gate "J8F1"
				( objectStatus "@baseboard_fab2_lib.baseboard_fab2(sch_1):page185_i53" )
				( pin "J8F1.2"
					( objectStatus "\3_3v\(0)" )
				)
				( pin "J8F1.4"
					( objectStatus "\3_3v\(1)" )
				)
				( pin "J8F1.12"
					( objectStatus "\3_3v\(2)" )
				)
				( pin "J8F1.14"
					( objectStatus "\3_3v\(3)" )
				)
				( pin "J8F1.16"
					( objectStatus "\3_3v\(4)" )
				)
				( pin "J8F1.18"
					( objectStatus "\3_3v\(5)" )
				)
				( pin "J8F1.70"
					( objectStatus "\3_3v\(6)" )
				)
				( pin "J8F1.72"
					( objectStatus "\3_3v\(7)" )
				)
				( pin "J8F1.74"
					( objectStatus "\3_3v\(8)" )
				)
				( pin "J8F1.52"
					( objectStatus "clkreq_n_nc" )
				)
				( pin "J8F1.10"
					( objectStatus "das_dss_n" )
				)
				( pin "J8F1.38"
					( objectStatus "devslp" )
				)
				( pin "J8F1.1"
					( objectStatus "gnd(0)" )
				)
				( pin "J8F1.3"
					( objectStatus "gnd(1)" )
				)
				( pin "J8F1.9"
					( objectStatus "gnd(2)" )
				)
				( pin "J8F1.15"
					( objectStatus "gnd(3)" )
				)
				( pin "J8F1.21"
					( objectStatus "gnd(4)" )
				)
				( pin "J8F1.27"
					( objectStatus "gnd(5)" )
				)
				( pin "J8F1.33"
					( objectStatus "gnd(6)" )
				)
				( pin "J8F1.39"
					( objectStatus "gnd(7)" )
				)
				( pin "J8F1.45"
					( objectStatus "gnd(8)" )
				)
				( pin "J8F1.51"
					( objectStatus "gnd(9)" )
				)
				( pin "J8F1.57"
					( objectStatus "gnd(10)" )
				)
				( pin "J8F1.71"
					( objectStatus "gnd(11)" )
				)
				( pin "J8F1.73"
					( objectStatus "gnd(12)" )
				)
				( pin "J8F1.75"
					( objectStatus "gnd(13)" )
				)
				( pin "J8F1.MP1"
					( objectStatus "mp1" )
				)
				( pin "J8F1.MP2"
					( objectStatus "mp2" )
				)
				( pin "J8F1.6"
					( objectStatus "nc(0)" )
				)
				( pin "J8F1.8"
					( objectStatus "nc(1)" )
				)
				( pin "J8F1.20"
					( objectStatus "nc(2)" )
				)
				( pin "J8F1.22"
					( objectStatus "nc(3)" )
				)
				( pin "J8F1.24"
					( objectStatus "nc(4)" )
				)
				( pin "J8F1.26"
					( objectStatus "nc(5)" )
				)
				( pin "J8F1.28"
					( objectStatus "nc(6)" )
				)
				( pin "J8F1.30"
					( objectStatus "nc(7)" )
				)
				( pin "J8F1.32"
					( objectStatus "nc(8)" )
				)
				( pin "J8F1.34"
					( objectStatus "nc(9)" )
				)
				( pin "J8F1.36"
					( objectStatus "nc(10)" )
				)
				( pin "J8F1.40"
					( objectStatus "nc(11)" )
				)
				( pin "J8F1.42"
					( objectStatus "nc(12)" )
				)
				( pin "J8F1.44"
					( objectStatus "nc(13)" )
				)
				( pin "J8F1.46"
					( objectStatus "nc(14)" )
				)
				( pin "J8F1.48"
					( objectStatus "nc(15)" )
				)
				( pin "J8F1.56"
					( objectStatus "nc(16)" )
				)
				( pin "J8F1.58"
					( objectStatus "nc(17)" )
				)
				( pin "J8F1.67"
					( objectStatus "nc(18)" )
				)
				( pin "J8F1.69"
					( objectStatus "pedet" )
				)
				( pin "J8F1.41"
					( objectStatus "pern0_sata_bp" )
				)
				( pin "J8F1.29"
					( objectStatus "pern1" )
				)
				( pin "J8F1.17"
					( objectStatus "pern2" )
				)
				( pin "J8F1.5"
					( objectStatus "pern3" )
				)
				( pin "J8F1.43"
					( objectStatus "perp0_sata_bn" )
				)
				( pin "J8F1.31"
					( objectStatus "perp1" )
				)
				( pin "J8F1.19"
					( objectStatus "perp2" )
				)
				( pin "J8F1.7"
					( objectStatus "perp3" )
				)
				( pin "J8F1.50"
					( objectStatus "perst_n_nc" )
				)
				( pin "J8F1.47"
					( objectStatus "petn0_sata_an" )
				)
				( pin "J8F1.35"
					( objectStatus "petn1" )
				)
				( pin "J8F1.23"
					( objectStatus "petn2" )
				)
				( pin "J8F1.11"
					( objectStatus "petn3" )
				)
				( pin "J8F1.49"
					( objectStatus "petp0_sata_ap" )
				)
				( pin "J8F1.37"
					( objectStatus "petp1" )
				)
				( pin "J8F1.25"
					( objectStatus "petp2" )
				)
				( pin "J8F1.13"
					( objectStatus "petp3" )
				)
				( pin "J8F1.54"
					( objectStatus "pewake_n_nc" )
				)
				( pin "J8F1.53"
					( objectStatus "refclkn" )
				)
				( pin "J8F1.55"
					( objectStatus "refclkp" )
				)
				( pin "J8F1.68"
					( objectStatus "susclk" )
				)
			)
			( gate "C2T11"
				( objectStatus "@baseboard_fab2_lib.baseboard_fab2(sch_1):page185_i62" )
				( pin "C2T11.1"
					( objectStatus "a" )
				)
				( pin "C2T11.2"
					( objectStatus "b" )
				)
			)
			( gate "C2T10"
				( objectStatus "@baseboard_fab2_lib.baseboard_fab2(sch_1):page185_i63" )
				( pin "C2T10.1"
					( objectStatus "a" )
				)
				( pin "C2T10.2"
					( objectStatus "b" )
				)
			)
			( gate "C2T13"
				( objectStatus "@baseboard_fab2_lib.baseboard_fab2(sch_1):page185_i64" )
				( pin "C2T13.1"
					( objectStatus "a" )
				)
				( pin "C2T13.2"
					( objectStatus "b" )
				)
			)
			( gate "C2T14"
				( objectStatus "@baseboard_fab2_lib.baseboard_fab2(sch_1):page185_i65" )
				( pin "C2T14.1"
					( objectStatus "a" )
				)
				( pin "C2T14.2"
					( objectStatus "b" )
				)
			)
			( gate "C2T20"
				( objectStatus "@baseboard_fab2_lib.baseboard_fab2(sch_1):page185_i66" )
				( pin "C2T20.1"
					( objectStatus "a" )
				)
				( pin "C2T20.2"
					( objectStatus "b" )
				)
			)
			( gate "C2T23"
				( objectStatus "@baseboard_fab2_lib.baseboard_fab2(sch_1):page185_i67" )
				( pin "C2T23.1"
					( objectStatus "a" )
				)
				( pin "C2T23.2"
					( objectStatus "b" )
				)
			)
			( gate "C8F15"
				( objectStatus "@baseboard_fab2_lib.baseboard_fab2(sch_1):page185_i90" )
				( pin "C8F15.1"
					( objectStatus "a" )
				)
				( pin "C8F15.2"
					( objectStatus "b" )
				)
			)
			( gate "C8F6"
				( objectStatus "@baseboard_fab2_lib.baseboard_fab2(sch_1):page185_i95" )
				( pin "C8F6.1"
					( objectStatus "a" )
				)
				( pin "C8F6.2"
					( objectStatus "b" )
				)
			)
			( gate "C8F7"
				( objectStatus "@baseboard_fab2_lib.baseboard_fab2(sch_1):page185_i96" )
				( pin "C8F7.1"
					( objectStatus "a" )
				)
				( pin "C8F7.2"
					( objectStatus "b" )
				)
			)
			( gate "C8F11"
				( objectStatus "@baseboard_fab2_lib.baseboard_fab2(sch_1):page185_i97" )
				( pin "C8F11.1"
					( objectStatus "a" )
				)
				( pin "C8F11.2"
					( objectStatus "b" )
				)
			)
			( gate "C8F12"
				( objectStatus "@baseboard_fab2_lib.baseboard_fab2(sch_1):page185_i98" )
				( pin "C8F12.1"
					( objectStatus "a" )
				)
				( pin "C8F12.2"
					( objectStatus "b" )
				)
			)
			( gate "C8F13"
				( objectStatus "@baseboard_fab2_lib.baseboard_fab2(sch_1):page185_i99" )
				( pin "C8F13.1"
					( objectStatus "a" )
				)
				( pin "C8F13.2"
					( objectStatus "b" )
				)
			)
			( gate "R8F18"
				( objectStatus "@baseboard_fab2_lib.baseboard_fab2(sch_1):page185_i105" )
				( pin "R8F18.1"
					( objectStatus "a" )
				)
				( pin "R8F18.2"
					( objectStatus "b" )
				)
			)
			( gate "R8F21"
				( objectStatus "@baseboard_fab2_lib.baseboard_fab2(sch_1):page185_i106" )
				( pin "R8F21.1"
					( objectStatus "a" )
				)
				( pin "R8F21.2"
					( objectStatus "b" )
				)
			)
			( gate "U8D1"
				( objectStatus "@baseboard_fab2_lib.baseboard_fab2(sch_1):page185_i110" )
				( pin "U8D1.2"
					( objectStatus "a" )
				)
				( pin "U8D1.4"
					( objectStatus "y" )
				)
			)
			( gate "R8D18"
				( objectStatus "@baseboard_fab2_lib.baseboard_fab2(sch_1):page185_i111" )
				( pin "R8D18.1"
					( objectStatus "a" )
				)
				( pin "R8D18.2"
					( objectStatus "b" )
				)
			)
			( gate "R8C26"
				( objectStatus "@baseboard_fab2_lib.baseboard_fab2(sch_1):page185_i113" )
				( pin "R8C26.1"
					( objectStatus "a" )
				)
				( pin "R8C26.2"
					( objectStatus "b" )
				)
			)
			( gate "R8C27"
				( objectStatus "@baseboard_fab2_lib.baseboard_fab2(sch_1):page185_i115" )
				( pin "R8C27.1"
					( objectStatus "a" )
				)
				( pin "R8C27.2"
					( objectStatus "b" )
				)
			)
			( gate "C8C7"
				( objectStatus "@baseboard_fab2_lib.baseboard_fab2(sch_1):page185_i117" )
				( pin "C8C7.1"
					( objectStatus "a" )
				)
				( pin "C8C7.2"
					( objectStatus "b" )
				)
			)
			( gate "C2T29"
				( objectStatus "@baseboard_fab2_lib.baseboard_fab2(sch_1):page185_i120" )
				( pin "C2T29.1"
					( objectStatus "a" )
				)
				( pin "C2T29.2"
					( objectStatus "b" )
				)
			)
			( gate "C2T26"
				( objectStatus "@baseboard_fab2_lib.baseboard_fab2(sch_1):page185_i123" )
				( pin "C2T26.1"
					( objectStatus "a" )
				)
				( pin "C2T26.2"
					( objectStatus "b" )
				)
			)
			( gate "C2T21"
				( objectStatus "@baseboard_fab2_lib.baseboard_fab2(sch_1):page185_i124" )
				( pin "C2T21.1"
					( objectStatus "a" )
				)
				( pin "C2T21.2"
					( objectStatus "b" )
				)
			)
			( gate "C2T16"
				( objectStatus "@baseboard_fab2_lib.baseboard_fab2(sch_1):page185_i126" )
				( pin "C2T16.1"
					( objectStatus "a" )
				)
				( pin "C2T16.2"
					( objectStatus "b" )
				)
			)
			( gate "C2T15"
				( objectStatus "@baseboard_fab2_lib.baseboard_fab2(sch_1):page185_i127" )
				( pin "C2T15.1"
					( objectStatus "a" )
				)
				( pin "C2T15.2"
					( objectStatus "b" )
				)
			)
			( gate "C2T24"
				( objectStatus "@baseboard_fab2_lib.baseboard_fab2(sch_1):page185_i129" )
				( pin "C2T24.1"
					( objectStatus "a" )
				)
				( pin "C2T24.2"
					( objectStatus "b" )
				)
			)
			( gate "C2T2"
				( objectStatus "@baseboard_fab2_lib.baseboard_fab2(sch_1):page185_i131" )
				( pin "C2T2.1"
					( objectStatus "a" )
				)
				( pin "C2T2.2"
					( objectStatus "b" )
				)
			)
			( gate "C2T4"
				( objectStatus "@baseboard_fab2_lib.baseboard_fab2(sch_1):page185_i132" )
				( pin "C2T4.1"
					( objectStatus "a" )
				)
				( pin "C2T4.2"
					( objectStatus "b" )
				)
			)
			( gate "C2T5"
				( objectStatus "@baseboard_fab2_lib.baseboard_fab2(sch_1):page185_i135" )
				( pin "C2T5.1"
					( objectStatus "a" )
				)
				( pin "C2T5.2"
					( objectStatus "b" )
				)
			)
			( gate "R1"
				( objectStatus "@baseboard_fab2_lib.baseboard_fab2(sch_1):page185_i136" )
				( pin "R1.1"
					( objectStatus "a" )
				)
				( pin "R1.2"
					( objectStatus "b" )
				)
			)
			( gate "C1M27"
				( objectStatus "@baseboard_fab2_lib.baseboard_fab2(sch_1):page186_i3" )
				( pin "C1M27.1"
					( objectStatus "a" )
				)
				( pin "C1M27.2"
					( objectStatus "b" )
				)
			)
			( gate "C1M26"
				( objectStatus "@baseboard_fab2_lib.baseboard_fab2(sch_1):page186_i6" )
				( pin "C1M26.1"
					( objectStatus "a" )
				)
				( pin "C1M26.2"
					( objectStatus "b" )
				)
			)
			( gate "C1M23"
				( objectStatus "@baseboard_fab2_lib.baseboard_fab2(sch_1):page186_i7" )
				( pin "C1M23.1"
					( objectStatus "a" )
				)
				( pin "C1M23.2"
					( objectStatus "b" )
				)
			)
			( gate "C1M22"
				( objectStatus "@baseboard_fab2_lib.baseboard_fab2(sch_1):page186_i8" )
				( pin "C1M22.1"
					( objectStatus "a" )
				)
				( pin "C1M22.2"
					( objectStatus "b" )
				)
			)
			( gate "C1M24"
				( objectStatus "@baseboard_fab2_lib.baseboard_fab2(sch_1):page186_i10" )
				( pin "C1M24.1"
					( objectStatus "a" )
				)
				( pin "C1M24.2"
					( objectStatus "b" )
				)
			)
			( gate "R1M14"
				( objectStatus "@baseboard_fab2_lib.baseboard_fab2(sch_1):page186_i220" )
				( pin "R1M14.1"
					( objectStatus "a" )
				)
				( pin "R1M14.2"
					( objectStatus "b" )
				)
			)
			( gate "R9B7"
				( objectStatus "@baseboard_fab2_lib.baseboard_fab2(sch_1):page186_i222" )
				( pin "R9B7.1"
					( objectStatus "a" )
				)
				( pin "R9B7.2"
					( objectStatus "b" )
				)
			)
			( gate "C1M20"
				( objectStatus "@baseboard_fab2_lib.baseboard_fab2(sch_1):page186_i270" )
				( pin "C1M20.1"
					( objectStatus "a" )
				)
				( pin "C1M20.2"
					( objectStatus "b" )
				)
			)
			( gate "C1M21"
				( objectStatus "@baseboard_fab2_lib.baseboard_fab2(sch_1):page186_i334" )
				( pin "C1M21.1"
					( objectStatus "a" )
				)
				( pin "C1M21.2"
					( objectStatus "b" )
				)
			)
			( gate "C1M25"
				( objectStatus "@baseboard_fab2_lib.baseboard_fab2(sch_1):page186_i335" )
				( pin "C1M25.1"
					( objectStatus "a" )
				)
				( pin "C1M25.2"
					( objectStatus "b" )
				)
			)
			( gate "J9B3"
				( objectStatus "@baseboard_fab2_lib.baseboard_fab2(sch_1):page186_i336" )
				( pin "J9B3.1"
					( objectStatus "io1" )
				)
				( pin "J9B3.2"
					( objectStatus "io2" )
				)
				( pin "J9B3.3"
					( objectStatus "io3" )
				)
				( pin "J9B3.4"
					( objectStatus "io4" )
				)
				( pin "J9B3.5"
					( objectStatus "io5" )
				)
				( pin "J9B3.6"
					( objectStatus "io6" )
				)
				( pin "J9B3.7"
					( objectStatus "io7" )
				)
				( pin "J9B3.8"
					( objectStatus "io8" )
				)
				( pin "J9B3.9"
					( objectStatus "io9" )
				)
				( pin "J9B3.10"
					( objectStatus "io10" )
				)
				( pin "J9B3.11"
					( objectStatus "io11" )
				)
				( pin "J9B3.12"
					( objectStatus "io12" )
				)
				( pin "J9B3.13"
					( objectStatus "io13" )
				)
				( pin "J9B3.14"
					( objectStatus "io14" )
				)
				( pin "J9B3.15"
					( objectStatus "io15" )
				)
				( pin "J9B3.16"
					( objectStatus "io16" )
				)
				( pin "J9B3.17"
					( objectStatus "io17" )
				)
				( pin "J9B3.18"
					( objectStatus "io18" )
				)
				( pin "J9B3.19"
					( objectStatus "io19" )
				)
				( pin "J9B3.20"
					( objectStatus "io20" )
				)
				( pin "J9B3.21"
					( objectStatus "io21" )
				)
				( pin "J9B3.22"
					( objectStatus "io22" )
				)
				( pin "J9B3.23"
					( objectStatus "io23" )
				)
				( pin "J9B3.24"
					( objectStatus "io24" )
				)
				( pin "J9B3.25"
					( objectStatus "io25" )
				)
				( pin "J9B3.26"
					( objectStatus "io26" )
				)
				( pin "J9B3.27"
					( objectStatus "io27" )
				)
				( pin "J9B3.28"
					( objectStatus "io28" )
				)
				( pin "J9B3.29"
					( objectStatus "io29" )
				)
				( pin "J9B3.30"
					( objectStatus "io30" )
				)
				( pin "J9B3.31"
					( objectStatus "io31" )
				)
				( pin "J9B3.32"
					( objectStatus "io32" )
				)
				( pin "J9B3.33"
					( objectStatus "io33" )
				)
				( pin "J9B3.34"
					( objectStatus "io34" )
				)
				( pin "J9B3.35"
					( objectStatus "io35" )
				)
				( pin "J9B3.36"
					( objectStatus "io36" )
				)
				( pin "J9B3.37"
					( objectStatus "io37" )
				)
				( pin "J9B3.38"
					( objectStatus "io38" )
				)
				( pin "J9B3.39"
					( objectStatus "io39" )
				)
				( pin "J9B3.40"
					( objectStatus "io40" )
				)
				( pin "J9B3.41"
					( objectStatus "io41" )
				)
				( pin "J9B3.42"
					( objectStatus "io42" )
				)
				( pin "J9B3.43"
					( objectStatus "io43" )
				)
				( pin "J9B3.44"
					( objectStatus "io44" )
				)
				( pin "J9B3.45"
					( objectStatus "io45" )
				)
				( pin "J9B3.46"
					( objectStatus "io46" )
				)
				( pin "J9B3.47"
					( objectStatus "io47" )
				)
				( pin "J9B3.48"
					( objectStatus "io48" )
				)
				( pin "J9B3.49"
					( objectStatus "io49" )
				)
				( pin "J9B3.50"
					( objectStatus "io50" )
				)
				( pin "J9B3.51"
					( objectStatus "io51" )
				)
				( pin "J9B3.52"
					( objectStatus "io52" )
				)
				( pin "J9B3.53"
					( objectStatus "io53" )
				)
				( pin "J9B3.54"
					( objectStatus "io54" )
				)
				( pin "J9B3.55"
					( objectStatus "io55" )
				)
				( pin "J9B3.56"
					( objectStatus "io56" )
				)
				( pin "J9B3.57"
					( objectStatus "io57" )
				)
				( pin "J9B3.58"
					( objectStatus "io58" )
				)
				( pin "J9B3.59"
					( objectStatus "io59" )
				)
				( pin "J9B3.60"
					( objectStatus "io60" )
				)
				( pin "J9B3.61"
					( objectStatus "io61" )
				)
				( pin "J9B3.62"
					( objectStatus "io62" )
				)
				( pin "J9B3.63"
					( objectStatus "io63" )
				)
				( pin "J9B3.64"
					( objectStatus "io64" )
				)
				( pin "J9B3.65"
					( objectStatus "io65" )
				)
				( pin "J9B3.66"
					( objectStatus "io66" )
				)
				( pin "J9B3.67"
					( objectStatus "io67" )
				)
				( pin "J9B3.68"
					( objectStatus "io68" )
				)
				( pin "J9B3.69"
					( objectStatus "io69" )
				)
				( pin "J9B3.70"
					( objectStatus "io70" )
				)
				( pin "J9B3.71"
					( objectStatus "io71" )
				)
				( pin "J9B3.72"
					( objectStatus "io72" )
				)
				( pin "J9B3.73"
					( objectStatus "io73" )
				)
				( pin "J9B3.74"
					( objectStatus "io74" )
				)
				( pin "J9B3.75"
					( objectStatus "io75" )
				)
				( pin "J9B3.76"
					( objectStatus "io76" )
				)
				( pin "J9B3.77"
					( objectStatus "io77" )
				)
				( pin "J9B3.78"
					( objectStatus "io78" )
				)
				( pin "J9B3.79"
					( objectStatus "io79" )
				)
				( pin "J9B3.80"
					( objectStatus "io80" )
				)
				( pin "J9B3.81"
					( objectStatus "io81" )
				)
				( pin "J9B3.82"
					( objectStatus "io82" )
				)
				( pin "J9B3.83"
					( objectStatus "io83" )
				)
				( pin "J9B3.84"
					( objectStatus "io84" )
				)
				( pin "J9B3.85"
					( objectStatus "io85" )
				)
				( pin "J9B3.86"
					( objectStatus "io86" )
				)
				( pin "J9B3.87"
					( objectStatus "io87" )
				)
				( pin "J9B3.88"
					( objectStatus "io88" )
				)
				( pin "J9B3.89"
					( objectStatus "io89" )
				)
				( pin "J9B3.90"
					( objectStatus "io90" )
				)
				( pin "J9B3.91"
					( objectStatus "io91" )
				)
				( pin "J9B3.92"
					( objectStatus "io92" )
				)
				( pin "J9B3.93"
					( objectStatus "io93" )
				)
				( pin "J9B3.94"
					( objectStatus "io94" )
				)
				( pin "J9B3.95"
					( objectStatus "io95" )
				)
				( pin "J9B3.96"
					( objectStatus "io96" )
				)
				( pin "J9B3.97"
					( objectStatus "io97" )
				)
				( pin "J9B3.98"
					( objectStatus "io98" )
				)
				( pin "J9B3.99"
					( objectStatus "io99" )
				)
				( pin "J9B3.100"
					( objectStatus "io100" )
				)
				( pin "J9B3.101"
					( objectStatus "io101" )
				)
				( pin "J9B3.102"
					( objectStatus "io102" )
				)
				( pin "J9B3.103"
					( objectStatus "io103" )
				)
				( pin "J9B3.104"
					( objectStatus "io104" )
				)
				( pin "J9B3.105"
					( objectStatus "io105" )
				)
				( pin "J9B3.106"
					( objectStatus "io106" )
				)
				( pin "J9B3.107"
					( objectStatus "io107" )
				)
				( pin "J9B3.108"
					( objectStatus "io108" )
				)
				( pin "J9B3.109"
					( objectStatus "io109" )
				)
				( pin "J9B3.110"
					( objectStatus "io110" )
				)
				( pin "J9B3.111"
					( objectStatus "io111" )
				)
				( pin "J9B3.112"
					( objectStatus "io112" )
				)
				( pin "J9B3.113"
					( objectStatus "io113" )
				)
				( pin "J9B3.114"
					( objectStatus "io114" )
				)
				( pin "J9B3.115"
					( objectStatus "io115" )
				)
				( pin "J9B3.116"
					( objectStatus "io116" )
				)
				( pin "J9B3.117"
					( objectStatus "io117" )
				)
				( pin "J9B3.118"
					( objectStatus "io118" )
				)
				( pin "J9B3.119"
					( objectStatus "io119" )
				)
				( pin "J9B3.120"
					( objectStatus "io120" )
				)
			)
			( gate "R1M16"
				( objectStatus "@baseboard_fab2_lib.baseboard_fab2(sch_1):page186_i337" )
				( pin "R1M16.1"
					( objectStatus "a" )
				)
				( pin "R1M16.2"
					( objectStatus "b" )
				)
			)
			( gate "R1M17"
				( objectStatus "@baseboard_fab2_lib.baseboard_fab2(sch_1):page186_i338" )
				( pin "R1M17.1"
					( objectStatus "a" )
				)
				( pin "R1M17.2"
					( objectStatus "b" )
				)
			)
			( gate "R1M15"
				( objectStatus "@baseboard_fab2_lib.baseboard_fab2(sch_1):page186_i339" )
				( pin "R1M15.1"
					( objectStatus "a" )
				)
				( pin "R1M15.2"
					( objectStatus "b" )
				)
			)
			( gate "R1M18"
				( objectStatus "@baseboard_fab2_lib.baseboard_fab2(sch_1):page186_i340" )
				( pin "R1M18.1"
					( objectStatus "a" )
				)
				( pin "R1M18.2"
					( objectStatus "b" )
				)
			)
			( gate "R2R8"
				( objectStatus "@baseboard_fab2_lib.baseboard_fab2(sch_1):page187_i18" )
				( pin "R2R8.1"
					( objectStatus "a" )
				)
				( pin "R2R8.2"
					( objectStatus "b" )
				)
			)
			( gate "J8E3"
				( objectStatus "@baseboard_fab2_lib.baseboard_fab2(sch_1):page187_i119" )
				( pin "J8E3.1"
					( objectStatus "io1" )
				)
				( pin "J8E3.2"
					( objectStatus "io2" )
				)
				( pin "J8E3.3"
					( objectStatus "io3" )
				)
				( pin "J8E3.4"
					( objectStatus "io4" )
				)
				( pin "J8E3.5"
					( objectStatus "io5" )
				)
				( pin "J8E3.6"
					( objectStatus "io6" )
				)
				( pin "J8E3.7"
					( objectStatus "io7" )
				)
				( pin "J8E3.8"
					( objectStatus "io8" )
				)
				( pin "J8E3.9"
					( objectStatus "io9" )
				)
				( pin "J8E3.10"
					( objectStatus "io10" )
				)
				( pin "J8E3.11"
					( objectStatus "io11" )
				)
				( pin "J8E3.12"
					( objectStatus "io12" )
				)
				( pin "J8E3.13"
					( objectStatus "io13" )
				)
				( pin "J8E3.14"
					( objectStatus "io14" )
				)
				( pin "J8E3.15"
					( objectStatus "io15" )
				)
				( pin "J8E3.16"
					( objectStatus "io16" )
				)
				( pin "J8E3.17"
					( objectStatus "io17" )
				)
				( pin "J8E3.18"
					( objectStatus "io18" )
				)
				( pin "J8E3.19"
					( objectStatus "io19" )
				)
				( pin "J8E3.20"
					( objectStatus "io20" )
				)
				( pin "J8E3.21"
					( objectStatus "io21" )
				)
				( pin "J8E3.22"
					( objectStatus "io22" )
				)
				( pin "J8E3.23"
					( objectStatus "io23" )
				)
				( pin "J8E3.24"
					( objectStatus "io24" )
				)
				( pin "J8E3.25"
					( objectStatus "io25" )
				)
				( pin "J8E3.26"
					( objectStatus "io26" )
				)
				( pin "J8E3.27"
					( objectStatus "io27" )
				)
				( pin "J8E3.28"
					( objectStatus "io28" )
				)
				( pin "J8E3.29"
					( objectStatus "io29" )
				)
				( pin "J8E3.30"
					( objectStatus "io30" )
				)
				( pin "J8E3.31"
					( objectStatus "io31" )
				)
				( pin "J8E3.32"
					( objectStatus "io32" )
				)
				( pin "J8E3.33"
					( objectStatus "io33" )
				)
				( pin "J8E3.34"
					( objectStatus "io34" )
				)
				( pin "J8E3.35"
					( objectStatus "io35" )
				)
				( pin "J8E3.36"
					( objectStatus "io36" )
				)
				( pin "J8E3.37"
					( objectStatus "io37" )
				)
				( pin "J8E3.38"
					( objectStatus "io38" )
				)
				( pin "J8E3.39"
					( objectStatus "io39" )
				)
				( pin "J8E3.40"
					( objectStatus "io40" )
				)
				( pin "J8E3.41"
					( objectStatus "io41" )
				)
				( pin "J8E3.42"
					( objectStatus "io42" )
				)
				( pin "J8E3.43"
					( objectStatus "io43" )
				)
				( pin "J8E3.44"
					( objectStatus "io44" )
				)
				( pin "J8E3.45"
					( objectStatus "io45" )
				)
				( pin "J8E3.46"
					( objectStatus "io46" )
				)
				( pin "J8E3.47"
					( objectStatus "io47" )
				)
				( pin "J8E3.48"
					( objectStatus "io48" )
				)
				( pin "J8E3.49"
					( objectStatus "io49" )
				)
				( pin "J8E3.50"
					( objectStatus "io50" )
				)
				( pin "J8E3.51"
					( objectStatus "io51" )
				)
				( pin "J8E3.52"
					( objectStatus "io52" )
				)
				( pin "J8E3.53"
					( objectStatus "io53" )
				)
				( pin "J8E3.54"
					( objectStatus "io54" )
				)
				( pin "J8E3.55"
					( objectStatus "io55" )
				)
				( pin "J8E3.56"
					( objectStatus "io56" )
				)
				( pin "J8E3.57"
					( objectStatus "io57" )
				)
				( pin "J8E3.58"
					( objectStatus "io58" )
				)
				( pin "J8E3.59"
					( objectStatus "io59" )
				)
				( pin "J8E3.60"
					( objectStatus "io60" )
				)
				( pin "J8E3.61"
					( objectStatus "io61" )
				)
				( pin "J8E3.62"
					( objectStatus "io62" )
				)
				( pin "J8E3.63"
					( objectStatus "io63" )
				)
				( pin "J8E3.64"
					( objectStatus "io64" )
				)
				( pin "J8E3.65"
					( objectStatus "io65" )
				)
				( pin "J8E3.66"
					( objectStatus "io66" )
				)
				( pin "J8E3.67"
					( objectStatus "io67" )
				)
				( pin "J8E3.68"
					( objectStatus "io68" )
				)
				( pin "J8E3.69"
					( objectStatus "io69" )
				)
				( pin "J8E3.70"
					( objectStatus "io70" )
				)
				( pin "J8E3.71"
					( objectStatus "io71" )
				)
				( pin "J8E3.72"
					( objectStatus "io72" )
				)
				( pin "J8E3.73"
					( objectStatus "io73" )
				)
				( pin "J8E3.74"
					( objectStatus "io74" )
				)
				( pin "J8E3.75"
					( objectStatus "io75" )
				)
				( pin "J8E3.76"
					( objectStatus "io76" )
				)
				( pin "J8E3.77"
					( objectStatus "io77" )
				)
				( pin "J8E3.78"
					( objectStatus "io78" )
				)
				( pin "J8E3.79"
					( objectStatus "io79" )
				)
				( pin "J8E3.80"
					( objectStatus "io80" )
				)
			)
			( gate "R9E10"
				( objectStatus "@baseboard_fab2_lib.baseboard_fab2(sch_1):page187_i145" )
				( pin "R9E10.1"
					( objectStatus "a" )
				)
				( pin "R9E10.2"
					( objectStatus "b" )
				)
			)
			( gate "R9E11"
				( objectStatus "@baseboard_fab2_lib.baseboard_fab2(sch_1):page187_i150" )
				( pin "R9E11.1"
					( objectStatus "a" )
				)
				( pin "R9E11.2"
					( objectStatus "b" )
				)
			)
			( gate "R9E12"
				( objectStatus "@baseboard_fab2_lib.baseboard_fab2(sch_1):page187_i153" )
				( pin "R9E12.1"
					( objectStatus "a" )
				)
				( pin "R9E12.2"
					( objectStatus "b" )
				)
			)
			( gate "C6"
				( objectStatus "@baseboard_fab2_lib.baseboard_fab2(sch_1):page188_i2" )
				( pin "C6.1"
					( objectStatus "a" )
				)
				( pin "C6.2"
					( objectStatus "b" )
				)
			)
			( gate "C13"
				( objectStatus "@baseboard_fab2_lib.baseboard_fab2(sch_1):page188_i3" )
				( pin "C13.1"
					( objectStatus "a" )
				)
				( pin "C13.2"
					( objectStatus "b" )
				)
			)
			( gate "C5"
				( objectStatus "@baseboard_fab2_lib.baseboard_fab2(sch_1):page188_i21" )
				( pin "C5.1"
					( objectStatus "a" )
				)
				( pin "C5.2"
					( objectStatus "b" )
				)
			)
			( gate "C4"
				( objectStatus "@baseboard_fab2_lib.baseboard_fab2(sch_1):page188_i23" )
				( pin "C4.1"
					( objectStatus "a" )
				)
				( pin "C4.2"
					( objectStatus "b" )
				)
			)
			( gate "C12"
				( objectStatus "@baseboard_fab2_lib.baseboard_fab2(sch_1):page188_i25" )
				( pin "C12.1"
					( objectStatus "a" )
				)
				( pin "C12.2"
					( objectStatus "b" )
				)
			)
			( gate "J1"
				( objectStatus "@baseboard_fab2_lib.baseboard_fab2(sch_1):page188_i27" )
				( pin "J1.1"
					( objectStatus "io1" )
				)
				( pin "J1.2"
					( objectStatus "io2" )
				)
				( pin "J1.3"
					( objectStatus "io3" )
				)
				( pin "J1.4"
					( objectStatus "io4" )
				)
				( pin "J1.5"
					( objectStatus "io5" )
				)
				( pin "J1.6"
					( objectStatus "io6" )
				)
				( pin "J1.7"
					( objectStatus "io7" )
				)
				( pin "J1.8"
					( objectStatus "io8" )
				)
				( pin "J1.9"
					( objectStatus "io9" )
				)
				( pin "J1.10"
					( objectStatus "io10" )
				)
				( pin "J1.11"
					( objectStatus "io11" )
				)
				( pin "J1.12"
					( objectStatus "io12" )
				)
				( pin "J1.13"
					( objectStatus "io13" )
				)
				( pin "J1.14"
					( objectStatus "io14" )
				)
				( pin "J1.15"
					( objectStatus "io15" )
				)
				( pin "J1.16"
					( objectStatus "io16" )
				)
				( pin "J1.17"
					( objectStatus "io17" )
				)
				( pin "J1.18"
					( objectStatus "io18" )
				)
				( pin "J1.19"
					( objectStatus "io19" )
				)
				( pin "J1.20"
					( objectStatus "io20" )
				)
				( pin "J1.21"
					( objectStatus "io21" )
				)
				( pin "J1.22"
					( objectStatus "io22" )
				)
				( pin "J1.23"
					( objectStatus "io23" )
				)
				( pin "J1.24"
					( objectStatus "io24" )
				)
				( pin "J1.25"
					( objectStatus "io25" )
				)
				( pin "J1.26"
					( objectStatus "io26" )
				)
				( pin "J1.27"
					( objectStatus "io27" )
				)
				( pin "J1.28"
					( objectStatus "io28" )
				)
				( pin "J1.29"
					( objectStatus "io29" )
				)
				( pin "J1.30"
					( objectStatus "io30" )
				)
				( pin "J1.31"
					( objectStatus "io31" )
				)
				( pin "J1.32"
					( objectStatus "io32" )
				)
				( pin "J1.33"
					( objectStatus "io33" )
				)
				( pin "J1.34"
					( objectStatus "io34" )
				)
				( pin "J1.35"
					( objectStatus "io35" )
				)
				( pin "J1.36"
					( objectStatus "io36" )
				)
				( pin "J1.37"
					( objectStatus "io37" )
				)
				( pin "J1.38"
					( objectStatus "io38" )
				)
				( pin "J1.39"
					( objectStatus "io39" )
				)
				( pin "J1.40"
					( objectStatus "io40" )
				)
				( pin "J1.41"
					( objectStatus "io41" )
				)
				( pin "J1.42"
					( objectStatus "io42" )
				)
				( pin "J1.43"
					( objectStatus "io43" )
				)
				( pin "J1.44"
					( objectStatus "io44" )
				)
				( pin "J1.45"
					( objectStatus "io45" )
				)
				( pin "J1.46"
					( objectStatus "io46" )
				)
				( pin "J1.47"
					( objectStatus "io47" )
				)
				( pin "J1.48"
					( objectStatus "io48" )
				)
				( pin "J1.49"
					( objectStatus "io49" )
				)
				( pin "J1.50"
					( objectStatus "io50" )
				)
				( pin "J1.51"
					( objectStatus "io51" )
				)
				( pin "J1.52"
					( objectStatus "io52" )
				)
				( pin "J1.53"
					( objectStatus "io53" )
				)
				( pin "J1.54"
					( objectStatus "io54" )
				)
				( pin "J1.55"
					( objectStatus "io55" )
				)
				( pin "J1.56"
					( objectStatus "io56" )
				)
				( pin "J1.57"
					( objectStatus "io57" )
				)
				( pin "J1.58"
					( objectStatus "io58" )
				)
				( pin "J1.59"
					( objectStatus "io59" )
				)
				( pin "J1.60"
					( objectStatus "io60" )
				)
				( pin "J1.61"
					( objectStatus "io61" )
				)
				( pin "J1.62"
					( objectStatus "io62" )
				)
				( pin "J1.63"
					( objectStatus "io63" )
				)
				( pin "J1.64"
					( objectStatus "io64" )
				)
			)
			( gate "C11"
				( objectStatus "@baseboard_fab2_lib.baseboard_fab2(sch_1):page188_i40" )
				( pin "C11.1"
					( objectStatus "a" )
				)
				( pin "C11.2"
					( objectStatus "b" )
				)
			)
			( gate "C3"
				( objectStatus "@baseboard_fab2_lib.baseboard_fab2(sch_1):page188_i41" )
				( pin "C3.1"
					( objectStatus "a" )
				)
				( pin "C3.2"
					( objectStatus "b" )
				)
			)
			( gate "C10"
				( objectStatus "@baseboard_fab2_lib.baseboard_fab2(sch_1):page188_i53" )
				( pin "C10.1"
					( objectStatus "a" )
				)
				( pin "C10.2"
					( objectStatus "b" )
				)
			)
			( gate "C9"
				( objectStatus "@baseboard_fab2_lib.baseboard_fab2(sch_1):page188_i55" )
				( pin "C9.1"
					( objectStatus "a" )
				)
				( pin "C9.2"
					( objectStatus "b" )
				)
			)
			( gate "C8"
				( objectStatus "@baseboard_fab2_lib.baseboard_fab2(sch_1):page188_i56" )
				( pin "C8.1"
					( objectStatus "a" )
				)
				( pin "C8.2"
					( objectStatus "b" )
				)
			)
			( gate "C7"
				( objectStatus "@baseboard_fab2_lib.baseboard_fab2(sch_1):page188_i57" )
				( pin "C7.1"
					( objectStatus "a" )
				)
				( pin "C7.2"
					( objectStatus "b" )
				)
			)
			( gate "C14"
				( objectStatus "@baseboard_fab2_lib.baseboard_fab2(sch_1):page188_i64" )
				( pin "C14.1"
					( objectStatus "a" )
				)
				( pin "C14.2"
					( objectStatus "b" )
				)
			)
			( gate "C15"
				( objectStatus "@baseboard_fab2_lib.baseboard_fab2(sch_1):page188_i68" )
				( pin "C15.1"
					( objectStatus "a" )
				)
				( pin "C15.2"
					( objectStatus "b" )
				)
			)
			( gate "C16"
				( objectStatus "@baseboard_fab2_lib.baseboard_fab2(sch_1):page188_i72" )
				( pin "C16.1"
					( objectStatus "a" )
				)
				( pin "C16.2"
					( objectStatus "b" )
				)
			)
			( gate "C17"
				( objectStatus "@baseboard_fab2_lib.baseboard_fab2(sch_1):page188_i73" )
				( pin "C17.1"
					( objectStatus "a" )
				)
				( pin "C17.2"
					( objectStatus "b" )
				)
			)
			( gate "C19"
				( objectStatus "@baseboard_fab2_lib.baseboard_fab2(sch_1):page188_i80" )
				( pin "C19.1"
					( objectStatus "a" )
				)
				( pin "C19.2"
					( objectStatus "b" )
				)
			)
			( gate "C20"
				( objectStatus "@baseboard_fab2_lib.baseboard_fab2(sch_1):page188_i81" )
				( pin "C20.1"
					( objectStatus "a" )
				)
				( pin "C20.2"
					( objectStatus "b" )
				)
			)
			( gate "C21"
				( objectStatus "@baseboard_fab2_lib.baseboard_fab2(sch_1):page188_i82" )
				( pin "C21.1"
					( objectStatus "a" )
				)
				( pin "C21.2"
					( objectStatus "b" )
				)
			)
			( gate "C22"
				( objectStatus "@baseboard_fab2_lib.baseboard_fab2(sch_1):page188_i86" )
				( pin "C22.1"
					( objectStatus "a" )
				)
				( pin "C22.2"
					( objectStatus "b" )
				)
			)
			( gate "R47"
				( objectStatus "@baseboard_fab2_lib.baseboard_fab2(sch_1):page188_i88" )
				( pin "R47.1"
					( objectStatus "a" )
				)
				( pin "R47.2"
					( objectStatus "b" )
				)
			)
			( gate "R48"
				( objectStatus "@baseboard_fab2_lib.baseboard_fab2(sch_1):page188_i89" )
				( pin "R48.1"
					( objectStatus "a" )
				)
				( pin "R48.2"
					( objectStatus "b" )
				)
			)
			( gate "R50"
				( objectStatus "@baseboard_fab2_lib.baseboard_fab2(sch_1):page188_i90" )
				( pin "R50.1"
					( objectStatus "a" )
				)
				( pin "R50.2"
					( objectStatus "b" )
				)
			)
			( gate "R49"
				( objectStatus "@baseboard_fab2_lib.baseboard_fab2(sch_1):page188_i91" )
				( pin "R49.1"
					( objectStatus "a" )
				)
				( pin "R49.2"
					( objectStatus "b" )
				)
			)
			( gate "R54"
				( objectStatus "@baseboard_fab2_lib.baseboard_fab2(sch_1):page188_i92" )
				( pin "R54.1"
					( objectStatus "a" )
				)
				( pin "R54.2"
					( objectStatus "b" )
				)
			)
			( gate "R51"
				( objectStatus "@baseboard_fab2_lib.baseboard_fab2(sch_1):page188_i93" )
				( pin "R51.1"
					( objectStatus "a" )
				)
				( pin "R51.2"
					( objectStatus "b" )
				)
			)
			( gate "R52"
				( objectStatus "@baseboard_fab2_lib.baseboard_fab2(sch_1):page188_i94" )
				( pin "R52.1"
					( objectStatus "a" )
				)
				( pin "R52.2"
					( objectStatus "b" )
				)
			)
			( gate "R53"
				( objectStatus "@baseboard_fab2_lib.baseboard_fab2(sch_1):page188_i95" )
				( pin "R53.1"
					( objectStatus "a" )
				)
				( pin "R53.2"
					( objectStatus "b" )
				)
			)
			( gate "R8G10"
				( objectStatus "@baseboard_fab2_lib.baseboard_fab2(sch_1):page189_i7" )
				( pin "R8G10.1"
					( objectStatus "a" )
				)
				( pin "R8G10.2"
					( objectStatus "b" )
				)
			)
			( gate "R7G19"
				( objectStatus "@baseboard_fab2_lib.baseboard_fab2(sch_1):page189_i8" )
				( pin "R7G19.1"
					( objectStatus "a" )
				)
				( pin "R7G19.2"
					( objectStatus "b" )
				)
			)
			( gate "R8G9"
				( objectStatus "@baseboard_fab2_lib.baseboard_fab2(sch_1):page189_i9" )
				( pin "R8G9.1"
					( objectStatus "a" )
				)
				( pin "R8G9.2"
					( objectStatus "b" )
				)
			)
			( gate "R7G18"
				( objectStatus "@baseboard_fab2_lib.baseboard_fab2(sch_1):page189_i13" )
				( pin "R7G18.1"
					( objectStatus "a" )
				)
				( pin "R7G18.2"
					( objectStatus "b" )
				)
			)
			( gate "R8G8"
				( objectStatus "@baseboard_fab2_lib.baseboard_fab2(sch_1):page189_i17" )
				( pin "R8G8.1"
					( objectStatus "a" )
				)
				( pin "R8G8.2"
					( objectStatus "b" )
				)
			)
			( gate "R8G7"
				( objectStatus "@baseboard_fab2_lib.baseboard_fab2(sch_1):page189_i18" )
				( pin "R8G7.1"
					( objectStatus "a" )
				)
				( pin "R8G7.2"
					( objectStatus "b" )
				)
			)
			( gate "R8G11"
				( objectStatus "@baseboard_fab2_lib.baseboard_fab2(sch_1):page189_i19" )
				( pin "R8G11.1"
					( objectStatus "a" )
				)
				( pin "R8G11.2"
					( objectStatus "b" )
				)
			)
			( gate "R8G14"
				( objectStatus "@baseboard_fab2_lib.baseboard_fab2(sch_1):page189_i20" )
				( pin "R8G14.1"
					( objectStatus "a" )
				)
				( pin "R8G14.2"
					( objectStatus "b" )
				)
			)
			( gate "R8G12"
				( objectStatus "@baseboard_fab2_lib.baseboard_fab2(sch_1):page189_i21" )
				( pin "R8G12.1"
					( objectStatus "a" )
				)
				( pin "R8G12.2"
					( objectStatus "b" )
				)
			)
			( gate "R8G16"
				( objectStatus "@baseboard_fab2_lib.baseboard_fab2(sch_1):page189_i22" )
				( pin "R8G16.1"
					( objectStatus "a" )
				)
				( pin "R8G16.2"
					( objectStatus "b" )
				)
			)
			( gate "R8G13"
				( objectStatus "@baseboard_fab2_lib.baseboard_fab2(sch_1):page189_i23" )
				( pin "R8G13.1"
					( objectStatus "a" )
				)
				( pin "R8G13.2"
					( objectStatus "b" )
				)
			)
			( gate "R8G15"
				( objectStatus "@baseboard_fab2_lib.baseboard_fab2(sch_1):page189_i24" )
				( pin "R8G15.1"
					( objectStatus "a" )
				)
				( pin "R8G15.2"
					( objectStatus "b" )
				)
			)
			( gate "R8G17"
				( objectStatus "@baseboard_fab2_lib.baseboard_fab2(sch_1):page189_i25" )
				( pin "R8G17.1"
					( objectStatus "a" )
				)
				( pin "R8G17.2"
					( objectStatus "b" )
				)
			)
			( gate "R8G18"
				( objectStatus "@baseboard_fab2_lib.baseboard_fab2(sch_1):page189_i26" )
				( pin "R8G18.1"
					( objectStatus "a" )
				)
				( pin "R8G18.2"
					( objectStatus "b" )
				)
			)
			( gate "R7G16"
				( objectStatus "@baseboard_fab2_lib.baseboard_fab2(sch_1):page189_i27" )
				( pin "R7G16.1"
					( objectStatus "a" )
				)
				( pin "R7G16.2"
					( objectStatus "b" )
				)
			)
			( gate "R7G15"
				( objectStatus "@baseboard_fab2_lib.baseboard_fab2(sch_1):page189_i36" )
				( pin "R7G15.1"
					( objectStatus "a" )
				)
				( pin "R7G15.2"
					( objectStatus "b" )
				)
			)
			( gate "R7G17"
				( objectStatus "@baseboard_fab2_lib.baseboard_fab2(sch_1):page189_i37" )
				( pin "R7G17.1"
					( objectStatus "a" )
				)
				( pin "R7G17.2"
					( objectStatus "b" )
				)
			)
			( gate "R7G14"
				( objectStatus "@baseboard_fab2_lib.baseboard_fab2(sch_1):page189_i38" )
				( pin "R7G14.1"
					( objectStatus "a" )
				)
				( pin "R7G14.2"
					( objectStatus "b" )
				)
			)
			( gate "R3R15"
				( objectStatus "@baseboard_fab2_lib.baseboard_fab2(sch_1):page189_i44" )
				( pin "R3R15.1"
					( objectStatus "a" )
				)
				( pin "R3R15.2"
					( objectStatus "b" )
				)
			)
			( gate "R3R11"
				( objectStatus "@baseboard_fab2_lib.baseboard_fab2(sch_1):page189_i45" )
				( pin "R3R11.1"
					( objectStatus "a" )
				)
				( pin "R3R11.2"
					( objectStatus "b" )
				)
			)
			( gate "J7G2"
				( objectStatus "@baseboard_fab2_lib.baseboard_fab2(sch_1):page189_i47" )
				( pin "J7G2.1"
					( objectStatus "io1" )
				)
				( pin "J7G2.2"
					( objectStatus "io2" )
				)
				( pin "J7G2.3"
					( objectStatus "io3" )
				)
				( pin "J7G2.4"
					( objectStatus "io4" )
				)
				( pin "J7G2.5"
					( objectStatus "io5" )
				)
				( pin "J7G2.6"
					( objectStatus "io6" )
				)
				( pin "J7G2.7"
					( objectStatus "io7" )
				)
				( pin "J7G2.8"
					( objectStatus "io8" )
				)
			)
			( gate "CR7G1"
				( objectStatus "@baseboard_fab2_lib.baseboard_fab2(sch_1):page189_i49" )
				( pin "CR7G1.2"
					( objectStatus "a" )
				)
				( pin "CR7G1.1"
					( objectStatus "c" )
				)
			)
			( gate "R8G20"
				( objectStatus "@baseboard_fab2_lib.baseboard_fab2(sch_1):page189_i50" )
				( pin "R8G20.1"
					( objectStatus "a" )
				)
				( pin "R8G20.2"
					( objectStatus "b" )
				)
			)
			( gate "R7G23"
				( objectStatus "@baseboard_fab2_lib.baseboard_fab2(sch_1):page189_i51" )
				( pin "R7G23.1"
					( objectStatus "a" )
				)
				( pin "R7G23.2"
					( objectStatus "b" )
				)
			)
			( gate "R7G22"
				( objectStatus "@baseboard_fab2_lib.baseboard_fab2(sch_1):page189_i53" )
				( pin "R7G22.1"
					( objectStatus "a" )
				)
				( pin "R7G22.2"
					( objectStatus "b" )
				)
			)
			( gate "R8G23"
				( objectStatus "@baseboard_fab2_lib.baseboard_fab2(sch_1):page189_i56" )
				( pin "R8G23.1"
					( objectStatus "a" )
				)
				( pin "R8G23.2"
					( objectStatus "b" )
				)
			)
			( gate "R7G21"
				( objectStatus "@baseboard_fab2_lib.baseboard_fab2(sch_1):page189_i63" )
				( pin "R7G21.1"
					( objectStatus "a" )
				)
				( pin "R7G21.2"
					( objectStatus "b" )
				)
			)
			( gate "R8G19"
				( objectStatus "@baseboard_fab2_lib.baseboard_fab2(sch_1):page189_i64" )
				( pin "R8G19.1"
					( objectStatus "a" )
				)
				( pin "R8G19.2"
					( objectStatus "b" )
				)
			)
			( gate "R8G21"
				( objectStatus "@baseboard_fab2_lib.baseboard_fab2(sch_1):page189_i65" )
				( pin "R8G21.1"
					( objectStatus "a" )
				)
				( pin "R8G21.2"
					( objectStatus "b" )
				)
			)
			( gate "R8G22"
				( objectStatus "@baseboard_fab2_lib.baseboard_fab2(sch_1):page189_i66" )
				( pin "R8G22.1"
					( objectStatus "a" )
				)
				( pin "R8G22.2"
					( objectStatus "b" )
				)
			)
			( gate "R3P34"
				( objectStatus "@baseboard_fab2_lib.baseboard_fab2(sch_1):page190_i116" )
				( pin "R3P34.1"
					( objectStatus "a" )
				)
				( pin "R3P34.2"
					( objectStatus "b" )
				)
			)
			( gate "R3P35"
				( objectStatus "@baseboard_fab2_lib.baseboard_fab2(sch_1):page190_i117" )
				( pin "R3P35.1"
					( objectStatus "a" )
				)
				( pin "R3P35.2"
					( objectStatus "b" )
				)
			)
			( gate "U8D7"
				( objectStatus "@baseboard_fab2_lib.baseboard_fab2(sch_1):page190_i179" )
				( pin "U8D7.P4"
					( objectStatus "pb3a" )
				)
				( pin "U8D7.T4"
					( objectStatus "pb3b" )
				)
				( pin "U8D7.T2"
					( objectStatus "pb3c" )
				)
				( pin "U8D7.R3"
					( objectStatus "pb3d" )
				)
				( pin "U8D7.R5"
					( objectStatus "pb5a_csspin" )
				)
				( pin "U8D7.P5"
					( objectStatus "pb5b" )
				)
				( pin "U8D7.T5"
					( objectStatus "pb6a" )
				)
				( pin "U8D7.R6"
					( objectStatus "pb6b" )
				)
				( pin "U8D7.T3"
					( objectStatus "pb6c" )
				)
				( pin "U8D7.R4"
					( objectStatus "pb6d" )
				)
				( pin "U8D7.P6"
					( objectStatus "pb8a_mclk_cclk" )
				)
				( pin "U8D7.T6"
					( objectStatus "pb8b_so_spiso" )
				)
				( pin "U8D7.N6"
					( objectStatus "pb8c" )
				)
				( pin "U8D7.L7"
					( objectStatus "pb8d" )
				)
				( pin "U8D7.R7"
					( objectStatus "pb9a" )
				)
				( pin "U8D7.P7"
					( objectStatus "pb9b" )
				)
				( pin "U8D7.M7"
					( objectStatus "pb9c" )
				)
				( pin "U8D7.N7"
					( objectStatus "pb9d" )
				)
				( pin "U8D7.T7"
					( objectStatus "pb11a_pclkt2_0" )
				)
				( pin "U8D7.R8"
					( objectStatus "pb11b_pclkc2_0" )
				)
				( pin "U8D7.M6"
					( objectStatus "pb11c" )
				)
				( pin "U8D7.L8"
					( objectStatus "pb11d" )
				)
				( pin "U8D7.P8"
					( objectStatus "pb12a" )
				)
				( pin "U8D7.T8"
					( objectStatus "pb12b" )
				)
				( pin "U8D7.N8"
					( objectStatus "pb12c" )
				)
				( pin "U8D7.L9"
					( objectStatus "pb12d" )
				)
				( pin "U8D7.T9"
					( objectStatus "pb16a_pclkt2_1" )
				)
				( pin "U8D7.P9"
					( objectStatus "pb16b_pclkc2_1" )
				)
				( pin "U8D7.M8"
					( objectStatus "pb16c" )
				)
				( pin "U8D7.N9"
					( objectStatus "pb16d" )
				)
				( pin "U8D7.R9"
					( objectStatus "pb18a" )
				)
				( pin "U8D7.T10"
					( objectStatus "pb18b" )
				)
				( pin "U8D7.M9"
					( objectStatus "pb18c" )
				)
				( pin "U8D7.L10"
					( objectStatus "pb18d" )
				)
				( pin "U8D7.P10"
					( objectStatus "pb19a" )
				)
				( pin "U8D7.R10"
					( objectStatus "pb19b" )
				)
				( pin "U8D7.N10"
					( objectStatus "pb19c" )
				)
				( pin "U8D7.M11"
					( objectStatus "pb19d" )
				)
				( pin "U8D7.T11"
					( objectStatus "pb21a" )
				)
				( pin "U8D7.P11"
					( objectStatus "pb21b" )
				)
				( pin "U8D7.M10"
					( objectStatus "pb21c" )
				)
				( pin "U8D7.N11"
					( objectStatus "pb21d" )
				)
				( pin "U8D7.R11"
					( objectStatus "pb22a" )
				)
				( pin "U8D7.T12"
					( objectStatus "pb22b" )
				)
				( pin "U8D7.R13"
					( objectStatus "pb22c" )
				)
				( pin "U8D7.T14"
					( objectStatus "pb22d" )
				)
				( pin "U8D7.P12"
					( objectStatus "pb24a" )
				)
				( pin "U8D7.T13"
					( objectStatus "pb24b" )
				)
				( pin "U8D7.R12"
					( objectStatus "pb25a_sn" )
				)
				( pin "U8D7.P13"
					( objectStatus "pb25b_si_sispi" )
				)
				( pin "U8D7.T15"
					( objectStatus "pb25c" )
				)
				( pin "U8D7.R14"
					( objectStatus "pb25d" )
				)
				( pin "U8D7.D3"
					( objectStatus "pl1a_l_gpllt_fb" )
				)
				( pin "U8D7.D1"
					( objectStatus "pl1b_l_gpllc_fb" )
				)
				( pin "U8D7.B1"
					( objectStatus "pl1c" )
				)
				( pin "U8D7.C2"
					( objectStatus "pl1d" )
				)
				( pin "U8D7.E2"
					( objectStatus "pl2a_l_gpllt_in" )
				)
				( pin "U8D7.E3"
					( objectStatus "pl2b_l_gpllc_in" )
				)
				( pin "U8D7.C1"
					( objectStatus "pl2c" )
				)
				( pin "U8D7.D2"
					( objectStatus "pl2d" )
				)
				( pin "U8D7.E1"
					( objectStatus "pl3a_pclkt5_0" )
				)
				( pin "U8D7.F2"
					( objectStatus "pl3b_pclkc5_0" )
				)
				( pin "U8D7.F4"
					( objectStatus "pl3c" )
				)
				( pin "U8D7.G6"
					( objectStatus "pl3d" )
				)
				( pin "U8D7.F3"
					( objectStatus "pl4a" )
				)
				( pin "U8D7.F1"
					( objectStatus "pl4b" )
				)
				( pin "U8D7.G5"
					( objectStatus "pl4c" )
				)
				( pin "U8D7.G4"
					( objectStatus "pl4d" )
				)
				( pin "U8D7.G2"
					( objectStatus "pl5a" )
				)
				( pin "U8D7.G3"
					( objectStatus "pl5b" )
				)
				( pin "U8D7.F5"
					( objectStatus "pl5c" )
				)
				( pin "U8D7.H6"
					( objectStatus "pl5d" )
				)
				( pin "U8D7.G1"
					( objectStatus "pl6a" )
				)
				( pin "U8D7.H2"
					( objectStatus "pl6b" )
				)
				( pin "U8D7.H4"
					( objectStatus "pl6c" )
				)
				( pin "U8D7.J6"
					( objectStatus "pl6d" )
				)
				( pin "U8D7.H3"
					( objectStatus "pl7a" )
				)
				( pin "U8D7.H1"
					( objectStatus "pl7b" )
				)
				( pin "U8D7.J1"
					( objectStatus "pl7c_pclkt4_0" )
				)
				( pin "U8D7.J3"
					( objectStatus "pl7d_pclkc4_0" )
				)
				( pin "U8D7.J2"
					( objectStatus "pl9a" )
				)
				( pin "U8D7.K1"
					( objectStatus "pl9b" )
				)
				( pin "U8D7.H5"
					( objectStatus "pl9c" )
				)
				( pin "U8D7.J4"
					( objectStatus "pl9d" )
				)
				( pin "U8D7.K3"
					( objectStatus "pl10a" )
				)
				( pin "U8D7.K2"
					( objectStatus "pl10b" )
				)
				( pin "U8D7.J5"
					( objectStatus "pl10c" )
				)
				( pin "U8D7.K6"
					( objectStatus "pl10d" )
				)
				( pin "U8D7.L1"
					( objectStatus "pl11a" )
				)
				( pin "U8D7.L3"
					( objectStatus "pl11b" )
				)
				( pin "U8D7.K4"
					( objectStatus "pl11c" )
				)
				( pin "U8D7.L5"
					( objectStatus "pl11d" )
				)
				( pin "U8D7.L2"
					( objectStatus "pl12a_pclkt3_0" )
				)
				( pin "U8D7.M1"
					( objectStatus "pl12b_pclkc3_0" )
				)
				( pin "U8D7.K5"
					( objectStatus "pl12c" )
				)
				( pin "U8D7.L4"
					( objectStatus "pl12d" )
				)
				( pin "U8D7.M3"
					( objectStatus "pl13a" )
				)
				( pin "U8D7.N1"
					( objectStatus "pl13b" )
				)
				( pin "U8D7.N2"
					( objectStatus "pl13c" )
				)
				( pin "U8D7.P1"
					( objectStatus "pl13d" )
				)
				( pin "U8D7.M2"
					( objectStatus "pl14a" )
				)
				( pin "U8D7.N3"
					( objectStatus "pl14b" )
				)
				( pin "U8D7.R1"
					( objectStatus "pl14c" )
				)
				( pin "U8D7.P2"
					( objectStatus "pl14d" )
				)
			)
			( gate "R2R2"
				( objectStatus "@baseboard_fab2_lib.baseboard_fab2(sch_1):page190_i338" )
				( pin "R2R2.1"
					( objectStatus "a" )
				)
				( pin "R2R2.2"
					( objectStatus "b" )
				)
			)
			( gate "U8D7"
				( objectStatus "@baseboard_fab2_lib.baseboard_fab2(sch_1):page191_i59" )
				( pin "U8D7.D14"
					( objectStatus "pr1a" )
				)
				( pin "U8D7.E15"
					( objectStatus "pr1b" )
				)
				( pin "U8D7.C15"
					( objectStatus "pr1c" )
				)
				( pin "U8D7.B16"
					( objectStatus "pr1d" )
				)
				( pin "U8D7.D16"
					( objectStatus "pr2a" )
				)
				( pin "U8D7.E14"
					( objectStatus "pr2b" )
				)
				( pin "U8D7.C16"
					( objectStatus "pr2c" )
				)
				( pin "U8D7.D15"
					( objectStatus "pr2d" )
				)
				( pin "U8D7.E16"
					( objectStatus "pr3a" )
				)
				( pin "U8D7.F15"
					( objectStatus "pr3b" )
				)
				( pin "U8D7.F13"
					( objectStatus "pr3c" )
				)
				( pin "U8D7.G12"
					( objectStatus "pr3d" )
				)
				( pin "U8D7.F14"
					( objectStatus "pr4a" )
				)
				( pin "U8D7.F16"
					( objectStatus "pr4b" )
				)
				( pin "U8D7.F12"
					( objectStatus "pr4c" )
				)
				( pin "U8D7.G13"
					( objectStatus "pr4d" )
				)
				( pin "U8D7.G15"
					( objectStatus "pr5a" )
				)
				( pin "U8D7.G14"
					( objectStatus "pr5b" )
				)
				( pin "U8D7.G11"
					( objectStatus "pr5c" )
				)
				( pin "U8D7.H12"
					( objectStatus "pr5d" )
				)
				( pin "U8D7.G16"
					( objectStatus "pr6a" )
				)
				( pin "U8D7.H15"
					( objectStatus "pr6b" )
				)
				( pin "U8D7.H13"
					( objectStatus "pr6c" )
				)
				( pin "U8D7.J12"
					( objectStatus "pr6d" )
				)
				( pin "U8D7.H14"
					( objectStatus "pr7a_pclkt1_0" )
				)
				( pin "U8D7.H16"
					( objectStatus "pr7b_pclkc1_0" )
				)
				( pin "U8D7.J16"
					( objectStatus "pr7c" )
				)
				( pin "U8D7.J14"
					( objectStatus "pr7d" )
				)
				( pin "U8D7.J15"
					( objectStatus "pr9a" )
				)
				( pin "U8D7.K16"
					( objectStatus "pr9b" )
				)
				( pin "U8D7.H11"
					( objectStatus "pr9c" )
				)
				( pin "U8D7.J13"
					( objectStatus "pr9d" )
				)
				( pin "U8D7.K14"
					( objectStatus "pr10a" )
				)
				( pin "U8D7.K15"
					( objectStatus "pr10b" )
				)
				( pin "U8D7.J11"
					( objectStatus "pr10c" )
				)
				( pin "U8D7.L12"
					( objectStatus "pr10d" )
				)
				( pin "U8D7.L16"
					( objectStatus "pr11a" )
				)
				( pin "U8D7.L14"
					( objectStatus "pr11b" )
				)
				( pin "U8D7.K13"
					( objectStatus "pr11c" )
				)
				( pin "U8D7.K12"
					( objectStatus "pr11d" )
				)
				( pin "U8D7.L15"
					( objectStatus "pr12a" )
				)
				( pin "U8D7.M16"
					( objectStatus "pr12b" )
				)
				( pin "U8D7.K11"
					( objectStatus "pr12c" )
				)
				( pin "U8D7.L13"
					( objectStatus "pr12d" )
				)
				( pin "U8D7.M14"
					( objectStatus "pr13a" )
				)
				( pin "U8D7.M15"
					( objectStatus "pr13b" )
				)
				( pin "U8D7.N15"
					( objectStatus "pr13c" )
				)
				( pin "U8D7.P16"
					( objectStatus "pr13d" )
				)
				( pin "U8D7.N16"
					( objectStatus "pr14a" )
				)
				( pin "U8D7.N14"
					( objectStatus "pr14b" )
				)
				( pin "U8D7.P15"
					( objectStatus "pr14c" )
				)
				( pin "U8D7.R16"
					( objectStatus "pr14d" )
				)
				( pin "U8D7.C4"
					( objectStatus "pt9a" )
				)
				( pin "U8D7.B5"
					( objectStatus "pt9b" )
				)
				( pin "U8D7.B3"
					( objectStatus "pt9c" )
				)
				( pin "U8D7.A4"
					( objectStatus "pt10a" )
				)
				( pin "U8D7.C5"
					( objectStatus "pt10b" )
				)
				( pin "U8D7.A5"
					( objectStatus "pt11a" )
				)
				( pin "U8D7.B6"
					( objectStatus "pt11b" )
				)
				( pin "U8D7.A3"
					( objectStatus "pt11c" )
				)
				( pin "U8D7.B4"
					( objectStatus "pt11d" )
				)
				( pin "U8D7.D6"
					( objectStatus "pt12a" )
				)
				( pin "U8D7.E7"
					( objectStatus "pt12b" )
				)
				( pin "U8D7.C6"
					( objectStatus "pt12c_tdo" )
				)
				( pin "U8D7.A6"
					( objectStatus "pt12d_tdi" )
				)
				( pin "U8D7.B7"
					( objectStatus "pt13a" )
				)
				( pin "U8D7.C7"
					( objectStatus "pt13b" )
				)
				( pin "U8D7.E6"
					( objectStatus "pt13c" )
				)
				( pin "U8D7.D7"
					( objectStatus "pt13d" )
				)
				( pin "U8D7.F7"
					( objectStatus "pt16a" )
				)
				( pin "U8D7.E8"
					( objectStatus "pt16b" )
				)
				( pin "U8D7.A7"
					( objectStatus "pt16c_tck" )
				)
				( pin "U8D7.B8"
					( objectStatus "pt16d_tms" )
				)
				( pin "U8D7.C8"
					( objectStatus "pt17a_pclkt0_1" )
				)
				( pin "U8D7.A8"
					( objectStatus "pt17b_pclkc0_1" )
				)
				( pin "U8D7.D8"
					( objectStatus "pt17c" )
				)
				( pin "U8D7.E9"
					( objectStatus "pt17d" )
				)
				( pin "U8D7.F8"
					( objectStatus "pt18a" )
				)
				( pin "U8D7.D9"
					( objectStatus "pt18b" )
				)
				( pin "U8D7.A9"
					( objectStatus "pt18c_scl_pclkt0_0" )
				)
				( pin "U8D7.C9"
					( objectStatus "pt18d_sda_pclkc0_0" )
				)
				( pin "U8D7.B9"
					( objectStatus "pt19a" )
				)
				( pin "U8D7.A10"
					( objectStatus "pt19b" )
				)
				( pin "U8D7.F9"
					( objectStatus "pt19c" )
				)
				( pin "U8D7.E11"
					( objectStatus "pt19d" )
				)
				( pin "U8D7.D10"
					( objectStatus "pt20a" )
				)
				( pin "U8D7.E10"
					( objectStatus "pt20b" )
				)
				( pin "U8D7.C10"
					( objectStatus "pt20c_jtagenb" )
				)
				( pin "U8D7.B10"
					( objectStatus "pt20d_programn" )
				)
				( pin "U8D7.A11"
					( objectStatus "pt21a" )
				)
				( pin "U8D7.C11"
					( objectStatus "pt21b" )
				)
				( pin "U8D7.F10"
					( objectStatus "pt21c" )
				)
				( pin "U8D7.D11"
					( objectStatus "pt21d" )
				)
				( pin "U8D7.B11"
					( objectStatus "pt22a" )
				)
				( pin "U8D7.A12"
					( objectStatus "pt22b" )
				)
				( pin "U8D7.B13"
					( objectStatus "pt22c" )
				)
				( pin "U8D7.A14"
					( objectStatus "pt22d" )
				)
				( pin "U8D7.C12"
					( objectStatus "pt23a" )
				)
				( pin "U8D7.B12"
					( objectStatus "pt23b" )
				)
				( pin "U8D7.B14"
					( objectStatus "pt24a" )
				)
				( pin "U8D7.A15"
					( objectStatus "pt24b" )
				)
				( pin "U8D7.A13"
					( objectStatus "pt24c_initn" )
				)
				( pin "U8D7.C13"
					( objectStatus "pt24d_done" )
				)
			)
			( gate "R2R6"
				( objectStatus "@baseboard_fab2_lib.baseboard_fab2(sch_1):page191_i166" )
				( pin "R2R6.1"
					( objectStatus "a" )
				)
				( pin "R2R6.2"
					( objectStatus "b" )
				)
			)
			( gate "R2R7"
				( objectStatus "@baseboard_fab2_lib.baseboard_fab2(sch_1):page191_i172" )
				( pin "R2R7.1"
					( objectStatus "a" )
				)
				( pin "R2R7.2"
					( objectStatus "b" )
				)
			)
			( gate "R2R4"
				( objectStatus "@baseboard_fab2_lib.baseboard_fab2(sch_1):page191_i184" )
				( pin "R2R4.1"
					( objectStatus "a" )
				)
				( pin "R2R4.2"
					( objectStatus "b" )
				)
			)
			( gate "C2P8"
				( objectStatus "@baseboard_fab2_lib.baseboard_fab2(sch_1):page192_i1" )
				( pin "C2P8.1"
					( objectStatus "a" )
				)
				( pin "C2P8.2"
					( objectStatus "b" )
				)
			)
			( gate "C2P5"
				( objectStatus "@baseboard_fab2_lib.baseboard_fab2(sch_1):page192_i3" )
				( pin "C2P5.1"
					( objectStatus "a" )
				)
				( pin "C2P5.2"
					( objectStatus "b" )
				)
			)
			( gate "C3R1"
				( objectStatus "@baseboard_fab2_lib.baseboard_fab2(sch_1):page192_i4" )
				( pin "C3R1.1"
					( objectStatus "a" )
				)
				( pin "C3R1.2"
					( objectStatus "b" )
				)
			)
			( gate "C3P43"
				( objectStatus "@baseboard_fab2_lib.baseboard_fab2(sch_1):page192_i6" )
				( pin "C3P43.1"
					( objectStatus "a" )
				)
				( pin "C3P43.2"
					( objectStatus "b" )
				)
			)
			( gate "C3R3"
				( objectStatus "@baseboard_fab2_lib.baseboard_fab2(sch_1):page192_i7" )
				( pin "C3R3.1"
					( objectStatus "a" )
				)
				( pin "C3R3.2"
					( objectStatus "b" )
				)
			)
			( gate "C2R1"
				( objectStatus "@baseboard_fab2_lib.baseboard_fab2(sch_1):page192_i8" )
				( pin "C2R1.1"
					( objectStatus "a" )
				)
				( pin "C2R1.2"
					( objectStatus "b" )
				)
			)
			( gate "C2P2"
				( objectStatus "@baseboard_fab2_lib.baseboard_fab2(sch_1):page192_i9" )
				( pin "C2P2.1"
					( objectStatus "a" )
				)
				( pin "C2P2.2"
					( objectStatus "b" )
				)
			)
			( gate "C3R2"
				( objectStatus "@baseboard_fab2_lib.baseboard_fab2(sch_1):page192_i10" )
				( pin "C3R2.1"
					( objectStatus "a" )
				)
				( pin "C3R2.2"
					( objectStatus "b" )
				)
			)
			( gate "C3P51"
				( objectStatus "@baseboard_fab2_lib.baseboard_fab2(sch_1):page192_i11" )
				( pin "C3P51.1"
					( objectStatus "a" )
				)
				( pin "C3P51.2"
					( objectStatus "b" )
				)
			)
			( gate "C3P47"
				( objectStatus "@baseboard_fab2_lib.baseboard_fab2(sch_1):page192_i12" )
				( pin "C3P47.1"
					( objectStatus "a" )
				)
				( pin "C3P47.2"
					( objectStatus "b" )
				)
			)
			( gate "U8D7"
				( objectStatus "@baseboard_fab2_lib.baseboard_fab2(sch_1):page192_i14" )
				( pin "U8D7.B2"
					( objectStatus "gnd(0)" )
				)
				( pin "U8D7.B15"
					( objectStatus "gnd(1)" )
				)
				( pin "U8D7.C3"
					( objectStatus "gnd(2)" )
				)
				( pin "U8D7.C14"
					( objectStatus "gnd(3)" )
				)
				( pin "U8D7.D4"
					( objectStatus "gnd(4)" )
				)
				( pin "U8D7.D13"
					( objectStatus "gnd(5)" )
				)
				( pin "U8D7.E5"
					( objectStatus "gnd(6)" )
				)
				( pin "U8D7.E12"
					( objectStatus "gnd(7)" )
				)
				( pin "U8D7.F6"
					( objectStatus "gnd(8)" )
				)
				( pin "U8D7.F11"
					( objectStatus "gnd(9)" )
				)
				( pin "U8D7.H8"
					( objectStatus "gnd(10)" )
				)
				( pin "U8D7.H9"
					( objectStatus "gnd(11)" )
				)
				( pin "U8D7.J8"
					( objectStatus "gnd(12)" )
				)
				( pin "U8D7.J9"
					( objectStatus "gnd(13)" )
				)
				( pin "U8D7.L6"
					( objectStatus "gnd(14)" )
				)
				( pin "U8D7.L11"
					( objectStatus "gnd(15)" )
				)
				( pin "U8D7.M5"
					( objectStatus "gnd(16)" )
				)
				( pin "U8D7.M12"
					( objectStatus "gnd(17)" )
				)
				( pin "U8D7.N4"
					( objectStatus "gnd(18)" )
				)
				( pin "U8D7.N13"
					( objectStatus "gnd(19)" )
				)
				( pin "U8D7.P3"
					( objectStatus "gnd(20)" )
				)
				( pin "U8D7.P14"
					( objectStatus "gnd(21)" )
				)
				( pin "U8D7.R2"
					( objectStatus "gnd(22)" )
				)
				( pin "U8D7.R15"
					( objectStatus "gnd(23)" )
				)
				( pin "U8D7.A2"
					( objectStatus "nc(0)" )
				)
				( pin "U8D7.A1"
					( objectStatus "vcc(0)" )
				)
				( pin "U8D7.A16"
					( objectStatus "vcc(1)" )
				)
				( pin "U8D7.T1"
					( objectStatus "vcc(2)" )
				)
				( pin "U8D7.T16"
					( objectStatus "vcc(3)" )
				)
				( pin "U8D7.G7"
					( objectStatus "vcc(4)" )
				)
				( pin "U8D7.G10"
					( objectStatus "vcc(5)" )
				)
				( pin "U8D7.K7"
					( objectStatus "vcc(6)" )
				)
				( pin "U8D7.K10"
					( objectStatus "vcc(7)" )
				)
				( pin "U8D7.G8"
					( objectStatus "vccio0(0)" )
				)
				( pin "U8D7.D12"
					( objectStatus "vccio0(1)" )
				)
				( pin "U8D7.G9"
					( objectStatus "vccio0(2)" )
				)
				( pin "U8D7.D5"
					( objectStatus "vccio0(3)" )
				)
				( pin "U8D7.E13"
					( objectStatus "vccio1(0)" )
				)
				( pin "U8D7.H10"
					( objectStatus "vccio1(1)" )
				)
				( pin "U8D7.J10"
					( objectStatus "vccio1(2)" )
				)
				( pin "U8D7.M13"
					( objectStatus "vccio1(3)" )
				)
				( pin "U8D7.K9"
					( objectStatus "vccio2(0)" )
				)
				( pin "U8D7.N12"
					( objectStatus "vccio2(1)" )
				)
				( pin "U8D7.K8"
					( objectStatus "vccio2(2)" )
				)
				( pin "U8D7.N5"
					( objectStatus "vccio2(3)" )
				)
				( pin "U8D7.M4"
					( objectStatus "vccio3(0)" )
				)
				( pin "U8D7.J7"
					( objectStatus "vccio4(0)" )
				)
				( pin "U8D7.H7"
					( objectStatus "vccio4(1)" )
				)
				( pin "U8D7.E4"
					( objectStatus "vccio5(0)" )
				)
			)
			( gate "C2R5"
				( objectStatus "@baseboard_fab2_lib.baseboard_fab2(sch_1):page192_i15" )
				( pin "C2R5.1"
					( objectStatus "a" )
				)
				( pin "C2R5.2"
					( objectStatus "b" )
				)
			)
			( gate "C2P4"
				( objectStatus "@baseboard_fab2_lib.baseboard_fab2(sch_1):page192_i16" )
				( pin "C2P4.1"
					( objectStatus "a" )
				)
				( pin "C2P4.2"
					( objectStatus "b" )
				)
			)
			( gate "C3P52"
				( objectStatus "@baseboard_fab2_lib.baseboard_fab2(sch_1):page192_i17" )
				( pin "C3P52.1"
					( objectStatus "a" )
				)
				( pin "C3P52.2"
					( objectStatus "b" )
				)
			)
			( gate "C2P6"
				( objectStatus "@baseboard_fab2_lib.baseboard_fab2(sch_1):page192_i18" )
				( pin "C2P6.1"
					( objectStatus "a" )
				)
				( pin "C2P6.2"
					( objectStatus "b" )
				)
			)
			( gate "C2R3"
				( objectStatus "@baseboard_fab2_lib.baseboard_fab2(sch_1):page192_i19" )
				( pin "C2R3.1"
					( objectStatus "a" )
				)
				( pin "C2R3.2"
					( objectStatus "b" )
				)
			)
			( gate "C2P7"
				( objectStatus "@baseboard_fab2_lib.baseboard_fab2(sch_1):page192_i20" )
				( pin "C2P7.1"
					( objectStatus "a" )
				)
				( pin "C2P7.2"
					( objectStatus "b" )
				)
			)
			( gate "C2R4"
				( objectStatus "@baseboard_fab2_lib.baseboard_fab2(sch_1):page192_i21" )
				( pin "C2R4.1"
					( objectStatus "a" )
				)
				( pin "C2R4.2"
					( objectStatus "b" )
				)
			)
			( gate "C2P3"
				( objectStatus "@baseboard_fab2_lib.baseboard_fab2(sch_1):page192_i22" )
				( pin "C2P3.1"
					( objectStatus "a" )
				)
				( pin "C2P3.2"
					( objectStatus "b" )
				)
			)
			( gate "C3P44"
				( objectStatus "@baseboard_fab2_lib.baseboard_fab2(sch_1):page192_i23" )
				( pin "C3P44.1"
					( objectStatus "a" )
				)
				( pin "C3P44.2"
					( objectStatus "b" )
				)
			)
			( gate "C3P48"
				( objectStatus "@baseboard_fab2_lib.baseboard_fab2(sch_1):page192_i25" )
				( pin "C3P48.1"
					( objectStatus "a" )
				)
				( pin "C3P48.2"
					( objectStatus "b" )
				)
			)
			( gate "C2R2"
				( objectStatus "@baseboard_fab2_lib.baseboard_fab2(sch_1):page192_i28" )
				( pin "C2R2.1"
					( objectStatus "a" )
				)
				( pin "C2R2.2"
					( objectStatus "b" )
				)
			)
			( gate "R7E6"
				( objectStatus "@baseboard_fab2_lib.baseboard_fab2(sch_1):page192_i33" )
				( pin "R7E6.1"
					( objectStatus "a" )
				)
				( pin "R7E6.2"
					( objectStatus "b" )
				)
			)
			( gate "R2R1"
				( objectStatus "@baseboard_fab2_lib.baseboard_fab2(sch_1):page192_i34" )
				( pin "R2R1.1"
					( objectStatus "a" )
				)
				( pin "R2R1.2"
					( objectStatus "b" )
				)
			)
			( gate "R7E5"
				( objectStatus "@baseboard_fab2_lib.baseboard_fab2(sch_1):page192_i38" )
				( pin "R7E5.1"
					( objectStatus "a" )
				)
				( pin "R7E5.2"
					( objectStatus "b" )
				)
			)
			( gate "R2R3"
				( objectStatus "@baseboard_fab2_lib.baseboard_fab2(sch_1):page192_i41" )
				( pin "R2R3.1"
					( objectStatus "a" )
				)
				( pin "R2R3.2"
					( objectStatus "b" )
				)
			)
			( gate "R2P10"
				( objectStatus "@baseboard_fab2_lib.baseboard_fab2(sch_1):page192_i48" )
				( pin "R2P10.1"
					( objectStatus "a" )
				)
				( pin "R2P10.2"
					( objectStatus "b" )
				)
			)
			( gate "R3P33"
				( objectStatus "@baseboard_fab2_lib.baseboard_fab2(sch_1):page192_i49" )
				( pin "R3P33.1"
					( objectStatus "a" )
				)
				( pin "R3P33.2"
					( objectStatus "b" )
				)
			)
			( gate "R55"
				( objectStatus "@baseboard_fab2_lib.baseboard_fab2(sch_1):page192_i55" )
				( pin "R55.1"
					( objectStatus "a" )
				)
				( pin "R55.2"
					( objectStatus "b" )
				)
			)
			( gate "R159"
				( objectStatus "@baseboard_fab2_lib.baseboard_fab2(sch_1):page192_i57" )
				( pin "R159.1"
					( objectStatus "a" )
				)
				( pin "R159.2"
					( objectStatus "b" )
				)
			)
			( gate "R160"
				( objectStatus "@baseboard_fab2_lib.baseboard_fab2(sch_1):page192_i59" )
				( pin "R160.1"
					( objectStatus "a" )
				)
				( pin "R160.2"
					( objectStatus "b" )
				)
			)
			( gate "C4C1"
				( objectStatus "@baseboard_fab2_lib.baseboard_fab2(sch_1):page193_i29" )
				( pin "C4C1.1"
					( objectStatus "a" )
				)
				( pin "C4C1.2"
					( objectStatus "b" )
				)
			)
			( gate "C3C2"
				( objectStatus "@baseboard_fab2_lib.baseboard_fab2(sch_1):page193_i31" )
				( pin "C3C2.1"
					( objectStatus "a" )
				)
				( pin "C3C2.2"
					( objectStatus "b" )
				)
			)
			( gate "C3C1"
				( objectStatus "@baseboard_fab2_lib.baseboard_fab2(sch_1):page193_i38" )
				( pin "C3C1.1"
					( objectStatus "a" )
				)
				( pin "C3C1.2"
					( objectStatus "b" )
				)
			)
			( gate "J4E1"
				( objectStatus "@baseboard_fab2_lib.baseboard_fab2(sch_1):page193_i45" )
				( pin "J4E1.A1"
					( objectStatus "ioa1" )
				)
				( pin "J4E1.A2"
					( objectStatus "ioa2" )
				)
				( pin "J4E1.A3"
					( objectStatus "ioa3" )
				)
				( pin "J4E1.A4"
					( objectStatus "ioa4" )
				)
				( pin "J4E1.A5"
					( objectStatus "ioa5" )
				)
				( pin "J4E1.A6"
					( objectStatus "ioa6" )
				)
				( pin "J4E1.A7"
					( objectStatus "ioa7" )
				)
				( pin "J4E1.A8"
					( objectStatus "ioa8" )
				)
				( pin "J4E1.A9"
					( objectStatus "ioa9" )
				)
				( pin "J4E1.A10"
					( objectStatus "ioa10" )
				)
				( pin "J4E1.A11"
					( objectStatus "ioa11" )
				)
				( pin "J4E1.A12"
					( objectStatus "ioa12" )
				)
				( pin "J4E1.A13"
					( objectStatus "ioa13" )
				)
				( pin "J4E1.A14"
					( objectStatus "ioa14" )
				)
				( pin "J4E1.A15"
					( objectStatus "ioa15" )
				)
				( pin "J4E1.A16"
					( objectStatus "ioa16" )
				)
				( pin "J4E1.A17"
					( objectStatus "ioa17" )
				)
				( pin "J4E1.A18"
					( objectStatus "ioa18" )
				)
				( pin "J4E1.A19"
					( objectStatus "ioa19" )
				)
				( pin "J4E1.A20"
					( objectStatus "ioa20" )
				)
				( pin "J4E1.B1"
					( objectStatus "iob1" )
				)
				( pin "J4E1.B2"
					( objectStatus "iob2" )
				)
				( pin "J4E1.B3"
					( objectStatus "iob3" )
				)
				( pin "J4E1.B4"
					( objectStatus "iob4" )
				)
				( pin "J4E1.B5"
					( objectStatus "iob5" )
				)
				( pin "J4E1.B6"
					( objectStatus "iob6" )
				)
				( pin "J4E1.B7"
					( objectStatus "iob7" )
				)
				( pin "J4E1.B8"
					( objectStatus "iob8" )
				)
				( pin "J4E1.B9"
					( objectStatus "iob9" )
				)
				( pin "J4E1.B10"
					( objectStatus "iob10" )
				)
				( pin "J4E1.B11"
					( objectStatus "iob11" )
				)
				( pin "J4E1.B12"
					( objectStatus "iob12" )
				)
				( pin "J4E1.B13"
					( objectStatus "iob13" )
				)
				( pin "J4E1.B14"
					( objectStatus "iob14" )
				)
				( pin "J4E1.B15"
					( objectStatus "iob15" )
				)
				( pin "J4E1.B16"
					( objectStatus "iob16" )
				)
				( pin "J4E1.B17"
					( objectStatus "iob17" )
				)
				( pin "J4E1.B18"
					( objectStatus "iob18" )
				)
				( pin "J4E1.B19"
					( objectStatus "iob19" )
				)
				( pin "J4E1.B20"
					( objectStatus "iob20" )
				)
				( pin "J4E1.C1"
					( objectStatus "ioc1" )
				)
				( pin "J4E1.C2"
					( objectStatus "ioc2" )
				)
				( pin "J4E1.C3"
					( objectStatus "ioc3" )
				)
				( pin "J4E1.C4"
					( objectStatus "ioc4" )
				)
				( pin "J4E1.C5"
					( objectStatus "ioc5" )
				)
				( pin "J4E1.C6"
					( objectStatus "ioc6" )
				)
				( pin "J4E1.C7"
					( objectStatus "ioc7" )
				)
				( pin "J4E1.C8"
					( objectStatus "ioc8" )
				)
				( pin "J4E1.C9"
					( objectStatus "ioc9" )
				)
				( pin "J4E1.C10"
					( objectStatus "ioc10" )
				)
				( pin "J4E1.C11"
					( objectStatus "ioc11" )
				)
				( pin "J4E1.C12"
					( objectStatus "ioc12" )
				)
				( pin "J4E1.C13"
					( objectStatus "ioc13" )
				)
				( pin "J4E1.C14"
					( objectStatus "ioc14" )
				)
				( pin "J4E1.C15"
					( objectStatus "ioc15" )
				)
				( pin "J4E1.C16"
					( objectStatus "ioc16" )
				)
				( pin "J4E1.C17"
					( objectStatus "ioc17" )
				)
				( pin "J4E1.C18"
					( objectStatus "ioc18" )
				)
				( pin "J4E1.C19"
					( objectStatus "ioc19" )
				)
				( pin "J4E1.C20"
					( objectStatus "ioc20" )
				)
				( pin "J4E1.D1"
					( objectStatus "iod1" )
				)
				( pin "J4E1.D2"
					( objectStatus "iod2" )
				)
				( pin "J4E1.D3"
					( objectStatus "iod3" )
				)
				( pin "J4E1.D4"
					( objectStatus "iod4" )
				)
				( pin "J4E1.D5"
					( objectStatus "iod5" )
				)
				( pin "J4E1.D6"
					( objectStatus "iod6" )
				)
				( pin "J4E1.D7"
					( objectStatus "iod7" )
				)
				( pin "J4E1.D8"
					( objectStatus "iod8" )
				)
				( pin "J4E1.D9"
					( objectStatus "iod9" )
				)
				( pin "J4E1.D10"
					( objectStatus "iod10" )
				)
				( pin "J4E1.D11"
					( objectStatus "iod11" )
				)
				( pin "J4E1.D12"
					( objectStatus "iod12" )
				)
				( pin "J4E1.D13"
					( objectStatus "iod13" )
				)
				( pin "J4E1.D14"
					( objectStatus "iod14" )
				)
				( pin "J4E1.D15"
					( objectStatus "iod15" )
				)
				( pin "J4E1.D16"
					( objectStatus "iod16" )
				)
				( pin "J4E1.D17"
					( objectStatus "iod17" )
				)
				( pin "J4E1.D18"
					( objectStatus "iod18" )
				)
				( pin "J4E1.D19"
					( objectStatus "iod19" )
				)
				( pin "J4E1.D20"
					( objectStatus "iod20" )
				)
				( pin "J4E1.E1"
					( objectStatus "ioe1" )
				)
				( pin "J4E1.E2"
					( objectStatus "ioe2" )
				)
				( pin "J4E1.E3"
					( objectStatus "ioe3" )
				)
				( pin "J4E1.E4"
					( objectStatus "ioe4" )
				)
				( pin "J4E1.E5"
					( objectStatus "ioe5" )
				)
				( pin "J4E1.E6"
					( objectStatus "ioe6" )
				)
				( pin "J4E1.E7"
					( objectStatus "ioe7" )
				)
				( pin "J4E1.E8"
					( objectStatus "ioe8" )
				)
				( pin "J4E1.E9"
					( objectStatus "ioe9" )
				)
				( pin "J4E1.E10"
					( objectStatus "ioe10" )
				)
				( pin "J4E1.E11"
					( objectStatus "ioe11" )
				)
				( pin "J4E1.E12"
					( objectStatus "ioe12" )
				)
				( pin "J4E1.E13"
					( objectStatus "ioe13" )
				)
				( pin "J4E1.E14"
					( objectStatus "ioe14" )
				)
				( pin "J4E1.E15"
					( objectStatus "ioe15" )
				)
				( pin "J4E1.E16"
					( objectStatus "ioe16" )
				)
				( pin "J4E1.E17"
					( objectStatus "ioe17" )
				)
				( pin "J4E1.E18"
					( objectStatus "ioe18" )
				)
				( pin "J4E1.E19"
					( objectStatus "ioe19" )
				)
				( pin "J4E1.E20"
					( objectStatus "ioe20" )
				)
				( pin "J4E1.F1"
					( objectStatus "iof1" )
				)
				( pin "J4E1.F2"
					( objectStatus "iof2" )
				)
				( pin "J4E1.F3"
					( objectStatus "iof3" )
				)
				( pin "J4E1.F4"
					( objectStatus "iof4" )
				)
				( pin "J4E1.F5"
					( objectStatus "iof5" )
				)
				( pin "J4E1.F6"
					( objectStatus "iof6" )
				)
				( pin "J4E1.F7"
					( objectStatus "iof7" )
				)
				( pin "J4E1.F8"
					( objectStatus "iof8" )
				)
				( pin "J4E1.F9"
					( objectStatus "iof9" )
				)
				( pin "J4E1.F10"
					( objectStatus "iof10" )
				)
				( pin "J4E1.F11"
					( objectStatus "iof11" )
				)
				( pin "J4E1.F12"
					( objectStatus "iof12" )
				)
				( pin "J4E1.F13"
					( objectStatus "iof13" )
				)
				( pin "J4E1.F14"
					( objectStatus "iof14" )
				)
				( pin "J4E1.F15"
					( objectStatus "iof15" )
				)
				( pin "J4E1.F16"
					( objectStatus "iof16" )
				)
				( pin "J4E1.F17"
					( objectStatus "iof17" )
				)
				( pin "J4E1.F18"
					( objectStatus "iof18" )
				)
				( pin "J4E1.F19"
					( objectStatus "iof19" )
				)
				( pin "J4E1.F20"
					( objectStatus "iof20" )
				)
			)
			( gate "J4B2"
				( objectStatus "@baseboard_fab2_lib.baseboard_fab2(sch_1):page193_i46" )
				( pin "J4B2.A1"
					( objectStatus "ioa1" )
				)
				( pin "J4B2.A2"
					( objectStatus "ioa2" )
				)
				( pin "J4B2.A3"
					( objectStatus "ioa3" )
				)
				( pin "J4B2.A4"
					( objectStatus "ioa4" )
				)
				( pin "J4B2.A5"
					( objectStatus "ioa5" )
				)
				( pin "J4B2.A6"
					( objectStatus "ioa6" )
				)
				( pin "J4B2.A7"
					( objectStatus "ioa7" )
				)
				( pin "J4B2.A8"
					( objectStatus "ioa8" )
				)
				( pin "J4B2.A9"
					( objectStatus "ioa9" )
				)
				( pin "J4B2.A10"
					( objectStatus "ioa10" )
				)
				( pin "J4B2.A11"
					( objectStatus "ioa11" )
				)
				( pin "J4B2.A12"
					( objectStatus "ioa12" )
				)
				( pin "J4B2.A13"
					( objectStatus "ioa13" )
				)
				( pin "J4B2.A14"
					( objectStatus "ioa14" )
				)
				( pin "J4B2.A15"
					( objectStatus "ioa15" )
				)
				( pin "J4B2.A16"
					( objectStatus "ioa16" )
				)
				( pin "J4B2.A17"
					( objectStatus "ioa17" )
				)
				( pin "J4B2.A18"
					( objectStatus "ioa18" )
				)
				( pin "J4B2.A19"
					( objectStatus "ioa19" )
				)
				( pin "J4B2.A20"
					( objectStatus "ioa20" )
				)
				( pin "J4B2.B1"
					( objectStatus "iob1" )
				)
				( pin "J4B2.B2"
					( objectStatus "iob2" )
				)
				( pin "J4B2.B3"
					( objectStatus "iob3" )
				)
				( pin "J4B2.B4"
					( objectStatus "iob4" )
				)
				( pin "J4B2.B5"
					( objectStatus "iob5" )
				)
				( pin "J4B2.B6"
					( objectStatus "iob6" )
				)
				( pin "J4B2.B7"
					( objectStatus "iob7" )
				)
				( pin "J4B2.B8"
					( objectStatus "iob8" )
				)
				( pin "J4B2.B9"
					( objectStatus "iob9" )
				)
				( pin "J4B2.B10"
					( objectStatus "iob10" )
				)
				( pin "J4B2.B11"
					( objectStatus "iob11" )
				)
				( pin "J4B2.B12"
					( objectStatus "iob12" )
				)
				( pin "J4B2.B13"
					( objectStatus "iob13" )
				)
				( pin "J4B2.B14"
					( objectStatus "iob14" )
				)
				( pin "J4B2.B15"
					( objectStatus "iob15" )
				)
				( pin "J4B2.B16"
					( objectStatus "iob16" )
				)
				( pin "J4B2.B17"
					( objectStatus "iob17" )
				)
				( pin "J4B2.B18"
					( objectStatus "iob18" )
				)
				( pin "J4B2.B19"
					( objectStatus "iob19" )
				)
				( pin "J4B2.B20"
					( objectStatus "iob20" )
				)
				( pin "J4B2.C1"
					( objectStatus "ioc1" )
				)
				( pin "J4B2.C2"
					( objectStatus "ioc2" )
				)
				( pin "J4B2.C3"
					( objectStatus "ioc3" )
				)
				( pin "J4B2.C4"
					( objectStatus "ioc4" )
				)
				( pin "J4B2.C5"
					( objectStatus "ioc5" )
				)
				( pin "J4B2.C6"
					( objectStatus "ioc6" )
				)
				( pin "J4B2.C7"
					( objectStatus "ioc7" )
				)
				( pin "J4B2.C8"
					( objectStatus "ioc8" )
				)
				( pin "J4B2.C9"
					( objectStatus "ioc9" )
				)
				( pin "J4B2.C10"
					( objectStatus "ioc10" )
				)
				( pin "J4B2.C11"
					( objectStatus "ioc11" )
				)
				( pin "J4B2.C12"
					( objectStatus "ioc12" )
				)
				( pin "J4B2.C13"
					( objectStatus "ioc13" )
				)
				( pin "J4B2.C14"
					( objectStatus "ioc14" )
				)
				( pin "J4B2.C15"
					( objectStatus "ioc15" )
				)
				( pin "J4B2.C16"
					( objectStatus "ioc16" )
				)
				( pin "J4B2.C17"
					( objectStatus "ioc17" )
				)
				( pin "J4B2.C18"
					( objectStatus "ioc18" )
				)
				( pin "J4B2.C19"
					( objectStatus "ioc19" )
				)
				( pin "J4B2.C20"
					( objectStatus "ioc20" )
				)
				( pin "J4B2.D1"
					( objectStatus "iod1" )
				)
				( pin "J4B2.D2"
					( objectStatus "iod2" )
				)
				( pin "J4B2.D3"
					( objectStatus "iod3" )
				)
				( pin "J4B2.D4"
					( objectStatus "iod4" )
				)
				( pin "J4B2.D5"
					( objectStatus "iod5" )
				)
				( pin "J4B2.D6"
					( objectStatus "iod6" )
				)
				( pin "J4B2.D7"
					( objectStatus "iod7" )
				)
				( pin "J4B2.D8"
					( objectStatus "iod8" )
				)
				( pin "J4B2.D9"
					( objectStatus "iod9" )
				)
				( pin "J4B2.D10"
					( objectStatus "iod10" )
				)
				( pin "J4B2.D11"
					( objectStatus "iod11" )
				)
				( pin "J4B2.D12"
					( objectStatus "iod12" )
				)
				( pin "J4B2.D13"
					( objectStatus "iod13" )
				)
				( pin "J4B2.D14"
					( objectStatus "iod14" )
				)
				( pin "J4B2.D15"
					( objectStatus "iod15" )
				)
				( pin "J4B2.D16"
					( objectStatus "iod16" )
				)
				( pin "J4B2.D17"
					( objectStatus "iod17" )
				)
				( pin "J4B2.D18"
					( objectStatus "iod18" )
				)
				( pin "J4B2.D19"
					( objectStatus "iod19" )
				)
				( pin "J4B2.D20"
					( objectStatus "iod20" )
				)
				( pin "J4B2.E1"
					( objectStatus "ioe1" )
				)
				( pin "J4B2.E2"
					( objectStatus "ioe2" )
				)
				( pin "J4B2.E3"
					( objectStatus "ioe3" )
				)
				( pin "J4B2.E4"
					( objectStatus "ioe4" )
				)
				( pin "J4B2.E5"
					( objectStatus "ioe5" )
				)
				( pin "J4B2.E6"
					( objectStatus "ioe6" )
				)
				( pin "J4B2.E7"
					( objectStatus "ioe7" )
				)
				( pin "J4B2.E8"
					( objectStatus "ioe8" )
				)
				( pin "J4B2.E9"
					( objectStatus "ioe9" )
				)
				( pin "J4B2.E10"
					( objectStatus "ioe10" )
				)
				( pin "J4B2.E11"
					( objectStatus "ioe11" )
				)
				( pin "J4B2.E12"
					( objectStatus "ioe12" )
				)
				( pin "J4B2.E13"
					( objectStatus "ioe13" )
				)
				( pin "J4B2.E14"
					( objectStatus "ioe14" )
				)
				( pin "J4B2.E15"
					( objectStatus "ioe15" )
				)
				( pin "J4B2.E16"
					( objectStatus "ioe16" )
				)
				( pin "J4B2.E17"
					( objectStatus "ioe17" )
				)
				( pin "J4B2.E18"
					( objectStatus "ioe18" )
				)
				( pin "J4B2.E19"
					( objectStatus "ioe19" )
				)
				( pin "J4B2.E20"
					( objectStatus "ioe20" )
				)
				( pin "J4B2.F1"
					( objectStatus "iof1" )
				)
				( pin "J4B2.F2"
					( objectStatus "iof2" )
				)
				( pin "J4B2.F3"
					( objectStatus "iof3" )
				)
				( pin "J4B2.F4"
					( objectStatus "iof4" )
				)
				( pin "J4B2.F5"
					( objectStatus "iof5" )
				)
				( pin "J4B2.F6"
					( objectStatus "iof6" )
				)
				( pin "J4B2.F7"
					( objectStatus "iof7" )
				)
				( pin "J4B2.F8"
					( objectStatus "iof8" )
				)
				( pin "J4B2.F9"
					( objectStatus "iof9" )
				)
				( pin "J4B2.F10"
					( objectStatus "iof10" )
				)
				( pin "J4B2.F11"
					( objectStatus "iof11" )
				)
				( pin "J4B2.F12"
					( objectStatus "iof12" )
				)
				( pin "J4B2.F13"
					( objectStatus "iof13" )
				)
				( pin "J4B2.F14"
					( objectStatus "iof14" )
				)
				( pin "J4B2.F15"
					( objectStatus "iof15" )
				)
				( pin "J4B2.F16"
					( objectStatus "iof16" )
				)
				( pin "J4B2.F17"
					( objectStatus "iof17" )
				)
				( pin "J4B2.F18"
					( objectStatus "iof18" )
				)
				( pin "J4B2.F19"
					( objectStatus "iof19" )
				)
				( pin "J4B2.F20"
					( objectStatus "iof20" )
				)
			)
			( gate "C4E24"
				( objectStatus "@baseboard_fab2_lib.baseboard_fab2(sch_1):page193_i61" )
				( pin "C4E24.1"
					( objectStatus "a" )
				)
				( pin "C4E24.2"
					( objectStatus "b" )
				)
			)
			( gate "C6R16"
				( objectStatus "@baseboard_fab2_lib.baseboard_fab2(sch_1):page193_i62" )
				( pin "C6R16.1"
					( objectStatus "a" )
				)
				( pin "C6R16.2"
					( objectStatus "b" )
				)
			)
			( gate "C4F1"
				( objectStatus "@baseboard_fab2_lib.baseboard_fab2(sch_1):page193_i68" )
				( pin "C4F1.1"
					( objectStatus "a" )
				)
				( pin "C4F1.2"
					( objectStatus "b" )
				)
			)
			( gate "C4F3"
				( objectStatus "@baseboard_fab2_lib.baseboard_fab2(sch_1):page193_i70" )
				( pin "C4F3.1"
					( objectStatus "a" )
				)
				( pin "C4F3.2"
					( objectStatus "b" )
				)
			)
			( gate "C3F1"
				( objectStatus "@baseboard_fab2_lib.baseboard_fab2(sch_1):page193_i140" )
				( pin "C3F1.1"
					( objectStatus "a" )
				)
				( pin "C3F1.2"
					( objectStatus "b" )
				)
			)
			( gate "C4F2"
				( objectStatus "@baseboard_fab2_lib.baseboard_fab2(sch_1):page193_i141" )
				( pin "C4F2.1"
					( objectStatus "a" )
				)
				( pin "C4F2.2"
					( objectStatus "b" )
				)
			)
			( gate "R83"
				( objectStatus "@baseboard_fab2_lib.baseboard_fab2(sch_1):page193_i169" )
				( pin "R83.1"
					( objectStatus "a" )
				)
				( pin "R83.2"
					( objectStatus "b" )
				)
			)
			( gate "R84"
				( objectStatus "@baseboard_fab2_lib.baseboard_fab2(sch_1):page193_i170" )
				( pin "R84.1"
					( objectStatus "a" )
				)
				( pin "R84.2"
					( objectStatus "b" )
				)
			)
			( gate "C4T2"
				( objectStatus "@baseboard_fab2_lib.baseboard_fab2(sch_1):page194_i9" )
				( pin "C4T2.1"
					( objectStatus "a" )
				)
				( pin "C4T2.2"
					( objectStatus "b" )
				)
			)
			( gate "C4T1"
				( objectStatus "@baseboard_fab2_lib.baseboard_fab2(sch_1):page194_i16" )
				( pin "C4T1.1"
					( objectStatus "a" )
				)
				( pin "C4T1.2"
					( objectStatus "b" )
				)
			)
			( gate "C4R1"
				( objectStatus "@baseboard_fab2_lib.baseboard_fab2(sch_1):page194_i29" )
				( pin "C4R1.1"
					( objectStatus "a" )
				)
				( pin "C4R1.2"
					( objectStatus "b" )
				)
			)
			( gate "C3R4"
				( objectStatus "@baseboard_fab2_lib.baseboard_fab2(sch_1):page194_i31" )
				( pin "C3R4.1"
					( objectStatus "a" )
				)
				( pin "C3R4.2"
					( objectStatus "b" )
				)
			)
			( gate "J6E1"
				( objectStatus "@baseboard_fab2_lib.baseboard_fab2(sch_1):page194_i55" )
				( pin "J6E1.A1"
					( objectStatus "ioa1" )
				)
				( pin "J6E1.A2"
					( objectStatus "ioa2" )
				)
				( pin "J6E1.A3"
					( objectStatus "ioa3" )
				)
				( pin "J6E1.A4"
					( objectStatus "ioa4" )
				)
				( pin "J6E1.A5"
					( objectStatus "ioa5" )
				)
				( pin "J6E1.A6"
					( objectStatus "ioa6" )
				)
				( pin "J6E1.A7"
					( objectStatus "ioa7" )
				)
				( pin "J6E1.A8"
					( objectStatus "ioa8" )
				)
				( pin "J6E1.A9"
					( objectStatus "ioa9" )
				)
				( pin "J6E1.A10"
					( objectStatus "ioa10" )
				)
				( pin "J6E1.A11"
					( objectStatus "ioa11" )
				)
				( pin "J6E1.A12"
					( objectStatus "ioa12" )
				)
				( pin "J6E1.A13"
					( objectStatus "ioa13" )
				)
				( pin "J6E1.A14"
					( objectStatus "ioa14" )
				)
				( pin "J6E1.A15"
					( objectStatus "ioa15" )
				)
				( pin "J6E1.A16"
					( objectStatus "ioa16" )
				)
				( pin "J6E1.A17"
					( objectStatus "ioa17" )
				)
				( pin "J6E1.A18"
					( objectStatus "ioa18" )
				)
				( pin "J6E1.A19"
					( objectStatus "ioa19" )
				)
				( pin "J6E1.A20"
					( objectStatus "ioa20" )
				)
				( pin "J6E1.B1"
					( objectStatus "iob1" )
				)
				( pin "J6E1.B2"
					( objectStatus "iob2" )
				)
				( pin "J6E1.B3"
					( objectStatus "iob3" )
				)
				( pin "J6E1.B4"
					( objectStatus "iob4" )
				)
				( pin "J6E1.B5"
					( objectStatus "iob5" )
				)
				( pin "J6E1.B6"
					( objectStatus "iob6" )
				)
				( pin "J6E1.B7"
					( objectStatus "iob7" )
				)
				( pin "J6E1.B8"
					( objectStatus "iob8" )
				)
				( pin "J6E1.B9"
					( objectStatus "iob9" )
				)
				( pin "J6E1.B10"
					( objectStatus "iob10" )
				)
				( pin "J6E1.B11"
					( objectStatus "iob11" )
				)
				( pin "J6E1.B12"
					( objectStatus "iob12" )
				)
				( pin "J6E1.B13"
					( objectStatus "iob13" )
				)
				( pin "J6E1.B14"
					( objectStatus "iob14" )
				)
				( pin "J6E1.B15"
					( objectStatus "iob15" )
				)
				( pin "J6E1.B16"
					( objectStatus "iob16" )
				)
				( pin "J6E1.B17"
					( objectStatus "iob17" )
				)
				( pin "J6E1.B18"
					( objectStatus "iob18" )
				)
				( pin "J6E1.B19"
					( objectStatus "iob19" )
				)
				( pin "J6E1.B20"
					( objectStatus "iob20" )
				)
				( pin "J6E1.C1"
					( objectStatus "ioc1" )
				)
				( pin "J6E1.C2"
					( objectStatus "ioc2" )
				)
				( pin "J6E1.C3"
					( objectStatus "ioc3" )
				)
				( pin "J6E1.C4"
					( objectStatus "ioc4" )
				)
				( pin "J6E1.C5"
					( objectStatus "ioc5" )
				)
				( pin "J6E1.C6"
					( objectStatus "ioc6" )
				)
				( pin "J6E1.C7"
					( objectStatus "ioc7" )
				)
				( pin "J6E1.C8"
					( objectStatus "ioc8" )
				)
				( pin "J6E1.C9"
					( objectStatus "ioc9" )
				)
				( pin "J6E1.C10"
					( objectStatus "ioc10" )
				)
				( pin "J6E1.C11"
					( objectStatus "ioc11" )
				)
				( pin "J6E1.C12"
					( objectStatus "ioc12" )
				)
				( pin "J6E1.C13"
					( objectStatus "ioc13" )
				)
				( pin "J6E1.C14"
					( objectStatus "ioc14" )
				)
				( pin "J6E1.C15"
					( objectStatus "ioc15" )
				)
				( pin "J6E1.C16"
					( objectStatus "ioc16" )
				)
				( pin "J6E1.C17"
					( objectStatus "ioc17" )
				)
				( pin "J6E1.C18"
					( objectStatus "ioc18" )
				)
				( pin "J6E1.C19"
					( objectStatus "ioc19" )
				)
				( pin "J6E1.C20"
					( objectStatus "ioc20" )
				)
				( pin "J6E1.D1"
					( objectStatus "iod1" )
				)
				( pin "J6E1.D2"
					( objectStatus "iod2" )
				)
				( pin "J6E1.D3"
					( objectStatus "iod3" )
				)
				( pin "J6E1.D4"
					( objectStatus "iod4" )
				)
				( pin "J6E1.D5"
					( objectStatus "iod5" )
				)
				( pin "J6E1.D6"
					( objectStatus "iod6" )
				)
				( pin "J6E1.D7"
					( objectStatus "iod7" )
				)
				( pin "J6E1.D8"
					( objectStatus "iod8" )
				)
				( pin "J6E1.D9"
					( objectStatus "iod9" )
				)
				( pin "J6E1.D10"
					( objectStatus "iod10" )
				)
				( pin "J6E1.D11"
					( objectStatus "iod11" )
				)
				( pin "J6E1.D12"
					( objectStatus "iod12" )
				)
				( pin "J6E1.D13"
					( objectStatus "iod13" )
				)
				( pin "J6E1.D14"
					( objectStatus "iod14" )
				)
				( pin "J6E1.D15"
					( objectStatus "iod15" )
				)
				( pin "J6E1.D16"
					( objectStatus "iod16" )
				)
				( pin "J6E1.D17"
					( objectStatus "iod17" )
				)
				( pin "J6E1.D18"
					( objectStatus "iod18" )
				)
				( pin "J6E1.D19"
					( objectStatus "iod19" )
				)
				( pin "J6E1.D20"
					( objectStatus "iod20" )
				)
				( pin "J6E1.E1"
					( objectStatus "ioe1" )
				)
				( pin "J6E1.E2"
					( objectStatus "ioe2" )
				)
				( pin "J6E1.E3"
					( objectStatus "ioe3" )
				)
				( pin "J6E1.E4"
					( objectStatus "ioe4" )
				)
				( pin "J6E1.E5"
					( objectStatus "ioe5" )
				)
				( pin "J6E1.E6"
					( objectStatus "ioe6" )
				)
				( pin "J6E1.E7"
					( objectStatus "ioe7" )
				)
				( pin "J6E1.E8"
					( objectStatus "ioe8" )
				)
				( pin "J6E1.E9"
					( objectStatus "ioe9" )
				)
				( pin "J6E1.E10"
					( objectStatus "ioe10" )
				)
				( pin "J6E1.E11"
					( objectStatus "ioe11" )
				)
				( pin "J6E1.E12"
					( objectStatus "ioe12" )
				)
				( pin "J6E1.E13"
					( objectStatus "ioe13" )
				)
				( pin "J6E1.E14"
					( objectStatus "ioe14" )
				)
				( pin "J6E1.E15"
					( objectStatus "ioe15" )
				)
				( pin "J6E1.E16"
					( objectStatus "ioe16" )
				)
				( pin "J6E1.E17"
					( objectStatus "ioe17" )
				)
				( pin "J6E1.E18"
					( objectStatus "ioe18" )
				)
				( pin "J6E1.E19"
					( objectStatus "ioe19" )
				)
				( pin "J6E1.E20"
					( objectStatus "ioe20" )
				)
				( pin "J6E1.F1"
					( objectStatus "iof1" )
				)
				( pin "J6E1.F2"
					( objectStatus "iof2" )
				)
				( pin "J6E1.F3"
					( objectStatus "iof3" )
				)
				( pin "J6E1.F4"
					( objectStatus "iof4" )
				)
				( pin "J6E1.F5"
					( objectStatus "iof5" )
				)
				( pin "J6E1.F6"
					( objectStatus "iof6" )
				)
				( pin "J6E1.F7"
					( objectStatus "iof7" )
				)
				( pin "J6E1.F8"
					( objectStatus "iof8" )
				)
				( pin "J6E1.F9"
					( objectStatus "iof9" )
				)
				( pin "J6E1.F10"
					( objectStatus "iof10" )
				)
				( pin "J6E1.F11"
					( objectStatus "iof11" )
				)
				( pin "J6E1.F12"
					( objectStatus "iof12" )
				)
				( pin "J6E1.F13"
					( objectStatus "iof13" )
				)
				( pin "J6E1.F14"
					( objectStatus "iof14" )
				)
				( pin "J6E1.F15"
					( objectStatus "iof15" )
				)
				( pin "J6E1.F16"
					( objectStatus "iof16" )
				)
				( pin "J6E1.F17"
					( objectStatus "iof17" )
				)
				( pin "J6E1.F18"
					( objectStatus "iof18" )
				)
				( pin "J6E1.F19"
					( objectStatus "iof19" )
				)
				( pin "J6E1.F20"
					( objectStatus "iof20" )
				)
			)
			( gate "J6B1"
				( objectStatus "@baseboard_fab2_lib.baseboard_fab2(sch_1):page194_i56" )
				( pin "J6B1.A1"
					( objectStatus "ioa1" )
				)
				( pin "J6B1.A2"
					( objectStatus "ioa2" )
				)
				( pin "J6B1.A3"
					( objectStatus "ioa3" )
				)
				( pin "J6B1.A4"
					( objectStatus "ioa4" )
				)
				( pin "J6B1.A5"
					( objectStatus "ioa5" )
				)
				( pin "J6B1.A6"
					( objectStatus "ioa6" )
				)
				( pin "J6B1.A7"
					( objectStatus "ioa7" )
				)
				( pin "J6B1.A8"
					( objectStatus "ioa8" )
				)
				( pin "J6B1.A9"
					( objectStatus "ioa9" )
				)
				( pin "J6B1.A10"
					( objectStatus "ioa10" )
				)
				( pin "J6B1.A11"
					( objectStatus "ioa11" )
				)
				( pin "J6B1.A12"
					( objectStatus "ioa12" )
				)
				( pin "J6B1.A13"
					( objectStatus "ioa13" )
				)
				( pin "J6B1.A14"
					( objectStatus "ioa14" )
				)
				( pin "J6B1.A15"
					( objectStatus "ioa15" )
				)
				( pin "J6B1.A16"
					( objectStatus "ioa16" )
				)
				( pin "J6B1.A17"
					( objectStatus "ioa17" )
				)
				( pin "J6B1.A18"
					( objectStatus "ioa18" )
				)
				( pin "J6B1.A19"
					( objectStatus "ioa19" )
				)
				( pin "J6B1.A20"
					( objectStatus "ioa20" )
				)
				( pin "J6B1.B1"
					( objectStatus "iob1" )
				)
				( pin "J6B1.B2"
					( objectStatus "iob2" )
				)
				( pin "J6B1.B3"
					( objectStatus "iob3" )
				)
				( pin "J6B1.B4"
					( objectStatus "iob4" )
				)
				( pin "J6B1.B5"
					( objectStatus "iob5" )
				)
				( pin "J6B1.B6"
					( objectStatus "iob6" )
				)
				( pin "J6B1.B7"
					( objectStatus "iob7" )
				)
				( pin "J6B1.B8"
					( objectStatus "iob8" )
				)
				( pin "J6B1.B9"
					( objectStatus "iob9" )
				)
				( pin "J6B1.B10"
					( objectStatus "iob10" )
				)
				( pin "J6B1.B11"
					( objectStatus "iob11" )
				)
				( pin "J6B1.B12"
					( objectStatus "iob12" )
				)
				( pin "J6B1.B13"
					( objectStatus "iob13" )
				)
				( pin "J6B1.B14"
					( objectStatus "iob14" )
				)
				( pin "J6B1.B15"
					( objectStatus "iob15" )
				)
				( pin "J6B1.B16"
					( objectStatus "iob16" )
				)
				( pin "J6B1.B17"
					( objectStatus "iob17" )
				)
				( pin "J6B1.B18"
					( objectStatus "iob18" )
				)
				( pin "J6B1.B19"
					( objectStatus "iob19" )
				)
				( pin "J6B1.B20"
					( objectStatus "iob20" )
				)
				( pin "J6B1.C1"
					( objectStatus "ioc1" )
				)
				( pin "J6B1.C2"
					( objectStatus "ioc2" )
				)
				( pin "J6B1.C3"
					( objectStatus "ioc3" )
				)
				( pin "J6B1.C4"
					( objectStatus "ioc4" )
				)
				( pin "J6B1.C5"
					( objectStatus "ioc5" )
				)
				( pin "J6B1.C6"
					( objectStatus "ioc6" )
				)
				( pin "J6B1.C7"
					( objectStatus "ioc7" )
				)
				( pin "J6B1.C8"
					( objectStatus "ioc8" )
				)
				( pin "J6B1.C9"
					( objectStatus "ioc9" )
				)
				( pin "J6B1.C10"
					( objectStatus "ioc10" )
				)
				( pin "J6B1.C11"
					( objectStatus "ioc11" )
				)
				( pin "J6B1.C12"
					( objectStatus "ioc12" )
				)
				( pin "J6B1.C13"
					( objectStatus "ioc13" )
				)
				( pin "J6B1.C14"
					( objectStatus "ioc14" )
				)
				( pin "J6B1.C15"
					( objectStatus "ioc15" )
				)
				( pin "J6B1.C16"
					( objectStatus "ioc16" )
				)
				( pin "J6B1.C17"
					( objectStatus "ioc17" )
				)
				( pin "J6B1.C18"
					( objectStatus "ioc18" )
				)
				( pin "J6B1.C19"
					( objectStatus "ioc19" )
				)
				( pin "J6B1.C20"
					( objectStatus "ioc20" )
				)
				( pin "J6B1.D1"
					( objectStatus "iod1" )
				)
				( pin "J6B1.D2"
					( objectStatus "iod2" )
				)
				( pin "J6B1.D3"
					( objectStatus "iod3" )
				)
				( pin "J6B1.D4"
					( objectStatus "iod4" )
				)
				( pin "J6B1.D5"
					( objectStatus "iod5" )
				)
				( pin "J6B1.D6"
					( objectStatus "iod6" )
				)
				( pin "J6B1.D7"
					( objectStatus "iod7" )
				)
				( pin "J6B1.D8"
					( objectStatus "iod8" )
				)
				( pin "J6B1.D9"
					( objectStatus "iod9" )
				)
				( pin "J6B1.D10"
					( objectStatus "iod10" )
				)
				( pin "J6B1.D11"
					( objectStatus "iod11" )
				)
				( pin "J6B1.D12"
					( objectStatus "iod12" )
				)
				( pin "J6B1.D13"
					( objectStatus "iod13" )
				)
				( pin "J6B1.D14"
					( objectStatus "iod14" )
				)
				( pin "J6B1.D15"
					( objectStatus "iod15" )
				)
				( pin "J6B1.D16"
					( objectStatus "iod16" )
				)
				( pin "J6B1.D17"
					( objectStatus "iod17" )
				)
				( pin "J6B1.D18"
					( objectStatus "iod18" )
				)
				( pin "J6B1.D19"
					( objectStatus "iod19" )
				)
				( pin "J6B1.D20"
					( objectStatus "iod20" )
				)
				( pin "J6B1.E1"
					( objectStatus "ioe1" )
				)
				( pin "J6B1.E2"
					( objectStatus "ioe2" )
				)
				( pin "J6B1.E3"
					( objectStatus "ioe3" )
				)
				( pin "J6B1.E4"
					( objectStatus "ioe4" )
				)
				( pin "J6B1.E5"
					( objectStatus "ioe5" )
				)
				( pin "J6B1.E6"
					( objectStatus "ioe6" )
				)
				( pin "J6B1.E7"
					( objectStatus "ioe7" )
				)
				( pin "J6B1.E8"
					( objectStatus "ioe8" )
				)
				( pin "J6B1.E9"
					( objectStatus "ioe9" )
				)
				( pin "J6B1.E10"
					( objectStatus "ioe10" )
				)
				( pin "J6B1.E11"
					( objectStatus "ioe11" )
				)
				( pin "J6B1.E12"
					( objectStatus "ioe12" )
				)
				( pin "J6B1.E13"
					( objectStatus "ioe13" )
				)
				( pin "J6B1.E14"
					( objectStatus "ioe14" )
				)
				( pin "J6B1.E15"
					( objectStatus "ioe15" )
				)
				( pin "J6B1.E16"
					( objectStatus "ioe16" )
				)
				( pin "J6B1.E17"
					( objectStatus "ioe17" )
				)
				( pin "J6B1.E18"
					( objectStatus "ioe18" )
				)
				( pin "J6B1.E19"
					( objectStatus "ioe19" )
				)
				( pin "J6B1.E20"
					( objectStatus "ioe20" )
				)
				( pin "J6B1.F1"
					( objectStatus "iof1" )
				)
				( pin "J6B1.F2"
					( objectStatus "iof2" )
				)
				( pin "J6B1.F3"
					( objectStatus "iof3" )
				)
				( pin "J6B1.F4"
					( objectStatus "iof4" )
				)
				( pin "J6B1.F5"
					( objectStatus "iof5" )
				)
				( pin "J6B1.F6"
					( objectStatus "iof6" )
				)
				( pin "J6B1.F7"
					( objectStatus "iof7" )
				)
				( pin "J6B1.F8"
					( objectStatus "iof8" )
				)
				( pin "J6B1.F9"
					( objectStatus "iof9" )
				)
				( pin "J6B1.F10"
					( objectStatus "iof10" )
				)
				( pin "J6B1.F11"
					( objectStatus "iof11" )
				)
				( pin "J6B1.F12"
					( objectStatus "iof12" )
				)
				( pin "J6B1.F13"
					( objectStatus "iof13" )
				)
				( pin "J6B1.F14"
					( objectStatus "iof14" )
				)
				( pin "J6B1.F15"
					( objectStatus "iof15" )
				)
				( pin "J6B1.F16"
					( objectStatus "iof16" )
				)
				( pin "J6B1.F17"
					( objectStatus "iof17" )
				)
				( pin "J6B1.F18"
					( objectStatus "iof18" )
				)
				( pin "J6B1.F19"
					( objectStatus "iof19" )
				)
				( pin "J6B1.F20"
					( objectStatus "iof20" )
				)
			)
			( gate "C3P9"
				( objectStatus "@baseboard_fab2_lib.baseboard_fab2(sch_1):page194_i86" )
				( pin "C3P9.1"
					( objectStatus "a" )
				)
				( pin "C3P9.2"
					( objectStatus "b" )
				)
			)
			( gate "C3P8"
				( objectStatus "@baseboard_fab2_lib.baseboard_fab2(sch_1):page194_i99" )
				( pin "C3P8.1"
					( objectStatus "a" )
				)
				( pin "C3P8.2"
					( objectStatus "b" )
				)
			)
			( gate "C3N14"
				( objectStatus "@baseboard_fab2_lib.baseboard_fab2(sch_1):page194_i101" )
				( pin "C3N14.1"
					( objectStatus "a" )
				)
				( pin "C3N14.2"
					( objectStatus "b" )
				)
			)
			( gate "C3T1"
				( objectStatus "@baseboard_fab2_lib.baseboard_fab2(sch_1):page194_i149" )
				( pin "C3T1.1"
					( objectStatus "a" )
				)
				( pin "C3T1.2"
					( objectStatus "b" )
				)
			)
			( gate "C3T2"
				( objectStatus "@baseboard_fab2_lib.baseboard_fab2(sch_1):page194_i150" )
				( pin "C3T2.1"
					( objectStatus "a" )
				)
				( pin "C3T2.2"
					( objectStatus "b" )
				)
			)
			( gate "R85"
				( objectStatus "@baseboard_fab2_lib.baseboard_fab2(sch_1):page194_i155" )
				( pin "R85.1"
					( objectStatus "a" )
				)
				( pin "R85.2"
					( objectStatus "b" )
				)
			)
			( gate "R86"
				( objectStatus "@baseboard_fab2_lib.baseboard_fab2(sch_1):page194_i156" )
				( pin "R86.1"
					( objectStatus "a" )
				)
				( pin "R86.2"
					( objectStatus "b" )
				)
			)
			( gate "RM1E1"
				( objectStatus "@baseboard_fab2_lib.baseboard_fab2(sch_1):page195_i26" )
				( pin "RM1E1.1"
					( objectStatus "io1" )
				)
				( pin "RM1E1.2"
					( objectStatus "io2" )
				)
				( pin "RM1E1.3"
					( objectStatus "io3" )
				)
			)
			( gate "J1E1"
				( objectStatus "@baseboard_fab2_lib.baseboard_fab2(sch_1):page195_i29" )
				( pin "J1E1.A1"
					( objectStatus "a1" )
				)
				( pin "J1E1.A2"
					( objectStatus "a2" )
				)
				( pin "J1E1.A3"
					( objectStatus "a3" )
				)
				( pin "J1E1.B1"
					( objectStatus "b1" )
				)
				( pin "J1E1.B2"
					( objectStatus "b2" )
				)
				( pin "J1E1.B3"
					( objectStatus "b3" )
				)
				( pin "J1E1.C1"
					( objectStatus "c1" )
				)
				( pin "J1E1.C2"
					( objectStatus "c2" )
				)
				( pin "J1E1.C3"
					( objectStatus "c3" )
				)
				( pin "J1E1.D1"
					( objectStatus "d1" )
				)
				( pin "J1E1.D2"
					( objectStatus "d2" )
				)
				( pin "J1E1.D3"
					( objectStatus "d3" )
				)
			)
			( gate "C9R5"
				( objectStatus "@baseboard_fab2_lib.baseboard_fab2(sch_1):page195_i31" )
				( pin "C9R5.1"
					( objectStatus "a" )
				)
				( pin "C9R5.2"
					( objectStatus "b" )
				)
			)
			( gate "C1E12"
				( objectStatus "@baseboard_fab2_lib.baseboard_fab2(sch_1):page195_i32" )
				( pin "C1E12.1"
					( objectStatus "a" )
				)
				( pin "C1E12.2"
					( objectStatus "b" )
				)
			)
			( gate "C1E15"
				( objectStatus "@baseboard_fab2_lib.baseboard_fab2(sch_1):page195_i35" )
				( pin "C1E15.1"
					( objectStatus "a" )
				)
				( pin "C1E15.2"
					( objectStatus "b" )
				)
			)
			( gate "C9R12"
				( objectStatus "@baseboard_fab2_lib.baseboard_fab2(sch_1):page195_i36" )
				( pin "C9R12.1"
					( objectStatus "a" )
				)
				( pin "C9R12.2"
					( objectStatus "b" )
				)
			)
			( gate "C9R6"
				( objectStatus "@baseboard_fab2_lib.baseboard_fab2(sch_1):page195_i37" )
				( pin "C9R6.1"
					( objectStatus "a" )
				)
				( pin "C9R6.2"
					( objectStatus "b" )
				)
			)
			( gate "C1E17"
				( objectStatus "@baseboard_fab2_lib.baseboard_fab2(sch_1):page195_i38" )
				( pin "C1E17.1"
					( objectStatus "a" )
				)
				( pin "C1E17.2"
					( objectStatus "b" )
				)
			)
			( gate "C1E16"
				( objectStatus "@baseboard_fab2_lib.baseboard_fab2(sch_1):page195_i39" )
				( pin "C1E16.1"
					( objectStatus "a" )
				)
				( pin "C1E16.2"
					( objectStatus "b" )
				)
			)
			( gate "TH4G1"
				( objectStatus "@baseboard_fab2_lib.baseboard_fab2(sch_1):page195_i49" )
				( pin "TH4G1.1"
					( objectStatus "\1\" )
				)
			)
			( gate "TH9G1"
				( objectStatus "@baseboard_fab2_lib.baseboard_fab2(sch_1):page195_i52" )
				( pin "TH9G1.1"
					( objectStatus "\1\" )
				)
			)
			( gate "TH9A1"
				( objectStatus "@baseboard_fab2_lib.baseboard_fab2(sch_1):page195_i54" )
				( pin "TH9A1.1"
					( objectStatus "\1\" )
				)
			)
			( gate "TH1A1"
				( objectStatus "@baseboard_fab2_lib.baseboard_fab2(sch_1):page195_i56" )
				( pin "TH1A1.1"
					( objectStatus "\1\" )
				)
			)
			( gate "TH4A1"
				( objectStatus "@baseboard_fab2_lib.baseboard_fab2(sch_1):page195_i62" )
				( pin "TH4A1.1"
					( objectStatus "\1\" )
				)
			)
			( gate "TH7A1"
				( objectStatus "@baseboard_fab2_lib.baseboard_fab2(sch_1):page195_i65" )
				( pin "TH7A1.1"
					( objectStatus "\1\" )
				)
			)
			( gate "TH7G1"
				( objectStatus "@baseboard_fab2_lib.baseboard_fab2(sch_1):page195_i67" )
				( pin "TH7G1.1"
					( objectStatus "\1\" )
				)
			)
			( gate "RM1G1"
				( objectStatus "@baseboard_fab2_lib.baseboard_fab2(sch_1):page195_i76" )
			)
			( gate "J1D1"
				( objectStatus "@baseboard_fab2_lib.baseboard_fab2(sch_1):page195_i78" )
				( pin "J1D1.A1"
					( objectStatus "a1" )
				)
				( pin "J1D1.A2"
					( objectStatus "a2" )
				)
				( pin "J1D1.A3"
					( objectStatus "a3" )
				)
				( pin "J1D1.B1"
					( objectStatus "b1" )
				)
				( pin "J1D1.B2"
					( objectStatus "b2" )
				)
				( pin "J1D1.B3"
					( objectStatus "b3" )
				)
				( pin "J1D1.C1"
					( objectStatus "c1" )
				)
				( pin "J1D1.C2"
					( objectStatus "c2" )
				)
				( pin "J1D1.C3"
					( objectStatus "c3" )
				)
				( pin "J1D1.D1"
					( objectStatus "d1" )
				)
				( pin "J1D1.D2"
					( objectStatus "d2" )
				)
				( pin "J1D1.D3"
					( objectStatus "d3" )
				)
			)
			( gate "C4F6"
				( objectStatus "@baseboard_fab2_lib.baseboard_fab2(sch_1):page195_i82" )
				( pin "C4F6.1"
					( objectStatus "a" )
				)
				( pin "C4F6.2"
					( objectStatus "b" )
				)
			)
			( gate "C4B13"
				( objectStatus "@baseboard_fab2_lib.baseboard_fab2(sch_1):page195_i83" )
				( pin "C4B13.1"
					( objectStatus "a" )
				)
				( pin "C4B13.2"
					( objectStatus "b" )
				)
			)
			( gate "C1B14"
				( objectStatus "@baseboard_fab2_lib.baseboard_fab2(sch_1):page195_i84" )
				( pin "C1B14.1"
					( objectStatus "a" )
				)
				( pin "C1B14.2"
					( objectStatus "b" )
				)
			)
			( gate "C1F7"
				( objectStatus "@baseboard_fab2_lib.baseboard_fab2(sch_1):page195_i85" )
				( pin "C1F7.1"
					( objectStatus "a" )
				)
				( pin "C1F7.2"
					( objectStatus "b" )
				)
			)
			( gate "C4F5"
				( objectStatus "@baseboard_fab2_lib.baseboard_fab2(sch_1):page195_i96" )
				( pin "C4F5.1"
					( objectStatus "a" )
				)
				( pin "C4F5.2"
					( objectStatus "b" )
				)
			)
			( gate "C4B14"
				( objectStatus "@baseboard_fab2_lib.baseboard_fab2(sch_1):page195_i97" )
				( pin "C4B14.1"
					( objectStatus "a" )
				)
				( pin "C4B14.2"
					( objectStatus "b" )
				)
			)
			( gate "C3T6"
				( objectStatus "@baseboard_fab2_lib.baseboard_fab2(sch_1):page195_i98" )
				( pin "C3T6.1"
					( objectStatus "a" )
				)
				( pin "C3T6.2"
					( objectStatus "b" )
				)
			)
			( gate "C9M3"
				( objectStatus "@baseboard_fab2_lib.baseboard_fab2(sch_1):page195_i99" )
				( pin "C9M3.1"
					( objectStatus "a" )
				)
				( pin "C9M3.2"
					( objectStatus "b" )
				)
			)
			( gate "C3B6"
				( objectStatus "@baseboard_fab2_lib.baseboard_fab2(sch_1):page195_i100" )
				( pin "C3B6.1"
					( objectStatus "a" )
				)
				( pin "C3B6.2"
					( objectStatus "b" )
				)
			)
			( gate "C1R23"
				( objectStatus "@baseboard_fab2_lib.baseboard_fab2(sch_1):page195_i101" )
				( pin "C1R23.1"
					( objectStatus "a" )
				)
				( pin "C1R23.2"
					( objectStatus "b" )
				)
			)
			( gate "C4M6"
				( objectStatus "@baseboard_fab2_lib.baseboard_fab2(sch_1):page195_i102" )
				( pin "C4M6.1"
					( objectStatus "a" )
				)
				( pin "C4M6.2"
					( objectStatus "b" )
				)
			)
			( gate "C1M5"
				( objectStatus "@baseboard_fab2_lib.baseboard_fab2(sch_1):page195_i103" )
				( pin "C1M5.1"
					( objectStatus "a" )
				)
				( pin "C1M5.2"
					( objectStatus "b" )
				)
			)
			( gate "C3T13"
				( objectStatus "@baseboard_fab2_lib.baseboard_fab2(sch_1):page195_i104" )
				( pin "C3T13.1"
					( objectStatus "a" )
				)
				( pin "C3T13.2"
					( objectStatus "b" )
				)
			)
			( gate "C4M7"
				( objectStatus "@baseboard_fab2_lib.baseboard_fab2(sch_1):page195_i105" )
				( pin "C4M7.1"
					( objectStatus "a" )
				)
				( pin "C4M7.2"
					( objectStatus "b" )
				)
			)
			( gate "C3T15"
				( objectStatus "@baseboard_fab2_lib.baseboard_fab2(sch_1):page195_i106" )
				( pin "C3T15.1"
					( objectStatus "a" )
				)
				( pin "C3T15.2"
					( objectStatus "b" )
				)
			)
			( gate "C7M6"
				( objectStatus "@baseboard_fab2_lib.baseboard_fab2(sch_1):page195_i108" )
				( pin "C7M6.1"
					( objectStatus "a" )
				)
				( pin "C7M6.2"
					( objectStatus "b" )
				)
			)
			( gate "C6N5"
				( objectStatus "@baseboard_fab2_lib.baseboard_fab2(sch_1):page195_i109" )
				( pin "C6N5.1"
					( objectStatus "a" )
				)
				( pin "C6N5.2"
					( objectStatus "b" )
				)
			)
			( gate "C9T3"
				( objectStatus "@baseboard_fab2_lib.baseboard_fab2(sch_1):page195_i111" )
				( pin "C9T3.1"
					( objectStatus "a" )
				)
				( pin "C9T3.2"
					( objectStatus "b" )
				)
			)
			( gate "C4F4"
				( objectStatus "@baseboard_fab2_lib.baseboard_fab2(sch_1):page195_i112" )
				( pin "C4F4.1"
					( objectStatus "a" )
				)
				( pin "C4F4.2"
					( objectStatus "b" )
				)
			)
			( gate "C3T3"
				( objectStatus "@baseboard_fab2_lib.baseboard_fab2(sch_1):page195_i113" )
				( pin "C3T3.1"
					( objectStatus "a" )
				)
				( pin "C3T3.2"
					( objectStatus "b" )
				)
			)
			( gate "R2U43"
				( objectStatus "@baseboard_fab2_lib.baseboard_fab2(sch_1):page196_i46" )
				( pin "R2U43.1"
					( objectStatus "a" )
				)
				( pin "R2U43.2"
					( objectStatus "b" )
				)
			)
			( gate "BT8G1"
				( objectStatus "@baseboard_fab2_lib.baseboard_fab2(sch_1):page196_i47" )
			)
			( gate "XBT8G1"
				( objectStatus "@baseboard_fab2_lib.baseboard_fab2(sch_1):page196_i51" )
				( pin "XBT8G1.3"
					( objectStatus "n" )
				)
				( pin "XBT8G1.1"
					( objectStatus "p1" )
				)
				( pin "XBT8G1.2"
					( objectStatus "p2" )
				)
			)
			( gate "CR2U1"
				( objectStatus "@baseboard_fab2_lib.baseboard_fab2(sch_1):page196_i53" )
				( pin "CR2U1.1"
					( objectStatus "a1" )
				)
				( pin "CR2U1.2"
					( objectStatus "a2" )
				)
				( pin "CR2U1.3"
					( objectStatus "c" )
				)
			)
			( gate "R3P44"
				( objectStatus "@baseboard_fab2_lib.baseboard_fab2(sch_1):page196_i59" )
				( pin "R3P44.1"
					( objectStatus "a" )
				)
				( pin "R3P44.2"
					( objectStatus "b" )
				)
			)
			( gate "C3P45"
				( objectStatus "@baseboard_fab2_lib.baseboard_fab2(sch_1):page196_i60" )
				( pin "C3P45.1"
					( objectStatus "a" )
				)
				( pin "C3P45.2"
					( objectStatus "b" )
				)
			)
			( gate "R8D32"
				( objectStatus "@baseboard_fab2_lib.baseboard_fab2(sch_1):page196_i65" )
				( pin "R8D32.1"
					( objectStatus "a" )
				)
				( pin "R8D32.2"
					( objectStatus "b" )
				)
			)
			( gate "R1L16"
				( objectStatus "@baseboard_fab2_lib.baseboard_fab2(sch_1):page196_i68" )
				( pin "R1L16.1"
					( objectStatus "a" )
				)
				( pin "R1L16.2"
					( objectStatus "b" )
				)
			)
			( gate "U7D3"
				( objectStatus "@baseboard_fab2_lib.baseboard_fab2(sch_1):page196_i70" )
				( pin "U7D3.5"
					( objectStatus "cext" )
				)
				( pin "U7D3.1"
					( objectStatus "enin" )
				)
				( pin "U7D3.4"
					( objectStatus "enout" )
				)
				( pin "U7D3.2"
					( objectStatus "gnd" )
				)
				( pin "U7D3.6"
					( objectStatus "vcc" )
				)
				( pin "U7D3.3"
					( objectStatus "vin" )
				)
			)
			( gate "R3P50"
				( objectStatus "@baseboard_fab2_lib.baseboard_fab2(sch_1):page196_i71" )
				( pin "R3P50.1"
					( objectStatus "a" )
				)
				( pin "R3P50.2"
					( objectStatus "b" )
				)
			)
			( gate "C3P46"
				( objectStatus "@baseboard_fab2_lib.baseboard_fab2(sch_1):page196_i72" )
				( pin "C3P46.1"
					( objectStatus "a" )
				)
				( pin "C3P46.2"
					( objectStatus "b" )
				)
			)
			( gate "R3P48"
				( objectStatus "@baseboard_fab2_lib.baseboard_fab2(sch_1):page196_i74" )
				( pin "R3P48.1"
					( objectStatus "a" )
				)
				( pin "R3P48.2"
					( objectStatus "b" )
				)
			)
			( gate "R3P51"
				( objectStatus "@baseboard_fab2_lib.baseboard_fab2(sch_1):page196_i75" )
				( pin "R3P51.1"
					( objectStatus "a" )
				)
				( pin "R3P51.2"
					( objectStatus "b" )
				)
			)
			( gate "U1L3"
				( objectStatus "@baseboard_fab2_lib.baseboard_fab2(sch_1):page196_i80" )
				( pin "U1L3.2"
					( objectStatus "reset_n" )
				)
				( pin "U1L3.3"
					( objectStatus "vcc" )
				)
			)
			( gate "C1L16"
				( objectStatus "@baseboard_fab2_lib.baseboard_fab2(sch_1):page196_i81" )
				( pin "C1L16.1"
					( objectStatus "a" )
				)
				( pin "C1L16.2"
					( objectStatus "b" )
				)
			)
			( gate "U8E2"
				( objectStatus "@baseboard_fab2_lib.baseboard_fab2(sch_1):page196_i89" )
				( pin "U8E2.2"
					( objectStatus "reset_n" )
				)
				( pin "U8E2.3"
					( objectStatus "vcc" )
				)
			)
			( gate "R8E7"
				( objectStatus "@baseboard_fab2_lib.baseboard_fab2(sch_1):page196_i90" )
				( pin "R8E7.1"
					( objectStatus "a" )
				)
				( pin "R8E7.2"
					( objectStatus "b" )
				)
			)
			( gate "C8E3"
				( objectStatus "@baseboard_fab2_lib.baseboard_fab2(sch_1):page196_i94" )
				( pin "C8E3.1"
					( objectStatus "a" )
				)
				( pin "C8E3.2"
					( objectStatus "b" )
				)
			)
			( gate "C2U26"
				( objectStatus "@baseboard_fab2_lib.baseboard_fab2(sch_1):page196_i102" )
				( pin "C2U26.1"
					( objectStatus "a" )
				)
				( pin "C2U26.2"
					( objectStatus "b" )
				)
			)
			( gate "CR7E1"
				( objectStatus "@baseboard_fab2_lib.baseboard_fab2(sch_1):page196_i103" )
				( pin "CR7E1.2"
					( objectStatus "a" )
				)
				( pin "CR7E1.1"
					( objectStatus "c" )
				)
			)
			( gate "U2"
				( objectStatus "@baseboard_fab2_lib.baseboard_fab2(sch_1):page196_i104" )
				( pin "U2.5"
					( objectStatus "gnd" )
				)
				( pin "U2.4"
					( objectStatus "inap" )
				)
				( pin "U2.3"
					( objectStatus "inbn" )
				)
				( pin "U2.6"
					( objectStatus "outa" )
				)
				( pin "U2.1"
					( objectStatus "outb" )
				)
				( pin "U2.2"
					( objectStatus "vdd" )
				)
			)
			( gate "C18"
				( objectStatus "@baseboard_fab2_lib.baseboard_fab2(sch_1):page196_i105" )
				( pin "C18.1"
					( objectStatus "a" )
				)
				( pin "C18.2"
					( objectStatus "b" )
				)
			)
			( gate "R63"
				( objectStatus "@baseboard_fab2_lib.baseboard_fab2(sch_1):page196_i106" )
				( pin "R63.1"
					( objectStatus "a" )
				)
				( pin "R63.2"
					( objectStatus "b" )
				)
			)
			( gate "R56"
				( objectStatus "@baseboard_fab2_lib.baseboard_fab2(sch_1):page196_i112" )
				( pin "R56.1"
					( objectStatus "a" )
				)
				( pin "R56.2"
					( objectStatus "b" )
				)
			)
			( gate "R57"
				( objectStatus "@baseboard_fab2_lib.baseboard_fab2(sch_1):page196_i113" )
				( pin "R57.1"
					( objectStatus "a" )
				)
				( pin "R57.2"
					( objectStatus "b" )
				)
			)
			( gate "R58"
				( objectStatus "@baseboard_fab2_lib.baseboard_fab2(sch_1):page196_i114" )
				( pin "R58.1"
					( objectStatus "a" )
				)
				( pin "R58.2"
					( objectStatus "b" )
				)
			)
			( gate "R59"
				( objectStatus "@baseboard_fab2_lib.baseboard_fab2(sch_1):page196_i115" )
				( pin "R59.1"
					( objectStatus "a" )
				)
				( pin "R59.2"
					( objectStatus "b" )
				)
			)
			( gate "R60"
				( objectStatus "@baseboard_fab2_lib.baseboard_fab2(sch_1):page196_i120" )
				( pin "R60.1"
					( objectStatus "a" )
				)
				( pin "R60.2"
					( objectStatus "b" )
				)
			)
			( gate "R61"
				( objectStatus "@baseboard_fab2_lib.baseboard_fab2(sch_1):page196_i121" )
				( pin "R61.1"
					( objectStatus "a" )
				)
				( pin "R61.2"
					( objectStatus "b" )
				)
			)
			( gate "R62"
				( objectStatus "@baseboard_fab2_lib.baseboard_fab2(sch_1):page196_i122" )
				( pin "R62.1"
					( objectStatus "a" )
				)
				( pin "R62.2"
					( objectStatus "b" )
				)
			)
			( gate "Q2"
				( objectStatus "@baseboard_fab2_lib.baseboard_fab2(sch_1):page196_i124" )
				( pin "Q2.3"
					( objectStatus "drn" )
				)
				( pin "Q2.1"
					( objectStatus "gate" )
				)
				( pin "Q2.2"
					( objectStatus "src" )
				)
			)
			( gate "CR2"
				( objectStatus "@baseboard_fab2_lib.baseboard_fab2(sch_1):page196_i128" )
				( pin "CR2.2"
					( objectStatus "a" )
				)
				( pin "CR2.1"
					( objectStatus "c" )
				)
			)
			( gate "C6U18"
				( objectStatus "@baseboard_fab2_lib.baseboard_fab2(sch_1):page197_i52" )
				( pin "C6U18.1"
					( objectStatus "a" )
				)
				( pin "C6U18.2"
					( objectStatus "b" )
				)
			)
			( gate "C6T2"
				( objectStatus "@baseboard_fab2_lib.baseboard_fab2(sch_1):page197_i54" )
				( pin "C6T2.1"
					( objectStatus "a" )
				)
				( pin "C6T2.2"
					( objectStatus "b" )
				)
			)
			( gate "C4B11"
				( objectStatus "@baseboard_fab2_lib.baseboard_fab2(sch_1):page197_i59" )
				( pin "C4B11.1"
					( objectStatus "a" )
				)
				( pin "C4B11.2"
					( objectStatus "b" )
				)
			)
			( gate "C4A4"
				( objectStatus "@baseboard_fab2_lib.baseboard_fab2(sch_1):page197_i62" )
				( pin "C4A4.1"
					( objectStatus "a" )
				)
				( pin "C4A4.2"
					( objectStatus "b" )
				)
			)
			( gate "C6U10"
				( objectStatus "@baseboard_fab2_lib.baseboard_fab2(sch_1):page197_i65" )
				( pin "C6U10.1"
					( objectStatus "a" )
				)
				( pin "C6U10.2"
					( objectStatus "b" )
				)
			)
			( gate "C4A17"
				( objectStatus "@baseboard_fab2_lib.baseboard_fab2(sch_1):page197_i67" )
				( pin "C4A17.1"
					( objectStatus "a" )
				)
				( pin "C4A17.2"
					( objectStatus "b" )
				)
			)
			( gate "C9T8"
				( objectStatus "@baseboard_fab2_lib.baseboard_fab2(sch_1):page197_i70" )
				( pin "C9T8.1"
					( objectStatus "a" )
				)
				( pin "C9T8.2"
					( objectStatus "b" )
				)
			)
			( gate "C9U11"
				( objectStatus "@baseboard_fab2_lib.baseboard_fab2(sch_1):page197_i73" )
				( pin "C9U11.1"
					( objectStatus "a" )
				)
				( pin "C9U11.2"
					( objectStatus "b" )
				)
			)
			( gate "C9U8"
				( objectStatus "@baseboard_fab2_lib.baseboard_fab2(sch_1):page197_i76" )
				( pin "C9U8.1"
					( objectStatus "a" )
				)
				( pin "C9U8.2"
					( objectStatus "b" )
				)
			)
			( gate "C1A4"
				( objectStatus "@baseboard_fab2_lib.baseboard_fab2(sch_1):page197_i79" )
				( pin "C1A4.1"
					( objectStatus "a" )
				)
				( pin "C1A4.2"
					( objectStatus "b" )
				)
			)
			( gate "C1B7"
				( objectStatus "@baseboard_fab2_lib.baseboard_fab2(sch_1):page197_i82" )
				( pin "C1B7.1"
					( objectStatus "a" )
				)
				( pin "C1B7.2"
					( objectStatus "b" )
				)
			)
			( gate "C1A16"
				( objectStatus "@baseboard_fab2_lib.baseboard_fab2(sch_1):page197_i85" )
				( pin "C1A16.1"
					( objectStatus "a" )
				)
				( pin "C1A16.2"
					( objectStatus "b" )
				)
			)
			( gate "U4F1"
				( objectStatus "@baseboard_fab2_lib.baseboard_fab2(sch_1):page197_i97" )
				( pin "U4F1.2"
					( objectStatus "gnd(0)" )
				)
				( pin "U4F1.1"
					( objectStatus "gnd(1)" )
				)
				( pin "U4F1.3"
					( objectStatus "\out\" )
				)
				( pin "U4F1.4"
					( objectStatus "rsn" )
				)
				( pin "U4F1.5"
					( objectStatus "rsp" )
				)
			)
			( gate "R4F2"
				( objectStatus "@baseboard_fab2_lib.baseboard_fab2(sch_1):page197_i99" )
				( pin "R4F2.1"
					( objectStatus "a" )
				)
				( pin "R4F2.2"
					( objectStatus "b" )
				)
			)
			( gate "R4F1"
				( objectStatus "@baseboard_fab2_lib.baseboard_fab2(sch_1):page197_i110" )
				( pin "R4F1.1"
					( objectStatus "a" )
				)
				( pin "R4F1.2"
					( objectStatus "b" )
				)
			)
			( gate "R4B11"
				( objectStatus "@baseboard_fab2_lib.baseboard_fab2(sch_1):page197_i113" )
				( pin "R4B11.1"
					( objectStatus "a" )
				)
				( pin "R4B11.2"
					( objectStatus "b" )
				)
			)
			( gate "U4B1"
				( objectStatus "@baseboard_fab2_lib.baseboard_fab2(sch_1):page197_i120" )
				( pin "U4B1.2"
					( objectStatus "gnd(0)" )
				)
				( pin "U4B1.1"
					( objectStatus "gnd(1)" )
				)
				( pin "U4B1.3"
					( objectStatus "\out\" )
				)
				( pin "U4B1.4"
					( objectStatus "rsn" )
				)
				( pin "U4B1.5"
					( objectStatus "rsp" )
				)
			)
			( gate "R4B12"
				( objectStatus "@baseboard_fab2_lib.baseboard_fab2(sch_1):page197_i121" )
				( pin "R4B12.1"
					( objectStatus "a" )
				)
				( pin "R4B12.2"
					( objectStatus "b" )
				)
			)
			( gate "R9T4"
				( objectStatus "@baseboard_fab2_lib.baseboard_fab2(sch_1):page197_i126" )
				( pin "R9T4.1"
					( objectStatus "a" )
				)
				( pin "R9T4.2"
					( objectStatus "b" )
				)
			)
			( gate "R1F3"
				( objectStatus "@baseboard_fab2_lib.baseboard_fab2(sch_1):page197_i131" )
				( pin "R1F3.1"
					( objectStatus "a" )
				)
				( pin "R1F3.2"
					( objectStatus "b" )
				)
			)
			( gate "U1F1"
				( objectStatus "@baseboard_fab2_lib.baseboard_fab2(sch_1):page197_i133" )
				( pin "U1F1.2"
					( objectStatus "gnd(0)" )
				)
				( pin "U1F1.1"
					( objectStatus "gnd(1)" )
				)
				( pin "U1F1.3"
					( objectStatus "\out\" )
				)
				( pin "U1F1.4"
					( objectStatus "rsn" )
				)
				( pin "U1F1.5"
					( objectStatus "rsp" )
				)
			)
			( gate "R1B14"
				( objectStatus "@baseboard_fab2_lib.baseboard_fab2(sch_1):page197_i137" )
				( pin "R1B14.1"
					( objectStatus "a" )
				)
				( pin "R1B14.2"
					( objectStatus "b" )
				)
			)
			( gate "R9M4"
				( objectStatus "@baseboard_fab2_lib.baseboard_fab2(sch_1):page197_i142" )
				( pin "R9M4.1"
					( objectStatus "a" )
				)
				( pin "R9M4.2"
					( objectStatus "b" )
				)
			)
			( gate "U1B1"
				( objectStatus "@baseboard_fab2_lib.baseboard_fab2(sch_1):page197_i144" )
				( pin "U1B1.2"
					( objectStatus "gnd(0)" )
				)
				( pin "U1B1.1"
					( objectStatus "gnd(1)" )
				)
				( pin "U1B1.3"
					( objectStatus "\out\" )
				)
				( pin "U1B1.4"
					( objectStatus "rsn" )
				)
				( pin "U1B1.5"
					( objectStatus "rsp" )
				)
			)
			( gate "EU2T1"
				( objectStatus "@baseboard_fab2_lib.baseboard_fab2(sch_1):page198_i1" )
				( pin "EU2T1.5"
					( objectStatus "d" )
				)
				( pin "EU2T1.7"
					( objectStatus "g" )
				)
				( pin "EU2T1.4"
					( objectStatus "gnd" )
				)
				( pin "EU2T1.2"
					( objectStatus "\on\" )
				)
				( pin "EU2T1.8"
					( objectStatus "pg" )
				)
				( pin "EU2T1.6"
					( objectStatus "s" )
				)
				( pin "EU2T1.3"
					( objectStatus "shdn_n" )
				)
				( pin "EU2T1.9"
					( objectStatus "thpad" )
				)
				( pin "EU2T1.1"
					( objectStatus "vcc" )
				)
			)
			( gate "EU8B1"
				( objectStatus "@baseboard_fab2_lib.baseboard_fab2(sch_1):page198_i13" )
				( pin "EU8B1.5"
					( objectStatus "d" )
				)
				( pin "EU8B1.7"
					( objectStatus "g" )
				)
				( pin "EU8B1.4"
					( objectStatus "gnd" )
				)
				( pin "EU8B1.2"
					( objectStatus "\on\" )
				)
				( pin "EU8B1.8"
					( objectStatus "pg" )
				)
				( pin "EU8B1.6"
					( objectStatus "s" )
				)
				( pin "EU8B1.3"
					( objectStatus "shdn_n" )
				)
				( pin "EU8B1.9"
					( objectStatus "thpad" )
				)
				( pin "EU8B1.1"
					( objectStatus "vcc" )
				)
			)
			( gate "EU7E1"
				( objectStatus "@baseboard_fab2_lib.baseboard_fab2(sch_1):page198_i19" )
				( pin "EU7E1.5"
					( objectStatus "d" )
				)
				( pin "EU7E1.7"
					( objectStatus "g" )
				)
				( pin "EU7E1.4"
					( objectStatus "gnd" )
				)
				( pin "EU7E1.2"
					( objectStatus "\on\" )
				)
				( pin "EU7E1.8"
					( objectStatus "pg" )
				)
				( pin "EU7E1.6"
					( objectStatus "s" )
				)
				( pin "EU7E1.3"
					( objectStatus "shdn_n" )
				)
				( pin "EU7E1.9"
					( objectStatus "thpad" )
				)
				( pin "EU7E1.1"
					( objectStatus "vcc" )
				)
			)
			( gate "C8F17"
				( objectStatus "@baseboard_fab2_lib.baseboard_fab2(sch_1):page198_i24" )
				( pin "C8F17.1"
					( objectStatus "a" )
				)
				( pin "C8F17.2"
					( objectStatus "b" )
				)
			)
			( gate "C8B8"
				( objectStatus "@baseboard_fab2_lib.baseboard_fab2(sch_1):page198_i26" )
				( pin "C8B8.1"
					( objectStatus "a" )
				)
				( pin "C8B8.2"
					( objectStatus "b" )
				)
			)
			( gate "C7E7"
				( objectStatus "@baseboard_fab2_lib.baseboard_fab2(sch_1):page198_i28" )
				( pin "C7E7.1"
					( objectStatus "a" )
				)
				( pin "C7E7.2"
					( objectStatus "b" )
				)
			)
			( gate "C8B5"
				( objectStatus "@baseboard_fab2_lib.baseboard_fab2(sch_1):page198_i37" )
				( pin "C8B5.1"
					( objectStatus "a" )
				)
				( pin "C8B5.2"
					( objectStatus "b" )
				)
			)
			( gate "C8B12"
				( objectStatus "@baseboard_fab2_lib.baseboard_fab2(sch_1):page198_i38" )
				( pin "C8B12.1"
					( objectStatus "a" )
				)
				( pin "C8B12.2"
					( objectStatus "b" )
				)
			)
			( gate "C8B6"
				( objectStatus "@baseboard_fab2_lib.baseboard_fab2(sch_1):page198_i40" )
				( pin "C8B6.1"
					( objectStatus "a" )
				)
				( pin "C8B6.2"
					( objectStatus "b" )
				)
			)
			( gate "C8B7"
				( objectStatus "@baseboard_fab2_lib.baseboard_fab2(sch_1):page198_i41" )
				( pin "C8B7.1"
					( objectStatus "a" )
				)
				( pin "C8B7.2"
					( objectStatus "b" )
				)
			)
			( gate "C2T36"
				( objectStatus "@baseboard_fab2_lib.baseboard_fab2(sch_1):page198_i43" )
				( pin "C2T36.1"
					( objectStatus "a" )
				)
				( pin "C2T36.2"
					( objectStatus "b" )
				)
			)
			( gate "C2U1"
				( objectStatus "@baseboard_fab2_lib.baseboard_fab2(sch_1):page198_i44" )
				( pin "C2U1.1"
					( objectStatus "a" )
				)
				( pin "C2U1.2"
					( objectStatus "b" )
				)
			)
			( gate "C2U19"
				( objectStatus "@baseboard_fab2_lib.baseboard_fab2(sch_1):page198_i46" )
				( pin "C2U19.1"
					( objectStatus "a" )
				)
				( pin "C2U19.2"
					( objectStatus "b" )
				)
			)
			( gate "C2U2"
				( objectStatus "@baseboard_fab2_lib.baseboard_fab2(sch_1):page198_i47" )
				( pin "C2U2.1"
					( objectStatus "a" )
				)
				( pin "C2U2.2"
					( objectStatus "b" )
				)
			)
			( gate "C7E9"
				( objectStatus "@baseboard_fab2_lib.baseboard_fab2(sch_1):page198_i49" )
				( pin "C7E9.1"
					( objectStatus "a" )
				)
				( pin "C7E9.2"
					( objectStatus "b" )
				)
			)
			( gate "C7E8"
				( objectStatus "@baseboard_fab2_lib.baseboard_fab2(sch_1):page198_i50" )
				( pin "C7E8.1"
					( objectStatus "a" )
				)
				( pin "C7E8.2"
					( objectStatus "b" )
				)
			)
			( gate "C7E5"
				( objectStatus "@baseboard_fab2_lib.baseboard_fab2(sch_1):page198_i52" )
				( pin "C7E5.1"
					( objectStatus "a" )
				)
				( pin "C7E5.2"
					( objectStatus "b" )
				)
			)
			( gate "C7E6"
				( objectStatus "@baseboard_fab2_lib.baseboard_fab2(sch_1):page198_i53" )
				( pin "C7E6.1"
					( objectStatus "a" )
				)
				( pin "C7E6.2"
					( objectStatus "b" )
				)
			)
			( gate "C1B18"
				( objectStatus "@baseboard_fab2_lib.baseboard_fab2(sch_1):page198_i61" )
				( pin "C1B18.1"
					( objectStatus "a" )
				)
				( pin "C1B18.2"
					( objectStatus "b" )
				)
			)
			( gate "C1B19"
				( objectStatus "@baseboard_fab2_lib.baseboard_fab2(sch_1):page198_i64" )
				( pin "C1B19.1"
					( objectStatus "a" )
				)
				( pin "C1B19.2"
					( objectStatus "b" )
				)
			)
			( gate "C9M6"
				( objectStatus "@baseboard_fab2_lib.baseboard_fab2(sch_1):page198_i67" )
				( pin "C9M6.1"
					( objectStatus "a" )
				)
				( pin "C9M6.2"
					( objectStatus "b" )
				)
			)
			( gate "EU9M1"
				( objectStatus "@baseboard_fab2_lib.baseboard_fab2(sch_1):page198_i69" )
				( pin "EU9M1.5"
					( objectStatus "d" )
				)
				( pin "EU9M1.7"
					( objectStatus "g" )
				)
				( pin "EU9M1.4"
					( objectStatus "gnd" )
				)
				( pin "EU9M1.2"
					( objectStatus "\on\" )
				)
				( pin "EU9M1.8"
					( objectStatus "pg" )
				)
				( pin "EU9M1.6"
					( objectStatus "s" )
				)
				( pin "EU9M1.3"
					( objectStatus "shdn_n" )
				)
				( pin "EU9M1.9"
					( objectStatus "thpad" )
				)
				( pin "EU9M1.1"
					( objectStatus "vcc" )
				)
			)
			( gate "C9M10"
				( objectStatus "@baseboard_fab2_lib.baseboard_fab2(sch_1):page198_i74" )
				( pin "C9M10.1"
					( objectStatus "a" )
				)
				( pin "C9M10.2"
					( objectStatus "b" )
				)
			)
			( gate "C9M9"
				( objectStatus "@baseboard_fab2_lib.baseboard_fab2(sch_1):page198_i76" )
				( pin "C9M9.1"
					( objectStatus "a" )
				)
				( pin "C9M9.2"
					( objectStatus "b" )
				)
			)
			( gate "R8E12"
				( objectStatus "@baseboard_fab2_lib.baseboard_fab2(sch_1):page198_i78" )
				( pin "R8E12.1"
					( objectStatus "a" )
				)
				( pin "R8E12.2"
					( objectStatus "b" )
				)
			)
			( gate "R8B4"
				( objectStatus "@baseboard_fab2_lib.baseboard_fab2(sch_1):page198_i83" )
				( pin "R8B4.1"
					( objectStatus "a" )
				)
				( pin "R8B4.2"
					( objectStatus "b" )
				)
			)
			( gate "Q8G1"
				( objectStatus "@baseboard_fab2_lib.baseboard_fab2(sch_1):page198_i85" )
				( pin "Q8G1.5"
					( objectStatus "drn" )
				)
				( pin "Q8G1.4"
					( objectStatus "gate" )
				)
				( pin "Q8G1.1"
					( objectStatus "src" )
				)
			)
			( gate "Q1B1"
				( objectStatus "@baseboard_fab2_lib.baseboard_fab2(sch_1):page198_i86" )
				( pin "Q1B1.5"
					( objectStatus "drn" )
				)
				( pin "Q1B1.4"
					( objectStatus "gate" )
				)
				( pin "Q1B1.1"
					( objectStatus "src" )
				)
			)
			( gate "Q8B1"
				( objectStatus "@baseboard_fab2_lib.baseboard_fab2(sch_1):page198_i87" )
				( pin "Q8B1.5"
					( objectStatus "drn" )
				)
				( pin "Q8B1.4"
					( objectStatus "gate" )
				)
				( pin "Q8B1.1"
					( objectStatus "src" )
				)
			)
			( gate "Q7E7"
				( objectStatus "@baseboard_fab2_lib.baseboard_fab2(sch_1):page198_i88" )
				( pin "Q7E7.5"
					( objectStatus "drn" )
				)
				( pin "Q7E7.4"
					( objectStatus "gate" )
				)
				( pin "Q7E7.1"
					( objectStatus "src" )
				)
			)
			( gate "R9P30"
				( objectStatus "@baseboard_fab2_lib.baseboard_fab2(sch_1):page199_i2" )
				( pin "R9P30.1"
					( objectStatus "a" )
				)
				( pin "R9P30.2"
					( objectStatus "b" )
				)
			)
			( gate "C1D25"
				( objectStatus "@baseboard_fab2_lib.baseboard_fab2(sch_1):page199_i3" )
				( pin "C1D25.1"
					( objectStatus "a" )
				)
				( pin "C1D25.2"
					( objectStatus "b" )
				)
			)
			( gate "R9P28"
				( objectStatus "@baseboard_fab2_lib.baseboard_fab2(sch_1):page199_i6" )
				( pin "R9P28.1"
					( objectStatus "a" )
				)
				( pin "R9P28.2"
					( objectStatus "b" )
				)
			)
			( gate "C1D27"
				( objectStatus "@baseboard_fab2_lib.baseboard_fab2(sch_1):page199_i7" )
				( pin "C1D27.1"
					( objectStatus "a" )
				)
				( pin "C1D27.2"
					( objectStatus "b" )
				)
			)
			( gate "R1D43"
				( objectStatus "@baseboard_fab2_lib.baseboard_fab2(sch_1):page199_i9" )
				( pin "R1D43.1"
					( objectStatus "a" )
				)
				( pin "R1D43.2"
					( objectStatus "b" )
				)
			)
			( gate "EU1D2"
				( objectStatus "@baseboard_fab2_lib.baseboard_fab2(sch_1):page199_i10" )
				( pin "EU1D2.7"
					( objectStatus "adr1" )
				)
				( pin "EU1D2.8"
					( objectStatus "adr2" )
				)
				( pin "EU1D2.19"
					( objectStatus "csout" )
				)
				( pin "EU1D2.12"
					( objectStatus "enable" )
				)
				( pin "EU1D2.33"
					( objectStatus "ep" )
				)
				( pin "EU1D2.6"
					( objectStatus "fault_n" )
				)
				( pin "EU1D2.24"
					( objectStatus "gate" )
				)
				( pin "EU1D2.22"
					( objectStatus "gnd" )
				)
				( pin "EU1D2.13"
					( objectStatus "gpo1_alert1_n_conv" )
				)
				( pin "EU1D2.14"
					( objectStatus "gpo2_alert2_n" )
				)
				( pin "EU1D2.27"
					( objectStatus "hsn" )
				)
				( pin "EU1D2.28"
					( objectStatus "hsp" )
				)
				( pin "EU1D2.3"
					( objectStatus "iset" )
				)
				( pin "EU1D2.4"
					( objectStatus "istart" )
				)
				( pin "EU1D2.10"
					( objectStatus "mclk" )
				)
				( pin "EU1D2.11"
					( objectStatus "mdat" )
				)
				( pin "EU1D2.26"
					( objectStatus "mon" )
				)
				( pin "EU1D2.29"
					( objectStatus "mop" )
				)
				( pin "EU1D2.32"
					( objectStatus "ov" )
				)
				( pin "EU1D2.23"
					( objectStatus "pgnd" )
				)
				( pin "EU1D2.1"
					( objectStatus "pset" )
				)
				( pin "EU1D2.21"
					( objectStatus "pwgin" )
				)
				( pin "EU1D2.18"
					( objectStatus "pwrgd" )
				)
				( pin "EU1D2.17"
					( objectStatus "retry_n" )
				)
				( pin "EU1D2.16"
					( objectStatus "scl" )
				)
				( pin "EU1D2.15"
					( objectStatus "sda" )
				)
				( pin "EU1D2.9"
					( objectStatus "spiss_n" )
				)
				( pin "EU1D2.25"
					( objectStatus "temp" )
				)
				( pin "EU1D2.5"
					( objectStatus "timer" )
				)
				( pin "EU1D2.31"
					( objectStatus "uv" )
				)
				( pin "EU1D2.2"
					( objectStatus "vcap" )
				)
				( pin "EU1D2.30"
					( objectStatus "vcc" )
				)
				( pin "EU1D2.20"
					( objectStatus "vout" )
				)
			)
			( gate "R9P29"
				( objectStatus "@baseboard_fab2_lib.baseboard_fab2(sch_1):page199_i12" )
				( pin "R9P29.1"
					( objectStatus "a" )
				)
				( pin "R9P29.2"
					( objectStatus "b" )
				)
			)
			( gate "R1D42"
				( objectStatus "@baseboard_fab2_lib.baseboard_fab2(sch_1):page199_i13" )
				( pin "R1D42.1"
					( objectStatus "a" )
				)
				( pin "R1D42.2"
					( objectStatus "b" )
				)
			)
			( gate "R1D37"
				( objectStatus "@baseboard_fab2_lib.baseboard_fab2(sch_1):page199_i15" )
				( pin "R1D37.1"
					( objectStatus "a" )
				)
				( pin "R1D37.2"
					( objectStatus "b" )
				)
			)
			( gate "R1D39"
				( objectStatus "@baseboard_fab2_lib.baseboard_fab2(sch_1):page199_i16" )
				( pin "R1D39.1"
					( objectStatus "a" )
				)
				( pin "R1D39.2"
					( objectStatus "b" )
				)
			)
			( gate "R1D32"
				( objectStatus "@baseboard_fab2_lib.baseboard_fab2(sch_1):page199_i17" )
				( pin "R1D32.1"
					( objectStatus "a" )
				)
				( pin "R1D32.2"
					( objectStatus "b" )
				)
			)
			( gate "R1D41"
				( objectStatus "@baseboard_fab2_lib.baseboard_fab2(sch_1):page199_i19" )
				( pin "R1D41.1"
					( objectStatus "a" )
				)
				( pin "R1D41.2"
					( objectStatus "b" )
				)
			)
			( gate "C9P14"
				( objectStatus "@baseboard_fab2_lib.baseboard_fab2(sch_1):page199_i24" )
				( pin "C9P14.1"
					( objectStatus "a" )
				)
				( pin "C9P14.2"
					( objectStatus "b" )
				)
			)
			( gate "R1D28"
				( objectStatus "@baseboard_fab2_lib.baseboard_fab2(sch_1):page199_i26" )
				( pin "R1D28.1"
					( objectStatus "a" )
				)
				( pin "R1D28.2"
					( objectStatus "b" )
				)
			)
			( gate "R1D24"
				( objectStatus "@baseboard_fab2_lib.baseboard_fab2(sch_1):page199_i27" )
				( pin "R1D24.1"
					( objectStatus "a" )
				)
				( pin "R1D24.2"
					( objectStatus "b" )
				)
			)
			( gate "R1D25"
				( objectStatus "@baseboard_fab2_lib.baseboard_fab2(sch_1):page199_i28" )
				( pin "R1D25.1"
					( objectStatus "a" )
				)
				( pin "R1D25.2"
					( objectStatus "b" )
				)
			)
			( gate "R9P17"
				( objectStatus "@baseboard_fab2_lib.baseboard_fab2(sch_1):page199_i33" )
				( pin "R9P17.1"
					( objectStatus "a" )
				)
				( pin "R9P17.2"
					( objectStatus "b" )
				)
			)
			( gate "R9P16"
				( objectStatus "@baseboard_fab2_lib.baseboard_fab2(sch_1):page199_i36" )
				( pin "R9P16.1"
					( objectStatus "a" )
				)
				( pin "R9P16.2"
					( objectStatus "b" )
				)
			)
			( gate "R1D29"
				( objectStatus "@baseboard_fab2_lib.baseboard_fab2(sch_1):page199_i37" )
				( pin "R1D29.1"
					( objectStatus "a" )
				)
				( pin "R1D29.2"
					( objectStatus "b" )
				)
			)
			( gate "R1D27"
				( objectStatus "@baseboard_fab2_lib.baseboard_fab2(sch_1):page199_i38" )
				( pin "R1D27.1"
					( objectStatus "a" )
				)
				( pin "R1D27.2"
					( objectStatus "b" )
				)
			)
			( gate "R9P18"
				( objectStatus "@baseboard_fab2_lib.baseboard_fab2(sch_1):page199_i41" )
				( pin "R9P18.1"
					( objectStatus "a" )
				)
				( pin "R9P18.2"
					( objectStatus "b" )
				)
			)
			( gate "R1D31"
				( objectStatus "@baseboard_fab2_lib.baseboard_fab2(sch_1):page199_i43" )
				( pin "R1D31.1"
					( objectStatus "a" )
				)
				( pin "R1D31.2"
					( objectStatus "b" )
				)
			)
			( gate "C1D11"
				( objectStatus "@baseboard_fab2_lib.baseboard_fab2(sch_1):page199_i53" )
				( pin "C1D11.1"
					( objectStatus "a" )
				)
				( pin "C1D11.2"
					( objectStatus "b" )
				)
			)
			( gate "R9P23"
				( objectStatus "@baseboard_fab2_lib.baseboard_fab2(sch_1):page199_i54" )
				( pin "R9P23.1"
					( objectStatus "a" )
				)
				( pin "R9P23.2"
					( objectStatus "b" )
				)
			)
			( gate "R9P24"
				( objectStatus "@baseboard_fab2_lib.baseboard_fab2(sch_1):page199_i55" )
				( pin "R9P24.1"
					( objectStatus "a" )
				)
				( pin "R9P24.2"
					( objectStatus "b" )
				)
			)
			( gate "Q1D3"
				( objectStatus "@baseboard_fab2_lib.baseboard_fab2(sch_1):page199_i58" )
				( pin "Q1D3.1"
					( objectStatus "b" )
				)
				( pin "Q1D3.3"
					( objectStatus "c" )
				)
				( pin "Q1D3.2"
					( objectStatus "e" )
				)
			)
			( gate "R1D36"
				( objectStatus "@baseboard_fab2_lib.baseboard_fab2(sch_1):page199_i65" )
				( pin "R1D36.1"
					( objectStatus "a" )
				)
				( pin "R1D36.2"
					( objectStatus "b" )
				)
			)
			( gate "C9P12"
				( objectStatus "@baseboard_fab2_lib.baseboard_fab2(sch_1):page199_i67" )
				( pin "C9P12.1"
					( objectStatus "a" )
				)
				( pin "C9P12.2"
					( objectStatus "b" )
				)
			)
			( gate "Q1D1"
				( objectStatus "@baseboard_fab2_lib.baseboard_fab2(sch_1):page199_i82" )
				( pin "Q1D1.3"
					( objectStatus "drain(0)" )
				)
				( pin "Q1D1.5"
					( objectStatus "gate(0)" )
				)
				( pin "Q1D1.4"
					( objectStatus "source(0)" )
				)
			)
			( gate "R1D13"
				( objectStatus "@baseboard_fab2_lib.baseboard_fab2(sch_1):page199_i84" )
				( pin "R1D13.1"
					( objectStatus "a" )
				)
				( pin "R1D13.2"
					( objectStatus "b" )
				)
			)
			( gate "R1D16"
				( objectStatus "@baseboard_fab2_lib.baseboard_fab2(sch_1):page199_i85" )
				( pin "R1D16.1"
					( objectStatus "a" )
				)
				( pin "R1D16.2"
					( objectStatus "b" )
				)
			)
			( gate "Q1D1"
				( objectStatus "@baseboard_fab2_lib.baseboard_fab2(sch_1):page199_i86" )
				( pin "Q1D1.6"
					( objectStatus "drain(0)" )
				)
				( pin "Q1D1.2"
					( objectStatus "gate(0)" )
				)
				( pin "Q1D1.1"
					( objectStatus "source(0)" )
				)
			)
			( gate "R1D18"
				( objectStatus "@baseboard_fab2_lib.baseboard_fab2(sch_1):page199_i87" )
				( pin "R1D18.1"
					( objectStatus "a" )
				)
				( pin "R1D18.2"
					( objectStatus "b" )
				)
			)
			( gate "R1D11"
				( objectStatus "@baseboard_fab2_lib.baseboard_fab2(sch_1):page199_i88" )
				( pin "R1D11.1"
					( objectStatus "a" )
				)
				( pin "R1D11.2"
					( objectStatus "b" )
				)
			)
			( gate "R1D15"
				( objectStatus "@baseboard_fab2_lib.baseboard_fab2(sch_1):page199_i92" )
				( pin "R1D15.1"
					( objectStatus "a" )
				)
				( pin "R1D15.2"
					( objectStatus "b" )
				)
			)
			( gate "VR1D1"
				( objectStatus "@baseboard_fab2_lib.baseboard_fab2(sch_1):page199_i99" )
				( pin "VR1D1.2"
					( objectStatus "a" )
				)
				( pin "VR1D1.1"
					( objectStatus "c" )
				)
			)
			( gate "R1D40"
				( objectStatus "@baseboard_fab2_lib.baseboard_fab2(sch_1):page199_i100" )
				( pin "R1D40.1"
					( objectStatus "a" )
				)
				( pin "R1D40.2"
					( objectStatus "b" )
				)
			)
			( gate "R1D34"
				( objectStatus "@baseboard_fab2_lib.baseboard_fab2(sch_1):page199_i102" )
				( pin "R1D34.1"
					( objectStatus "a" )
				)
				( pin "R1D34.2"
					( objectStatus "b" )
				)
			)
			( gate "C9P15"
				( objectStatus "@baseboard_fab2_lib.baseboard_fab2(sch_1):page199_i105" )
				( pin "C9P15.1"
					( objectStatus "a" )
				)
				( pin "C9P15.2"
					( objectStatus "b" )
				)
			)
			( gate "C1D26"
				( objectStatus "@baseboard_fab2_lib.baseboard_fab2(sch_1):page199_i107" )
				( pin "C1D26.1"
					( objectStatus "a" )
				)
				( pin "C1D26.2"
					( objectStatus "b" )
				)
			)
			( gate "R1D33"
				( objectStatus "@baseboard_fab2_lib.baseboard_fab2(sch_1):page199_i108" )
				( pin "R1D33.1"
					( objectStatus "a" )
				)
				( pin "R1D33.2"
					( objectStatus "b" )
				)
			)
			( gate "R1D26"
				( objectStatus "@baseboard_fab2_lib.baseboard_fab2(sch_1):page199_i109" )
				( pin "R1D26.1"
					( objectStatus "a" )
				)
				( pin "R1D26.2"
					( objectStatus "b" )
				)
			)
			( gate "R1D30"
				( objectStatus "@baseboard_fab2_lib.baseboard_fab2(sch_1):page199_i110" )
				( pin "R1D30.1"
					( objectStatus "a" )
				)
				( pin "R1D30.2"
					( objectStatus "b" )
				)
			)
			( gate "C1D19"
				( objectStatus "@baseboard_fab2_lib.baseboard_fab2(sch_1):page199_i119" )
				( pin "C1D19.1"
					( objectStatus "a" )
				)
				( pin "C1D19.2"
					( objectStatus "b" )
				)
			)
			( gate "C1D21"
				( objectStatus "@baseboard_fab2_lib.baseboard_fab2(sch_1):page199_i121" )
				( pin "C1D21.1"
					( objectStatus "a" )
				)
				( pin "C1D21.2"
					( objectStatus "b" )
				)
			)
			( gate "J1B3"
				( objectStatus "@baseboard_fab2_lib.baseboard_fab2(sch_1):page199_i123" )
				( pin "J1B3.1"
					( objectStatus "io1" )
				)
				( pin "J1B3.2"
					( objectStatus "io2" )
				)
				( pin "J1B3.3"
					( objectStatus "io3" )
				)
			)
			( gate "C9P17"
				( objectStatus "@baseboard_fab2_lib.baseboard_fab2(sch_1):page200_i36" )
				( pin "C9P17.1"
					( objectStatus "a" )
				)
				( pin "C9P17.2"
					( objectStatus "b" )
				)
			)
			( gate "C9P16"
				( objectStatus "@baseboard_fab2_lib.baseboard_fab2(sch_1):page200_i40" )
				( pin "C9P16.1"
					( objectStatus "a" )
				)
				( pin "C9P16.2"
					( objectStatus "b" )
				)
			)
			( gate "C1D22"
				( objectStatus "@baseboard_fab2_lib.baseboard_fab2(sch_1):page200_i42" )
				( pin "C1D22.1"
					( objectStatus "a" )
				)
				( pin "C1D22.2"
					( objectStatus "b" )
				)
			)
			( gate "R1D45"
				( objectStatus "@baseboard_fab2_lib.baseboard_fab2(sch_1):page200_i43" )
				( pin "R1D45.1"
					( objectStatus "a" )
				)
				( pin "R1D45.2"
					( objectStatus "b" )
				)
			)
			( gate "R1D44"
				( objectStatus "@baseboard_fab2_lib.baseboard_fab2(sch_1):page200_i44" )
				( pin "R1D44.1"
					( objectStatus "a" )
				)
				( pin "R1D44.2"
					( objectStatus "b" )
				)
			)
			( gate "R9P27"
				( objectStatus "@baseboard_fab2_lib.baseboard_fab2(sch_1):page200_i47" )
				( pin "R9P27.1"
					( objectStatus "a" )
				)
				( pin "R9P27.2"
					( objectStatus "b" )
				)
			)
			( gate "R1D46"
				( objectStatus "@baseboard_fab2_lib.baseboard_fab2(sch_1):page200_i48" )
				( pin "R1D46.1"
					( objectStatus "a" )
				)
				( pin "R1D46.2"
					( objectStatus "b" )
				)
			)
			( gate "R9R1"
				( objectStatus "@baseboard_fab2_lib.baseboard_fab2(sch_1):page200_i49" )
				( pin "R9R1.1"
					( objectStatus "\1\" )
				)
				( pin "R9R1.2"
					( objectStatus "\2\" )
				)
				( pin "R9R1.3"
					( objectStatus "\3\" )
				)
				( pin "R9R1.4"
					( objectStatus "\4\" )
				)
				( pin "R9R1.5"
					( objectStatus "\5\" )
				)
				( pin "R9R1.6"
					( objectStatus "\6\" )
				)
			)
			( gate "R1D49"
				( objectStatus "@baseboard_fab2_lib.baseboard_fab2(sch_1):page200_i50" )
				( pin "R1D49.1"
					( objectStatus "\1\" )
				)
				( pin "R1D49.2"
					( objectStatus "\2\" )
				)
				( pin "R1D49.3"
					( objectStatus "\3\" )
				)
				( pin "R1D49.4"
					( objectStatus "\4\" )
				)
				( pin "R1D49.5"
					( objectStatus "\5\" )
				)
				( pin "R1D49.6"
					( objectStatus "\6\" )
				)
			)
			( gate "R9P26"
				( objectStatus "@baseboard_fab2_lib.baseboard_fab2(sch_1):page200_i51" )
				( pin "R9P26.1"
					( objectStatus "a" )
				)
				( pin "R9P26.2"
					( objectStatus "b" )
				)
			)
			( gate "R1D47"
				( objectStatus "@baseboard_fab2_lib.baseboard_fab2(sch_1):page200_i52" )
				( pin "R1D47.1"
					( objectStatus "a" )
				)
				( pin "R1D47.2"
					( objectStatus "b" )
				)
			)
			( gate "EU1E3"
				( objectStatus "@baseboard_fab2_lib.baseboard_fab2(sch_1):page200_i54" )
				( pin "EU1E3.5"
					( objectStatus "d" )
				)
				( pin "EU1E3.4"
					( objectStatus "g" )
				)
				( pin "EU1E3.1"
					( objectStatus "s1" )
				)
				( pin "EU1E3.2"
					( objectStatus "s2" )
				)
				( pin "EU1E3.3"
					( objectStatus "s3" )
				)
			)
			( gate "R1E1"
				( objectStatus "@baseboard_fab2_lib.baseboard_fab2(sch_1):page200_i56" )
				( pin "R1E1.1"
					( objectStatus "a" )
				)
				( pin "R1E1.2"
					( objectStatus "b" )
				)
			)
			( gate "EU9R1"
				( objectStatus "@baseboard_fab2_lib.baseboard_fab2(sch_1):page200_i57" )
				( pin "EU9R1.5"
					( objectStatus "d" )
				)
				( pin "EU9R1.4"
					( objectStatus "g" )
				)
				( pin "EU9R1.1"
					( objectStatus "s1" )
				)
				( pin "EU9R1.2"
					( objectStatus "s2" )
				)
				( pin "EU9R1.3"
					( objectStatus "s3" )
				)
			)
			( gate "R9R4"
				( objectStatus "@baseboard_fab2_lib.baseboard_fab2(sch_1):page200_i58" )
				( pin "R9R4.1"
					( objectStatus "a" )
				)
				( pin "R9R4.2"
					( objectStatus "b" )
				)
			)
			( gate "EU1E1"
				( objectStatus "@baseboard_fab2_lib.baseboard_fab2(sch_1):page200_i59" )
				( pin "EU1E1.5"
					( objectStatus "d" )
				)
				( pin "EU1E1.4"
					( objectStatus "g" )
				)
				( pin "EU1E1.1"
					( objectStatus "s1" )
				)
				( pin "EU1E1.2"
					( objectStatus "s2" )
				)
				( pin "EU1E1.3"
					( objectStatus "s3" )
				)
			)
			( gate "R1D48"
				( objectStatus "@baseboard_fab2_lib.baseboard_fab2(sch_1):page200_i60" )
				( pin "R1D48.1"
					( objectStatus "a" )
				)
				( pin "R1D48.2"
					( objectStatus "b" )
				)
			)
			( gate "R9P19"
				( objectStatus "@baseboard_fab2_lib.baseboard_fab2(sch_1):page200_i70" )
				( pin "R9P19.1"
					( objectStatus "a" )
				)
				( pin "R9P19.2"
					( objectStatus "b" )
				)
			)
			( gate "R9P21"
				( objectStatus "@baseboard_fab2_lib.baseboard_fab2(sch_1):page200_i71" )
				( pin "R9P21.1"
					( objectStatus "a" )
				)
				( pin "R9P21.2"
					( objectStatus "b" )
				)
			)
			( gate "R9P20"
				( objectStatus "@baseboard_fab2_lib.baseboard_fab2(sch_1):page200_i86" )
				( pin "R9P20.1"
					( objectStatus "a" )
				)
				( pin "R9P20.2"
					( objectStatus "b" )
				)
			)
			( gate "U1D1"
				( objectStatus "@baseboard_fab2_lib.baseboard_fab2(sch_1):page200_i103" )
				( pin "U1D1.2"
					( objectStatus "a" )
				)
				( pin "U1D1.1"
					( objectStatus "oe" )
				)
				( pin "U1D1.4"
					( objectStatus "y" )
				)
			)
			( gate "R9P13"
				( objectStatus "@baseboard_fab2_lib.baseboard_fab2(sch_1):page200_i107" )
				( pin "R9P13.1"
					( objectStatus "a" )
				)
				( pin "R9P13.2"
					( objectStatus "b" )
				)
			)
			( gate "R9P11"
				( objectStatus "@baseboard_fab2_lib.baseboard_fab2(sch_1):page200_i108" )
				( pin "R9P11.1"
					( objectStatus "a" )
				)
				( pin "R9P11.2"
					( objectStatus "b" )
				)
			)
			( gate "R9P7"
				( objectStatus "@baseboard_fab2_lib.baseboard_fab2(sch_1):page200_i145" )
				( pin "R9P7.1"
					( objectStatus "a" )
				)
				( pin "R9P7.2"
					( objectStatus "b" )
				)
			)
			( gate "R9P9"
				( objectStatus "@baseboard_fab2_lib.baseboard_fab2(sch_1):page200_i146" )
				( pin "R9P9.1"
					( objectStatus "a" )
				)
				( pin "R9P9.2"
					( objectStatus "b" )
				)
			)
			( gate "R9P6"
				( objectStatus "@baseboard_fab2_lib.baseboard_fab2(sch_1):page200_i149" )
				( pin "R9P6.1"
					( objectStatus "a" )
				)
				( pin "R9P6.2"
					( objectStatus "b" )
				)
			)
			( gate "R1D51"
				( objectStatus "@baseboard_fab2_lib.baseboard_fab2(sch_1):page200_i154" )
				( pin "R1D51.1"
					( objectStatus "a" )
				)
				( pin "R1D51.2"
					( objectStatus "b" )
				)
			)
			( gate "C1E2"
				( objectStatus "@baseboard_fab2_lib.baseboard_fab2(sch_1):page200_i155" )
				( pin "C1E2.1"
					( objectStatus "a" )
				)
				( pin "C1E2.2"
					( objectStatus "b" )
				)
			)
			( gate "R1D22"
				( objectStatus "@baseboard_fab2_lib.baseboard_fab2(sch_1):page200_i158" )
				( pin "R1D22.1"
					( objectStatus "a" )
				)
				( pin "R1D22.2"
					( objectStatus "b" )
				)
			)
			( gate "U9P1"
				( objectStatus "@baseboard_fab2_lib.baseboard_fab2(sch_1):page200_i163" )
				( pin "U9P1.5"
					( objectStatus "gnd" )
				)
				( pin "U9P1.4"
					( objectStatus "inap" )
				)
				( pin "U9P1.3"
					( objectStatus "inbn" )
				)
				( pin "U9P1.6"
					( objectStatus "outa" )
				)
				( pin "U9P1.1"
					( objectStatus "outb" )
				)
				( pin "U9P1.2"
					( objectStatus "vdd" )
				)
			)
			( gate "U1D2"
				( objectStatus "@baseboard_fab2_lib.baseboard_fab2(sch_1):page200_i170" )
				( pin "U1D2.5"
					( objectStatus "gnd" )
				)
				( pin "U1D2.4"
					( objectStatus "inap" )
				)
				( pin "U1D2.3"
					( objectStatus "inbn" )
				)
				( pin "U1D2.6"
					( objectStatus "outa" )
				)
				( pin "U1D2.1"
					( objectStatus "outb" )
				)
				( pin "U1D2.2"
					( objectStatus "vdd" )
				)
			)
			( gate "R1D20"
				( objectStatus "@baseboard_fab2_lib.baseboard_fab2(sch_1):page200_i172" )
				( pin "R1D20.1"
					( objectStatus "a" )
				)
				( pin "R1D20.2"
					( objectStatus "b" )
				)
			)
			( gate "R1D14"
				( objectStatus "@baseboard_fab2_lib.baseboard_fab2(sch_1):page200_i173" )
				( pin "R1D14.1"
					( objectStatus "a" )
				)
				( pin "R1D14.2"
					( objectStatus "b" )
				)
			)
			( gate "R1D12"
				( objectStatus "@baseboard_fab2_lib.baseboard_fab2(sch_1):page200_i174" )
				( pin "R1D12.1"
					( objectStatus "a" )
				)
				( pin "R1D12.2"
					( objectStatus "b" )
				)
			)
			( gate "R1D19"
				( objectStatus "@baseboard_fab2_lib.baseboard_fab2(sch_1):page200_i175" )
				( pin "R1D19.1"
					( objectStatus "a" )
				)
				( pin "R1D19.2"
					( objectStatus "b" )
				)
			)
			( gate "C9P6"
				( objectStatus "@baseboard_fab2_lib.baseboard_fab2(sch_1):page200_i185" )
				( pin "C9P6.1"
					( objectStatus "a" )
				)
				( pin "C9P6.2"
					( objectStatus "b" )
				)
			)
			( gate "C1D9"
				( objectStatus "@baseboard_fab2_lib.baseboard_fab2(sch_1):page200_i187" )
				( pin "C1D9.1"
					( objectStatus "a" )
				)
				( pin "C1D9.2"
					( objectStatus "b" )
				)
			)
			( gate "R1D10"
				( objectStatus "@baseboard_fab2_lib.baseboard_fab2(sch_1):page200_i189" )
				( pin "R1D10.1"
					( objectStatus "a" )
				)
				( pin "R1D10.2"
					( objectStatus "b" )
				)
			)
			( gate "R1D23"
				( objectStatus "@baseboard_fab2_lib.baseboard_fab2(sch_1):page200_i191" )
				( pin "R1D23.1"
					( objectStatus "a" )
				)
				( pin "R1D23.2"
					( objectStatus "b" )
				)
			)
			( gate "R9P10"
				( objectStatus "@baseboard_fab2_lib.baseboard_fab2(sch_1):page200_i192" )
				( pin "R9P10.1"
					( objectStatus "a" )
				)
				( pin "R9P10.2"
					( objectStatus "b" )
				)
			)
			( gate "Q9P1"
				( objectStatus "@baseboard_fab2_lib.baseboard_fab2(sch_1):page200_i196" )
				( pin "Q9P1.6"
					( objectStatus "drain(0)" )
				)
				( pin "Q9P1.2"
					( objectStatus "gate(0)" )
				)
				( pin "Q9P1.1"
					( objectStatus "source(0)" )
				)
			)
			( gate "R9P15"
				( objectStatus "@baseboard_fab2_lib.baseboard_fab2(sch_1):page200_i198" )
				( pin "R9P15.1"
					( objectStatus "a" )
				)
				( pin "R9P15.2"
					( objectStatus "b" )
				)
			)
			( gate "Q9P1"
				( objectStatus "@baseboard_fab2_lib.baseboard_fab2(sch_1):page200_i199" )
				( pin "Q9P1.3"
					( objectStatus "drain(0)" )
				)
				( pin "Q9P1.5"
					( objectStatus "gate(0)" )
				)
				( pin "Q9P1.4"
					( objectStatus "source(0)" )
				)
			)
			( gate "U9P2"
				( objectStatus "@baseboard_fab2_lib.baseboard_fab2(sch_1):page200_i200" )
				( pin "U9P2.5"
					( objectStatus "gnd" )
				)
				( pin "U9P2.4"
					( objectStatus "inap" )
				)
				( pin "U9P2.3"
					( objectStatus "inbn" )
				)
				( pin "U9P2.6"
					( objectStatus "outa" )
				)
				( pin "U9P2.1"
					( objectStatus "outb" )
				)
				( pin "U9P2.2"
					( objectStatus "vdd" )
				)
			)
			( gate "C9P11"
				( objectStatus "@baseboard_fab2_lib.baseboard_fab2(sch_1):page200_i201" )
				( pin "C9P11.1"
					( objectStatus "a" )
				)
				( pin "C9P11.2"
					( objectStatus "b" )
				)
			)
			( gate "Q1D2"
				( objectStatus "@baseboard_fab2_lib.baseboard_fab2(sch_1):page200_i203" )
				( pin "Q1D2.3"
					( objectStatus "drn" )
				)
				( pin "Q1D2.1"
					( objectStatus "gate" )
				)
				( pin "Q1D2.2"
					( objectStatus "src" )
				)
			)
			( gate "R1D21"
				( objectStatus "@baseboard_fab2_lib.baseboard_fab2(sch_1):page200_i204" )
				( pin "R1D21.1"
					( objectStatus "a" )
				)
				( pin "R1D21.2"
					( objectStatus "b" )
				)
			)
			( gate "R9P4"
				( objectStatus "@baseboard_fab2_lib.baseboard_fab2(sch_1):page200_i210" )
				( pin "R9P4.1"
					( objectStatus "a" )
				)
				( pin "R9P4.2"
					( objectStatus "b" )
				)
			)
			( gate "CR9P2"
				( objectStatus "@baseboard_fab2_lib.baseboard_fab2(sch_1):page200_i213" )
				( pin "CR9P2.2"
					( objectStatus "a" )
				)
				( pin "CR9P2.1"
					( objectStatus "c" )
				)
			)
			( gate "CR9P1"
				( objectStatus "@baseboard_fab2_lib.baseboard_fab2(sch_1):page200_i214" )
				( pin "CR9P1.2"
					( objectStatus "a" )
				)
				( pin "CR9P1.1"
					( objectStatus "c" )
				)
			)
			( gate "R9P5"
				( objectStatus "@baseboard_fab2_lib.baseboard_fab2(sch_1):page200_i215" )
				( pin "R9P5.1"
					( objectStatus "a" )
				)
				( pin "R9P5.2"
					( objectStatus "b" )
				)
			)
			( gate "R9P12"
				( objectStatus "@baseboard_fab2_lib.baseboard_fab2(sch_1):page200_i218" )
				( pin "R9P12.1"
					( objectStatus "a" )
				)
				( pin "R9P12.2"
					( objectStatus "b" )
				)
			)
			( gate "CR1"
				( objectStatus "@baseboard_fab2_lib.baseboard_fab2(sch_1):page200_i220" )
				( pin "CR1.2"
					( objectStatus "a" )
				)
				( pin "CR1.1"
					( objectStatus "c" )
				)
			)
			( gate "R112"
				( objectStatus "@baseboard_fab2_lib.baseboard_fab2(sch_1):page200_i222" )
				( pin "R112.1"
					( objectStatus "a" )
				)
				( pin "R112.2"
					( objectStatus "b" )
				)
			)
			( gate "R4E4"
				( objectStatus "@baseboard_fab2_lib.baseboard_fab2(sch_1):page201_i19" )
				( pin "R4E4.1"
					( objectStatus "a" )
				)
				( pin "R4E4.2"
					( objectStatus "b" )
				)
			)
			( gate "R4E10"
				( objectStatus "@baseboard_fab2_lib.baseboard_fab2(sch_1):page201_i20" )
				( pin "R4E10.1"
					( objectStatus "a" )
				)
				( pin "R4E10.2"
					( objectStatus "b" )
				)
			)
			( gate "R4D31"
				( objectStatus "@baseboard_fab2_lib.baseboard_fab2(sch_1):page201_i22" )
				( pin "R4D31.1"
					( objectStatus "a" )
				)
				( pin "R4D31.2"
					( objectStatus "b" )
				)
			)
			( gate "R4D58"
				( objectStatus "@baseboard_fab2_lib.baseboard_fab2(sch_1):page201_i25" )
				( pin "R4D58.1"
					( objectStatus "a" )
				)
				( pin "R4D58.2"
					( objectStatus "b" )
				)
			)
			( gate "R4D67"
				( objectStatus "@baseboard_fab2_lib.baseboard_fab2(sch_1):page201_i26" )
				( pin "R4D67.1"
					( objectStatus "a" )
				)
				( pin "R4D67.2"
					( objectStatus "b" )
				)
			)
			( gate "R4E5"
				( objectStatus "@baseboard_fab2_lib.baseboard_fab2(sch_1):page201_i27" )
				( pin "R4E5.1"
					( objectStatus "a" )
				)
				( pin "R4E5.2"
					( objectStatus "b" )
				)
			)
			( gate "R4D50"
				( objectStatus "@baseboard_fab2_lib.baseboard_fab2(sch_1):page201_i28" )
				( pin "R4D50.1"
					( objectStatus "a" )
				)
				( pin "R4D50.2"
					( objectStatus "b" )
				)
			)
			( gate "C4D25"
				( objectStatus "@baseboard_fab2_lib.baseboard_fab2(sch_1):page201_i30" )
				( pin "C4D25.1"
					( objectStatus "a" )
				)
				( pin "C4D25.2"
					( objectStatus "b" )
				)
			)
			( gate "R4D53"
				( objectStatus "@baseboard_fab2_lib.baseboard_fab2(sch_1):page201_i31" )
				( pin "R4D53.1"
					( objectStatus "a" )
				)
				( pin "R4D53.2"
					( objectStatus "b" )
				)
			)
			( gate "C4D26"
				( objectStatus "@baseboard_fab2_lib.baseboard_fab2(sch_1):page201_i32" )
				( pin "C4D26.1"
					( objectStatus "a" )
				)
				( pin "C4D26.2"
					( objectStatus "b" )
				)
			)
			( gate "C4D15"
				( objectStatus "@baseboard_fab2_lib.baseboard_fab2(sch_1):page201_i37" )
				( pin "C4D15.1"
					( objectStatus "a" )
				)
				( pin "C4D15.2"
					( objectStatus "b" )
				)
			)
			( gate "C4D19"
				( objectStatus "@baseboard_fab2_lib.baseboard_fab2(sch_1):page201_i39" )
				( pin "C4D19.1"
					( objectStatus "a" )
				)
				( pin "C4D19.2"
					( objectStatus "b" )
				)
			)
			( gate "R4D26"
				( objectStatus "@baseboard_fab2_lib.baseboard_fab2(sch_1):page201_i40" )
				( pin "R4D26.1"
					( objectStatus "a" )
				)
				( pin "R4D26.2"
					( objectStatus "b" )
				)
			)
			( gate "R4E9"
				( objectStatus "@baseboard_fab2_lib.baseboard_fab2(sch_1):page201_i52" )
				( pin "R4E9.1"
					( objectStatus "a" )
				)
				( pin "R4E9.2"
					( objectStatus "b" )
				)
			)
			( gate "R4D27"
				( objectStatus "@baseboard_fab2_lib.baseboard_fab2(sch_1):page201_i54" )
				( pin "R4D27.1"
					( objectStatus "a" )
				)
				( pin "R4D27.2"
					( objectStatus "b" )
				)
			)
			( gate "R4D32"
				( objectStatus "@baseboard_fab2_lib.baseboard_fab2(sch_1):page201_i55" )
				( pin "R4D32.1"
					( objectStatus "a" )
				)
				( pin "R4D32.2"
					( objectStatus "b" )
				)
			)
			( gate "R4E6"
				( objectStatus "@baseboard_fab2_lib.baseboard_fab2(sch_1):page201_i56" )
				( pin "R4E6.1"
					( objectStatus "a" )
				)
				( pin "R4E6.2"
					( objectStatus "b" )
				)
			)
			( gate "C4D20"
				( objectStatus "@baseboard_fab2_lib.baseboard_fab2(sch_1):page201_i60" )
				( pin "C4D20.1"
					( objectStatus "a" )
				)
				( pin "C4D20.2"
					( objectStatus "b" )
				)
			)
			( gate "C4D29"
				( objectStatus "@baseboard_fab2_lib.baseboard_fab2(sch_1):page201_i64" )
				( pin "C4D29.1"
					( objectStatus "a" )
				)
				( pin "C4D29.2"
					( objectStatus "b" )
				)
			)
			( gate "C4D17"
				( objectStatus "@baseboard_fab2_lib.baseboard_fab2(sch_1):page201_i66" )
				( pin "C4D17.1"
					( objectStatus "a" )
				)
				( pin "C4D17.2"
					( objectStatus "b" )
				)
			)
			( gate "C4D18"
				( objectStatus "@baseboard_fab2_lib.baseboard_fab2(sch_1):page201_i68" )
				( pin "C4D18.1"
					( objectStatus "a" )
				)
				( pin "C4D18.2"
					( objectStatus "b" )
				)
			)
			( gate "C4D45"
				( objectStatus "@baseboard_fab2_lib.baseboard_fab2(sch_1):page201_i70" )
				( pin "C4D45.1"
					( objectStatus "a" )
				)
				( pin "C4D45.2"
					( objectStatus "b" )
				)
			)
			( gate "R4D66"
				( objectStatus "@baseboard_fab2_lib.baseboard_fab2(sch_1):page201_i98" )
				( pin "R4D66.1"
					( objectStatus "a" )
				)
				( pin "R4D66.2"
					( objectStatus "b" )
				)
			)
			( gate "R6P32"
				( objectStatus "@baseboard_fab2_lib.baseboard_fab2(sch_1):page201_i102" )
				( pin "R6P32.1"
					( objectStatus "a" )
				)
				( pin "R6P32.2"
					( objectStatus "b" )
				)
			)
			( gate "R6P37"
				( objectStatus "@baseboard_fab2_lib.baseboard_fab2(sch_1):page201_i103" )
				( pin "R6P37.1"
					( objectStatus "a" )
				)
				( pin "R6P37.2"
					( objectStatus "b" )
				)
			)
			( gate "R4E8"
				( objectStatus "@baseboard_fab2_lib.baseboard_fab2(sch_1):page201_i109" )
				( pin "R4E8.1"
					( objectStatus "a" )
				)
				( pin "R4E8.2"
					( objectStatus "b" )
				)
			)
			( gate "R4D39"
				( objectStatus "@baseboard_fab2_lib.baseboard_fab2(sch_1):page201_i110" )
				( pin "R4D39.1"
					( objectStatus "a" )
				)
				( pin "R4D39.2"
					( objectStatus "b" )
				)
			)
			( gate "R4E3"
				( objectStatus "@baseboard_fab2_lib.baseboard_fab2(sch_1):page201_i111" )
				( pin "R4E3.1"
					( objectStatus "a" )
				)
				( pin "R4E3.2"
					( objectStatus "b" )
				)
			)
			( gate "R4D30"
				( objectStatus "@baseboard_fab2_lib.baseboard_fab2(sch_1):page201_i116" )
				( pin "R4D30.1"
					( objectStatus "a" )
				)
				( pin "R4D30.2"
					( objectStatus "b" )
				)
			)
			( gate "R6P27"
				( objectStatus "@baseboard_fab2_lib.baseboard_fab2(sch_1):page201_i120" )
				( pin "R6P27.1"
					( objectStatus "a" )
				)
				( pin "R6P27.2"
					( objectStatus "b" )
				)
			)
			( gate "R6P28"
				( objectStatus "@baseboard_fab2_lib.baseboard_fab2(sch_1):page201_i121" )
				( pin "R6P28.1"
					( objectStatus "a" )
				)
				( pin "R6P28.2"
					( objectStatus "b" )
				)
			)
			( gate "J8D4"
				( objectStatus "@baseboard_fab2_lib.baseboard_fab2(sch_1):page201_i122" )
				( pin "J8D4.1"
					( objectStatus "io1" )
				)
				( pin "J8D4.2"
					( objectStatus "io2" )
				)
				( pin "J8D4.3"
					( objectStatus "io3" )
				)
			)
			( gate "R4D63"
				( objectStatus "@baseboard_fab2_lib.baseboard_fab2(sch_1):page201_i124" )
				( pin "R4D63.1"
					( objectStatus "a" )
				)
				( pin "R4D63.2"
					( objectStatus "b" )
				)
			)
			( gate "C4D42"
				( objectStatus "@baseboard_fab2_lib.baseboard_fab2(sch_1):page201_i125" )
				( pin "C4D42.1"
					( objectStatus "a" )
				)
				( pin "C4D42.2"
					( objectStatus "b" )
				)
			)
			( gate "R4D65"
				( objectStatus "@baseboard_fab2_lib.baseboard_fab2(sch_1):page201_i127" )
				( pin "R4D65.1"
					( objectStatus "a" )
				)
				( pin "R4D65.2"
					( objectStatus "b" )
				)
			)
			( gate "R6P45"
				( objectStatus "@baseboard_fab2_lib.baseboard_fab2(sch_1):page201_i128" )
				( pin "R6P45.1"
					( objectStatus "a" )
				)
				( pin "R6P45.2"
					( objectStatus "b" )
				)
			)
			( gate "R6P18"
				( objectStatus "@baseboard_fab2_lib.baseboard_fab2(sch_1):page201_i131" )
				( pin "R6P18.1"
					( objectStatus "a" )
				)
				( pin "R6P18.2"
					( objectStatus "b" )
				)
			)
			( gate "R6P16"
				( objectStatus "@baseboard_fab2_lib.baseboard_fab2(sch_1):page201_i132" )
				( pin "R6P16.1"
					( objectStatus "a" )
				)
				( pin "R6P16.2"
					( objectStatus "b" )
				)
			)
			( gate "R6P42"
				( objectStatus "@baseboard_fab2_lib.baseboard_fab2(sch_1):page201_i139" )
				( pin "R6P42.1"
					( objectStatus "a" )
				)
				( pin "R6P42.2"
					( objectStatus "b" )
				)
			)
			( gate "R6P38"
				( objectStatus "@baseboard_fab2_lib.baseboard_fab2(sch_1):page201_i147" )
				( pin "R6P38.1"
					( objectStatus "a" )
				)
				( pin "R6P38.2"
					( objectStatus "b" )
				)
			)
			( gate "R6P34"
				( objectStatus "@baseboard_fab2_lib.baseboard_fab2(sch_1):page201_i148" )
				( pin "R6P34.1"
					( objectStatus "a" )
				)
				( pin "R6P34.2"
					( objectStatus "b" )
				)
			)
			( gate "R6P30"
				( objectStatus "@baseboard_fab2_lib.baseboard_fab2(sch_1):page201_i149" )
				( pin "R6P30.1"
					( objectStatus "a" )
				)
				( pin "R6P30.2"
					( objectStatus "b" )
				)
			)
			( gate "R6P43"
				( objectStatus "@baseboard_fab2_lib.baseboard_fab2(sch_1):page201_i150" )
				( pin "R6P43.1"
					( objectStatus "a" )
				)
				( pin "R6P43.2"
					( objectStatus "b" )
				)
			)
			( gate "R6P29"
				( objectStatus "@baseboard_fab2_lib.baseboard_fab2(sch_1):page201_i154" )
				( pin "R6P29.1"
					( objectStatus "a" )
				)
				( pin "R6P29.2"
					( objectStatus "b" )
				)
			)
			( gate "EU4D4"
				( objectStatus "@baseboard_fab2_lib.baseboard_fab2(sch_1):page201_i155" )
				( pin "EU4D4.23"
					( objectStatus "airef1" )
				)
				( pin "EU4D4.25"
					( objectStatus "airef2" )
				)
				( pin "EU4D4.27"
					( objectStatus "airef3" )
				)
				( pin "EU4D4.29"
					( objectStatus "airef4" )
				)
				( pin "EU4D4.31"
					( objectStatus "airef5" )
				)
				( pin "EU4D4.33"
					( objectStatus "airef6" )
				)
				( pin "EU4D4.24"
					( objectStatus "aisen1" )
				)
				( pin "EU4D4.26"
					( objectStatus "aisen2" )
				)
				( pin "EU4D4.28"
					( objectStatus "aisen3" )
				)
				( pin "EU4D4.30"
					( objectStatus "aisen4" )
				)
				( pin "EU4D4.32"
					( objectStatus "aisen5" )
				)
				( pin "EU4D4.34"
					( objectStatus "aisen6" )
				)
				( pin "EU4D4.7"
					( objectStatus "apwm1" )
				)
				( pin "EU4D4.6"
					( objectStatus "apwm2" )
				)
				( pin "EU4D4.5"
					( objectStatus "apwm3" )
				)
				( pin "EU4D4.4"
					( objectStatus "apwm4" )
				)
				( pin "EU4D4.3"
					( objectStatus "apwm5" )
				)
				( pin "EU4D4.2"
					( objectStatus "apwm6" )
				)
				( pin "EU4D4.43"
					( objectStatus "atsen" )
				)
				( pin "EU4D4.22"
					( objectStatus "avref" )
				)
				( pin "EU4D4.12"
					( objectStatus "avren" )
				)
				( pin "EU4D4.11"
					( objectStatus "avrrdy" )
				)
				( pin "EU4D4.21"
					( objectStatus "avsen" )
				)
				( pin "EU4D4.37"
					( objectStatus "biref1" )
				)
				( pin "EU4D4.38"
					( objectStatus "bisen1" )
				)
				( pin "EU4D4.1"
					( objectStatus "bpwm1" )
				)
				( pin "EU4D4.42"
					( objectStatus "btsen" )
				)
				( pin "EU4D4.36"
					( objectStatus "bvref" )
				)
				( pin "EU4D4.35"
					( objectStatus "bvsen" )
				)
				( pin "EU4D4.46"
					( objectStatus "iinsen" )
				)
				( pin "EU4D4.15"
					( objectStatus "mp0" )
				)
				( pin "EU4D4.16"
					( objectStatus "mp1" )
				)
				( pin "EU4D4.20"
					( objectStatus "mp2" )
				)
				( pin "EU4D4.39"
					( objectStatus "mp3" )
				)
				( pin "EU4D4.40"
					( objectStatus "mp4" )
				)
				( pin "EU4D4.14"
					( objectStatus "pinalrt_n" )
				)
				( pin "EU4D4.10"
					( objectStatus "reset_n" )
				)
				( pin "EU4D4.9"
					( objectStatus "scl" )
				)
				( pin "EU4D4.8"
					( objectStatus "sda" )
				)
				( pin "EU4D4.49"
					( objectStatus "thpad" )
				)
				( pin "EU4D4.19"
					( objectStatus "valrt_n" )
				)
				( pin "EU4D4.17"
					( objectStatus "vclk" )
				)
				( pin "EU4D4.48"
					( objectStatus "vd12" )
				)
				( pin "EU4D4.47"
					( objectStatus "vdd" )
				)
				( pin "EU4D4.18"
					( objectStatus "vdio" )
				)
				( pin "EU4D4.45"
					( objectStatus "vinsen" )
				)
				( pin "EU4D4.13"
					( objectStatus "vrhot_n" )
				)
				( pin "EU4D4.44"
					( objectStatus "xaddr1" )
				)
				( pin "EU4D4.41"
					( objectStatus "xaddr2" )
				)
			)
			( gate "L4E1"
				( objectStatus "@baseboard_fab2_lib.baseboard_fab2(sch_1):page202_i5" )
				( pin "L4E1.1"
					( objectStatus "ina" )
				)
				( pin "L4E1.2"
					( objectStatus "inb" )
				)
			)
			( gate "C6R7"
				( objectStatus "@baseboard_fab2_lib.baseboard_fab2(sch_1):page202_i9" )
				( pin "C6R7.1"
					( objectStatus "a" )
				)
				( pin "C6R7.2"
					( objectStatus "b" )
				)
			)
			( gate "C4E5"
				( objectStatus "@baseboard_fab2_lib.baseboard_fab2(sch_1):page202_i18" )
				( pin "C4E5.1"
					( objectStatus "a" )
				)
				( pin "C4E5.2"
					( objectStatus "b" )
				)
			)
			( gate "C4E6"
				( objectStatus "@baseboard_fab2_lib.baseboard_fab2(sch_1):page202_i19" )
				( pin "C4E6.1"
					( objectStatus "a" )
				)
				( pin "C4E6.2"
					( objectStatus "b" )
				)
			)
			( gate "C4E17"
				( objectStatus "@baseboard_fab2_lib.baseboard_fab2(sch_1):page202_i22" )
				( pin "C4E17.1"
					( objectStatus "a" )
				)
				( pin "C4E17.2"
					( objectStatus "b" )
				)
			)
			( gate "C4D37"
				( objectStatus "@baseboard_fab2_lib.baseboard_fab2(sch_1):page202_i24" )
				( pin "C4D37.1"
					( objectStatus "a" )
				)
				( pin "C4D37.2"
					( objectStatus "b" )
				)
			)
			( gate "C4D39"
				( objectStatus "@baseboard_fab2_lib.baseboard_fab2(sch_1):page202_i25" )
				( pin "C4D39.1"
					( objectStatus "a" )
				)
				( pin "C4D39.2"
					( objectStatus "b" )
				)
			)
			( gate "C4E11"
				( objectStatus "@baseboard_fab2_lib.baseboard_fab2(sch_1):page202_i27" )
				( pin "C4E11.1"
					( objectStatus "a" )
				)
				( pin "C4E11.2"
					( objectStatus "b" )
				)
			)
			( gate "L4D3"
				( objectStatus "@baseboard_fab2_lib.baseboard_fab2(sch_1):page202_i29" )
				( pin "L4D3.1"
					( objectStatus "ina" )
				)
				( pin "L4D3.2"
					( objectStatus "inb" )
				)
			)
			( gate "C4E1"
				( objectStatus "@baseboard_fab2_lib.baseboard_fab2(sch_1):page202_i32" )
				( pin "C4E1.1"
					( objectStatus "a" )
				)
				( pin "C4E1.2"
					( objectStatus "b" )
				)
			)
			( gate "R6R2"
				( objectStatus "@baseboard_fab2_lib.baseboard_fab2(sch_1):page202_i33" )
				( pin "R6R2.1"
					( objectStatus "a" )
				)
				( pin "R6R2.2"
					( objectStatus "b" )
				)
			)
			( gate "C4E10"
				( objectStatus "@baseboard_fab2_lib.baseboard_fab2(sch_1):page202_i34" )
				( pin "C4E10.1"
					( objectStatus "a" )
				)
				( pin "C4E10.2"
					( objectStatus "b" )
				)
			)
			( gate "C4E20"
				( objectStatus "@baseboard_fab2_lib.baseboard_fab2(sch_1):page202_i35" )
				( pin "C4E20.1"
					( objectStatus "a" )
				)
				( pin "C4E20.2"
					( objectStatus "b" )
				)
			)
			( gate "C4E19"
				( objectStatus "@baseboard_fab2_lib.baseboard_fab2(sch_1):page202_i36" )
				( pin "C4E19.1"
					( objectStatus "a" )
				)
				( pin "C4E19.2"
					( objectStatus "b" )
				)
			)
			( gate "C6R11"
				( objectStatus "@baseboard_fab2_lib.baseboard_fab2(sch_1):page202_i37" )
				( pin "C6R11.1"
					( objectStatus "a" )
				)
				( pin "C6R11.2"
					( objectStatus "b" )
				)
			)
			( gate "C6P13"
				( objectStatus "@baseboard_fab2_lib.baseboard_fab2(sch_1):page202_i38" )
				( pin "C6P13.1"
					( objectStatus "a" )
				)
				( pin "C6P13.2"
					( objectStatus "b" )
				)
			)
			( gate "R6P36"
				( objectStatus "@baseboard_fab2_lib.baseboard_fab2(sch_1):page202_i39" )
				( pin "R6P36.1"
					( objectStatus "a" )
				)
				( pin "R6P36.2"
					( objectStatus "b" )
				)
			)
			( gate "C6R13"
				( objectStatus "@baseboard_fab2_lib.baseboard_fab2(sch_1):page202_i42" )
				( pin "C6R13.1"
					( objectStatus "a" )
				)
				( pin "C6R13.2"
					( objectStatus "b" )
				)
			)
			( gate "C4D41"
				( objectStatus "@baseboard_fab2_lib.baseboard_fab2(sch_1):page202_i45" )
				( pin "C4D41.1"
					( objectStatus "a" )
				)
				( pin "C4D41.2"
					( objectStatus "b" )
				)
			)
			( gate "C4E4"
				( objectStatus "@baseboard_fab2_lib.baseboard_fab2(sch_1):page202_i46" )
				( pin "C4E4.1"
					( objectStatus "a" )
				)
				( pin "C4E4.2"
					( objectStatus "b" )
				)
			)
			( gate "C4E2"
				( objectStatus "@baseboard_fab2_lib.baseboard_fab2(sch_1):page202_i47" )
				( pin "C4E2.1"
					( objectStatus "a" )
				)
				( pin "C4E2.2"
					( objectStatus "b" )
				)
			)
			( gate "C6R4"
				( objectStatus "@baseboard_fab2_lib.baseboard_fab2(sch_1):page202_i48" )
				( pin "C6R4.1"
					( objectStatus "a" )
				)
				( pin "C6R4.2"
					( objectStatus "b" )
				)
			)
			( gate "C6P22"
				( objectStatus "@baseboard_fab2_lib.baseboard_fab2(sch_1):page202_i49" )
				( pin "C6P22.1"
					( objectStatus "a" )
				)
				( pin "C6P22.2"
					( objectStatus "b" )
				)
			)
			( gate "C6N8"
				( objectStatus "@baseboard_fab2_lib.baseboard_fab2(sch_1):page202_i51" )
				( pin "C6N8.1"
					( objectStatus "a" )
				)
				( pin "C6N8.2"
					( objectStatus "b" )
				)
			)
			( gate "C4E3"
				( objectStatus "@baseboard_fab2_lib.baseboard_fab2(sch_1):page202_i61" )
				( pin "C4E3.1"
					( objectStatus "a" )
				)
				( pin "C4E3.2"
					( objectStatus "b" )
				)
			)
			( gate "C6P16"
				( objectStatus "@baseboard_fab2_lib.baseboard_fab2(sch_1):page202_i62" )
				( pin "C6P16.1"
					( objectStatus "a" )
				)
				( pin "C6P16.2"
					( objectStatus "b" )
				)
			)
			( gate "EU4E1"
				( objectStatus "@baseboard_fab2_lib.baseboard_fab2(sch_1):page202_i63" )
				( pin "EU4E1.33"
					( objectStatus "boost" )
				)
				( pin "EU4E1.35"
					( objectStatus "en" )
				)
				( pin "EU4E1.6"
					( objectStatus "gl(0)" )
				)
				( pin "EU4E1.41"
					( objectStatus "gl(1)" )
				)
				( pin "EU4E1.38"
					( objectStatus "iout" )
				)
				( pin "EU4E1.2"
					( objectStatus "lgnd" )
				)
				( pin "EU4E1.31"
					( objectStatus "nc" )
				)
				( pin "EU4E1.37"
					( objectStatus "ocset" )
				)
				( pin "EU4E1.5"
					( objectStatus "pgnd(0)" )
				)
				( pin "EU4E1.7"
					( objectStatus "pgnd(1)" )
				)
				( pin "EU4E1.40"
					( objectStatus "pgnd(2)" )
				)
				( pin "EU4E1.32"
					( objectStatus "phase" )
				)
				( pin "EU4E1.34"
					( objectStatus "pwm" )
				)
				( pin "EU4E1.39"
					( objectStatus "refin" )
				)
				( pin "EU4E1.10"
					( objectStatus "sw" )
				)
				( pin "EU4E1.36"
					( objectStatus "tout_flt" )
				)
				( pin "EU4E1.3"
					( objectStatus "vcc" )
				)
				( pin "EU4E1.4"
					( objectStatus "vdrv" )
				)
				( pin "EU4E1.25"
					( objectStatus "vin(0)" )
				)
				( pin "EU4E1.30"
					( objectStatus "vin(1)" )
				)
				( pin "EU4E1.1"
					( objectStatus "vos" )
				)
			)
			( gate "EU4D6"
				( objectStatus "@baseboard_fab2_lib.baseboard_fab2(sch_1):page202_i64" )
				( pin "EU4D6.33"
					( objectStatus "boost" )
				)
				( pin "EU4D6.35"
					( objectStatus "en" )
				)
				( pin "EU4D6.6"
					( objectStatus "gl(0)" )
				)
				( pin "EU4D6.41"
					( objectStatus "gl(1)" )
				)
				( pin "EU4D6.38"
					( objectStatus "iout" )
				)
				( pin "EU4D6.2"
					( objectStatus "lgnd" )
				)
				( pin "EU4D6.31"
					( objectStatus "nc" )
				)
				( pin "EU4D6.37"
					( objectStatus "ocset" )
				)
				( pin "EU4D6.5"
					( objectStatus "pgnd(0)" )
				)
				( pin "EU4D6.7"
					( objectStatus "pgnd(1)" )
				)
				( pin "EU4D6.40"
					( objectStatus "pgnd(2)" )
				)
				( pin "EU4D6.32"
					( objectStatus "phase" )
				)
				( pin "EU4D6.34"
					( objectStatus "pwm" )
				)
				( pin "EU4D6.39"
					( objectStatus "refin" )
				)
				( pin "EU4D6.10"
					( objectStatus "sw" )
				)
				( pin "EU4D6.36"
					( objectStatus "tout_flt" )
				)
				( pin "EU4D6.3"
					( objectStatus "vcc" )
				)
				( pin "EU4D6.4"
					( objectStatus "vdrv" )
				)
				( pin "EU4D6.25"
					( objectStatus "vin(0)" )
				)
				( pin "EU4D6.30"
					( objectStatus "vin(1)" )
				)
				( pin "EU4D6.1"
					( objectStatus "vos" )
				)
			)
			( gate "R31"
				( objectStatus "@baseboard_fab2_lib.baseboard_fab2(sch_1):page202_i65" )
				( pin "R31.1"
					( objectStatus "a" )
				)
				( pin "R31.2"
					( objectStatus "b" )
				)
			)
			( gate "R30"
				( objectStatus "@baseboard_fab2_lib.baseboard_fab2(sch_1):page202_i67" )
				( pin "R30.1"
					( objectStatus "a" )
				)
				( pin "R30.2"
					( objectStatus "b" )
				)
			)
			( gate "C6R1"
				( objectStatus "@baseboard_fab2_lib.baseboard_fab2(sch_1):page203_i1" )
				( pin "C6R1.1"
					( objectStatus "a" )
				)
				( pin "C6R1.2"
					( objectStatus "b" )
				)
			)
			( gate "C6R6"
				( objectStatus "@baseboard_fab2_lib.baseboard_fab2(sch_1):page203_i2" )
				( pin "C6R6.1"
					( objectStatus "a" )
				)
				( pin "C6R6.2"
					( objectStatus "b" )
				)
			)
			( gate "C4D9"
				( objectStatus "@baseboard_fab2_lib.baseboard_fab2(sch_1):page203_i3" )
				( pin "C4D9.1"
					( objectStatus "a" )
				)
				( pin "C4D9.2"
					( objectStatus "b" )
				)
			)
			( gate "L4D2"
				( objectStatus "@baseboard_fab2_lib.baseboard_fab2(sch_1):page203_i15" )
				( pin "L4D2.1"
					( objectStatus "ina" )
				)
				( pin "L4D2.2"
					( objectStatus "inb" )
				)
			)
			( gate "C6R3"
				( objectStatus "@baseboard_fab2_lib.baseboard_fab2(sch_1):page203_i16" )
				( pin "C6R3.1"
					( objectStatus "a" )
				)
				( pin "C6R3.2"
					( objectStatus "b" )
				)
			)
			( gate "C6R9"
				( objectStatus "@baseboard_fab2_lib.baseboard_fab2(sch_1):page203_i18" )
				( pin "C6R9.1"
					( objectStatus "a" )
				)
				( pin "C6R9.2"
					( objectStatus "b" )
				)
			)
			( gate "L4D1"
				( objectStatus "@baseboard_fab2_lib.baseboard_fab2(sch_1):page203_i24" )
				( pin "L4D1.1"
					( objectStatus "ina" )
				)
				( pin "L4D1.2"
					( objectStatus "inb" )
				)
			)
			( gate "C6P3"
				( objectStatus "@baseboard_fab2_lib.baseboard_fab2(sch_1):page203_i25" )
				( pin "C6P3.1"
					( objectStatus "a" )
				)
				( pin "C6P3.2"
					( objectStatus "b" )
				)
			)
			( gate "C6P23"
				( objectStatus "@baseboard_fab2_lib.baseboard_fab2(sch_1):page203_i28" )
				( pin "C6P23.1"
					( objectStatus "a" )
				)
				( pin "C6P23.2"
					( objectStatus "b" )
				)
			)
			( gate "C6P14"
				( objectStatus "@baseboard_fab2_lib.baseboard_fab2(sch_1):page203_i29" )
				( pin "C6P14.1"
					( objectStatus "a" )
				)
				( pin "C6P14.2"
					( objectStatus "b" )
				)
			)
			( gate "C6P18"
				( objectStatus "@baseboard_fab2_lib.baseboard_fab2(sch_1):page203_i30" )
				( pin "C6P18.1"
					( objectStatus "a" )
				)
				( pin "C6P18.2"
					( objectStatus "b" )
				)
			)
			( gate "C6P8"
				( objectStatus "@baseboard_fab2_lib.baseboard_fab2(sch_1):page203_i32" )
				( pin "C6P8.1"
					( objectStatus "a" )
				)
				( pin "C6P8.2"
					( objectStatus "b" )
				)
			)
			( gate "C6N9"
				( objectStatus "@baseboard_fab2_lib.baseboard_fab2(sch_1):page203_i34" )
				( pin "C6N9.1"
					( objectStatus "a" )
				)
				( pin "C6N9.2"
					( objectStatus "b" )
				)
			)
			( gate "R6P19"
				( objectStatus "@baseboard_fab2_lib.baseboard_fab2(sch_1):page203_i38" )
				( pin "R6P19.1"
					( objectStatus "a" )
				)
				( pin "R6P19.2"
					( objectStatus "b" )
				)
			)
			( gate "C4D13"
				( objectStatus "@baseboard_fab2_lib.baseboard_fab2(sch_1):page203_i40" )
				( pin "C4D13.1"
					( objectStatus "a" )
				)
				( pin "C4D13.2"
					( objectStatus "b" )
				)
			)
			( gate "C4D14"
				( objectStatus "@baseboard_fab2_lib.baseboard_fab2(sch_1):page203_i41" )
				( pin "C4D14.1"
					( objectStatus "a" )
				)
				( pin "C4D14.2"
					( objectStatus "b" )
				)
			)
			( gate "C4D28"
				( objectStatus "@baseboard_fab2_lib.baseboard_fab2(sch_1):page203_i42" )
				( pin "C4D28.1"
					( objectStatus "a" )
				)
				( pin "C4D28.2"
					( objectStatus "b" )
				)
			)
			( gate "C4D16"
				( objectStatus "@baseboard_fab2_lib.baseboard_fab2(sch_1):page203_i45" )
				( pin "C4D16.1"
					( objectStatus "a" )
				)
				( pin "C4D16.2"
					( objectStatus "b" )
				)
			)
			( gate "C4D35"
				( objectStatus "@baseboard_fab2_lib.baseboard_fab2(sch_1):page203_i46" )
				( pin "C4D35.1"
					( objectStatus "a" )
				)
				( pin "C4D35.2"
					( objectStatus "b" )
				)
			)
			( gate "C4D30"
				( objectStatus "@baseboard_fab2_lib.baseboard_fab2(sch_1):page203_i47" )
				( pin "C4D30.1"
					( objectStatus "a" )
				)
				( pin "C4D30.2"
					( objectStatus "b" )
				)
			)
			( gate "C4D5"
				( objectStatus "@baseboard_fab2_lib.baseboard_fab2(sch_1):page203_i48" )
				( pin "C4D5.1"
					( objectStatus "a" )
				)
				( pin "C4D5.2"
					( objectStatus "b" )
				)
			)
			( gate "C4D6"
				( objectStatus "@baseboard_fab2_lib.baseboard_fab2(sch_1):page203_i49" )
				( pin "C4D6.1"
					( objectStatus "a" )
				)
				( pin "C4D6.2"
					( objectStatus "b" )
				)
			)
			( gate "R6P10"
				( objectStatus "@baseboard_fab2_lib.baseboard_fab2(sch_1):page203_i50" )
				( pin "R6P10.1"
					( objectStatus "a" )
				)
				( pin "R6P10.2"
					( objectStatus "b" )
				)
			)
			( gate "C4D7"
				( objectStatus "@baseboard_fab2_lib.baseboard_fab2(sch_1):page203_i51" )
				( pin "C4D7.1"
					( objectStatus "a" )
				)
				( pin "C4D7.2"
					( objectStatus "b" )
				)
			)
			( gate "C4D11"
				( objectStatus "@baseboard_fab2_lib.baseboard_fab2(sch_1):page203_i52" )
				( pin "C4D11.1"
					( objectStatus "a" )
				)
				( pin "C4D11.2"
					( objectStatus "b" )
				)
			)
			( gate "C4D10"
				( objectStatus "@baseboard_fab2_lib.baseboard_fab2(sch_1):page203_i53" )
				( pin "C4D10.1"
					( objectStatus "a" )
				)
				( pin "C4D10.2"
					( objectStatus "b" )
				)
			)
			( gate "C6P19"
				( objectStatus "@baseboard_fab2_lib.baseboard_fab2(sch_1):page203_i54" )
				( pin "C6P19.1"
					( objectStatus "a" )
				)
				( pin "C6P19.2"
					( objectStatus "b" )
				)
			)
			( gate "C6P20"
				( objectStatus "@baseboard_fab2_lib.baseboard_fab2(sch_1):page203_i57" )
				( pin "C6P20.1"
					( objectStatus "a" )
				)
				( pin "C6P20.2"
					( objectStatus "b" )
				)
			)
			( gate "C6P15"
				( objectStatus "@baseboard_fab2_lib.baseboard_fab2(sch_1):page203_i58" )
				( pin "C6P15.1"
					( objectStatus "a" )
				)
				( pin "C6P15.2"
					( objectStatus "b" )
				)
			)
			( gate "C6P7"
				( objectStatus "@baseboard_fab2_lib.baseboard_fab2(sch_1):page203_i59" )
				( pin "C6P7.1"
					( objectStatus "a" )
				)
				( pin "C6P7.2"
					( objectStatus "b" )
				)
			)
			( gate "C6P21"
				( objectStatus "@baseboard_fab2_lib.baseboard_fab2(sch_1):page203_i66" )
				( pin "C6P21.1"
					( objectStatus "a" )
				)
				( pin "C6P21.2"
					( objectStatus "b" )
				)
			)
			( gate "R4E13"
				( objectStatus "@baseboard_fab2_lib.baseboard_fab2(sch_1):page203_i67" )
				( pin "R4E13.1"
					( objectStatus "a" )
				)
				( pin "R4E13.2"
					( objectStatus "b" )
				)
			)
			( gate "C4D34"
				( objectStatus "@baseboard_fab2_lib.baseboard_fab2(sch_1):page203_i68" )
				( pin "C4D34.1"
					( objectStatus "a" )
				)
				( pin "C4D34.2"
					( objectStatus "b" )
				)
			)
			( gate "C4D4"
				( objectStatus "@baseboard_fab2_lib.baseboard_fab2(sch_1):page203_i69" )
				( pin "C4D4.1"
					( objectStatus "a" )
				)
				( pin "C4D4.2"
					( objectStatus "b" )
				)
			)
			( gate "EU4D3"
				( objectStatus "@baseboard_fab2_lib.baseboard_fab2(sch_1):page203_i70" )
				( pin "EU4D3.33"
					( objectStatus "boost" )
				)
				( pin "EU4D3.35"
					( objectStatus "en" )
				)
				( pin "EU4D3.6"
					( objectStatus "gl(0)" )
				)
				( pin "EU4D3.41"
					( objectStatus "gl(1)" )
				)
				( pin "EU4D3.38"
					( objectStatus "iout" )
				)
				( pin "EU4D3.2"
					( objectStatus "lgnd" )
				)
				( pin "EU4D3.31"
					( objectStatus "nc" )
				)
				( pin "EU4D3.37"
					( objectStatus "ocset" )
				)
				( pin "EU4D3.5"
					( objectStatus "pgnd(0)" )
				)
				( pin "EU4D3.7"
					( objectStatus "pgnd(1)" )
				)
				( pin "EU4D3.40"
					( objectStatus "pgnd(2)" )
				)
				( pin "EU4D3.32"
					( objectStatus "phase" )
				)
				( pin "EU4D3.34"
					( objectStatus "pwm" )
				)
				( pin "EU4D3.39"
					( objectStatus "refin" )
				)
				( pin "EU4D3.10"
					( objectStatus "sw" )
				)
				( pin "EU4D3.36"
					( objectStatus "tout_flt" )
				)
				( pin "EU4D3.3"
					( objectStatus "vcc" )
				)
				( pin "EU4D3.4"
					( objectStatus "vdrv" )
				)
				( pin "EU4D3.25"
					( objectStatus "vin(0)" )
				)
				( pin "EU4D3.30"
					( objectStatus "vin(1)" )
				)
				( pin "EU4D3.1"
					( objectStatus "vos" )
				)
			)
			( gate "EU4D1"
				( objectStatus "@baseboard_fab2_lib.baseboard_fab2(sch_1):page203_i71" )
				( pin "EU4D1.33"
					( objectStatus "boost" )
				)
				( pin "EU4D1.35"
					( objectStatus "en" )
				)
				( pin "EU4D1.6"
					( objectStatus "gl(0)" )
				)
				( pin "EU4D1.41"
					( objectStatus "gl(1)" )
				)
				( pin "EU4D1.38"
					( objectStatus "iout" )
				)
				( pin "EU4D1.2"
					( objectStatus "lgnd" )
				)
				( pin "EU4D1.31"
					( objectStatus "nc" )
				)
				( pin "EU4D1.37"
					( objectStatus "ocset" )
				)
				( pin "EU4D1.5"
					( objectStatus "pgnd(0)" )
				)
				( pin "EU4D1.7"
					( objectStatus "pgnd(1)" )
				)
				( pin "EU4D1.40"
					( objectStatus "pgnd(2)" )
				)
				( pin "EU4D1.32"
					( objectStatus "phase" )
				)
				( pin "EU4D1.34"
					( objectStatus "pwm" )
				)
				( pin "EU4D1.39"
					( objectStatus "refin" )
				)
				( pin "EU4D1.10"
					( objectStatus "sw" )
				)
				( pin "EU4D1.36"
					( objectStatus "tout_flt" )
				)
				( pin "EU4D1.3"
					( objectStatus "vcc" )
				)
				( pin "EU4D1.4"
					( objectStatus "vdrv" )
				)
				( pin "EU4D1.25"
					( objectStatus "vin(0)" )
				)
				( pin "EU4D1.30"
					( objectStatus "vin(1)" )
				)
				( pin "EU4D1.1"
					( objectStatus "vos" )
				)
			)
			( gate "R32"
				( objectStatus "@baseboard_fab2_lib.baseboard_fab2(sch_1):page203_i89" )
				( pin "R32.1"
					( objectStatus "a" )
				)
				( pin "R32.2"
					( objectStatus "b" )
				)
			)
			( gate "R33"
				( objectStatus "@baseboard_fab2_lib.baseboard_fab2(sch_1):page203_i91" )
				( pin "R33.1"
					( objectStatus "a" )
				)
				( pin "R33.2"
					( objectStatus "b" )
				)
			)
			( gate "L4C3"
				( objectStatus "@baseboard_fab2_lib.baseboard_fab2(sch_1):page204_i5" )
				( pin "L4C3.1"
					( objectStatus "ina" )
				)
				( pin "L4C3.2"
					( objectStatus "inb" )
				)
			)
			( gate "C4D12"
				( objectStatus "@baseboard_fab2_lib.baseboard_fab2(sch_1):page204_i9" )
				( pin "C4D12.1"
					( objectStatus "a" )
				)
				( pin "C4D12.2"
					( objectStatus "b" )
				)
			)
			( gate "C4C13"
				( objectStatus "@baseboard_fab2_lib.baseboard_fab2(sch_1):page204_i18" )
				( pin "C4C13.1"
					( objectStatus "a" )
				)
				( pin "C4C13.2"
					( objectStatus "b" )
				)
			)
			( gate "C4C14"
				( objectStatus "@baseboard_fab2_lib.baseboard_fab2(sch_1):page204_i19" )
				( pin "C4C14.1"
					( objectStatus "a" )
				)
				( pin "C4C14.2"
					( objectStatus "b" )
				)
			)
			( gate "C4C17"
				( objectStatus "@baseboard_fab2_lib.baseboard_fab2(sch_1):page204_i22" )
				( pin "C4C17.1"
					( objectStatus "a" )
				)
				( pin "C4C17.2"
					( objectStatus "b" )
				)
			)
			( gate "R6N6"
				( objectStatus "@baseboard_fab2_lib.baseboard_fab2(sch_1):page204_i33" )
				( pin "R6N6.1"
					( objectStatus "a" )
				)
				( pin "R6N6.2"
					( objectStatus "b" )
				)
			)
			( gate "C4C15"
				( objectStatus "@baseboard_fab2_lib.baseboard_fab2(sch_1):page204_i34" )
				( pin "C4C15.1"
					( objectStatus "a" )
				)
				( pin "C4C15.2"
					( objectStatus "b" )
				)
			)
			( gate "C4D3"
				( objectStatus "@baseboard_fab2_lib.baseboard_fab2(sch_1):page204_i35" )
				( pin "C4D3.1"
					( objectStatus "a" )
				)
				( pin "C4D3.2"
					( objectStatus "b" )
				)
			)
			( gate "C4D1"
				( objectStatus "@baseboard_fab2_lib.baseboard_fab2(sch_1):page204_i36" )
				( pin "C4D1.1"
					( objectStatus "a" )
				)
				( pin "C4D1.2"
					( objectStatus "b" )
				)
			)
			( gate "C6P1"
				( objectStatus "@baseboard_fab2_lib.baseboard_fab2(sch_1):page204_i37" )
				( pin "C6P1.1"
					( objectStatus "a" )
				)
				( pin "C6P1.2"
					( objectStatus "b" )
				)
			)
			( gate "C6P17"
				( objectStatus "@baseboard_fab2_lib.baseboard_fab2(sch_1):page204_i38" )
				( pin "C6P17.1"
					( objectStatus "a" )
				)
				( pin "C6P17.2"
					( objectStatus "b" )
				)
			)
			( gate "C6P2"
				( objectStatus "@baseboard_fab2_lib.baseboard_fab2(sch_1):page204_i42" )
				( pin "C6P2.1"
					( objectStatus "a" )
				)
				( pin "C6P2.2"
					( objectStatus "b" )
				)
			)
			( gate "R4C6"
				( objectStatus "@baseboard_fab2_lib.baseboard_fab2(sch_1):page204_i45" )
				( pin "R4C6.1"
					( objectStatus "a" )
				)
				( pin "R4C6.2"
					( objectStatus "b" )
				)
			)
			( gate "L4C1"
				( objectStatus "@baseboard_fab2_lib.baseboard_fab2(sch_1):page204_i46" )
				( pin "L4C1.1"
					( objectStatus "ina" )
				)
				( pin "L4C1.2"
					( objectStatus "inb" )
				)
			)
			( gate "C4D2"
				( objectStatus "@baseboard_fab2_lib.baseboard_fab2(sch_1):page204_i48" )
				( pin "C4D2.1"
					( objectStatus "a" )
				)
				( pin "C4D2.2"
					( objectStatus "b" )
				)
			)
			( gate "C4E16"
				( objectStatus "@baseboard_fab2_lib.baseboard_fab2(sch_1):page204_i50" )
				( pin "C4E16.1"
					( objectStatus "a" )
				)
				( pin "C4E16.2"
					( objectStatus "b" )
				)
			)
			( gate "C4C2"
				( objectStatus "@baseboard_fab2_lib.baseboard_fab2(sch_1):page204_i51" )
				( pin "C4C2.1"
					( objectStatus "a" )
				)
				( pin "C4C2.2"
					( objectStatus "b" )
				)
			)
			( gate "U4C1"
				( objectStatus "@baseboard_fab2_lib.baseboard_fab2(sch_1):page204_i53" )
				( pin "U4C1.1"
					( objectStatus "gnd(0)" )
				)
				( pin "U4C1.2"
					( objectStatus "gnd(1)" )
				)
				( pin "U4C1.6"
					( objectStatus "\out\" )
				)
				( pin "U4C1.5"
					( objectStatus "rsn" )
				)
				( pin "U4C1.4"
					( objectStatus "rsp" )
				)
				( pin "U4C1.3"
					( objectStatus "vcc" )
				)
			)
			( gate "R4E14"
				( objectStatus "@baseboard_fab2_lib.baseboard_fab2(sch_1):page204_i60" )
				( pin "R4E14.1"
					( objectStatus "a" )
				)
				( pin "R4E14.2"
					( objectStatus "b" )
				)
			)
			( gate "R4E16"
				( objectStatus "@baseboard_fab2_lib.baseboard_fab2(sch_1):page204_i61" )
				( pin "R4E16.1"
					( objectStatus "a" )
				)
				( pin "R4E16.2"
					( objectStatus "b" )
				)
			)
			( gate "R4E17"
				( objectStatus "@baseboard_fab2_lib.baseboard_fab2(sch_1):page204_i62" )
				( pin "R4E17.1"
					( objectStatus "a" )
				)
				( pin "R4E17.2"
					( objectStatus "b" )
				)
			)
			( gate "R4E15"
				( objectStatus "@baseboard_fab2_lib.baseboard_fab2(sch_1):page204_i63" )
				( pin "R4E15.1"
					( objectStatus "a" )
				)
				( pin "R4E15.2"
					( objectStatus "b" )
				)
			)
			( gate "R4E18"
				( objectStatus "@baseboard_fab2_lib.baseboard_fab2(sch_1):page204_i64" )
				( pin "R4E18.1"
					( objectStatus "a" )
				)
				( pin "R4E18.2"
					( objectStatus "b" )
				)
			)
			( gate "C4C12"
				( objectStatus "@baseboard_fab2_lib.baseboard_fab2(sch_1):page204_i67" )
				( pin "C4C12.1"
					( objectStatus "a" )
				)
				( pin "C4C12.2"
					( objectStatus "b" )
				)
			)
			( gate "C6R2"
				( objectStatus "@baseboard_fab2_lib.baseboard_fab2(sch_1):page204_i70" )
				( pin "C6R2.1"
					( objectStatus "a" )
				)
				( pin "C6R2.2"
					( objectStatus "b" )
				)
			)
			( gate "EU4C2"
				( objectStatus "@baseboard_fab2_lib.baseboard_fab2(sch_1):page204_i71" )
				( pin "EU4C2.33"
					( objectStatus "boost" )
				)
				( pin "EU4C2.35"
					( objectStatus "en" )
				)
				( pin "EU4C2.6"
					( objectStatus "gl(0)" )
				)
				( pin "EU4C2.41"
					( objectStatus "gl(1)" )
				)
				( pin "EU4C2.38"
					( objectStatus "iout" )
				)
				( pin "EU4C2.2"
					( objectStatus "lgnd" )
				)
				( pin "EU4C2.31"
					( objectStatus "nc" )
				)
				( pin "EU4C2.37"
					( objectStatus "ocset" )
				)
				( pin "EU4C2.5"
					( objectStatus "pgnd(0)" )
				)
				( pin "EU4C2.7"
					( objectStatus "pgnd(1)" )
				)
				( pin "EU4C2.40"
					( objectStatus "pgnd(2)" )
				)
				( pin "EU4C2.32"
					( objectStatus "phase" )
				)
				( pin "EU4C2.34"
					( objectStatus "pwm" )
				)
				( pin "EU4C2.39"
					( objectStatus "refin" )
				)
				( pin "EU4C2.10"
					( objectStatus "sw" )
				)
				( pin "EU4C2.36"
					( objectStatus "tout_flt" )
				)
				( pin "EU4C2.3"
					( objectStatus "vcc" )
				)
				( pin "EU4C2.4"
					( objectStatus "vdrv" )
				)
				( pin "EU4C2.25"
					( objectStatus "vin(0)" )
				)
				( pin "EU4C2.30"
					( objectStatus "vin(1)" )
				)
				( pin "EU4C2.1"
					( objectStatus "vos" )
				)
			)
			( gate "R34"
				( objectStatus "@baseboard_fab2_lib.baseboard_fab2(sch_1):page204_i83" )
				( pin "R34.1"
					( objectStatus "a" )
				)
				( pin "R34.2"
					( objectStatus "b" )
				)
			)
			( gate "C6N7"
				( objectStatus "@baseboard_fab2_lib.baseboard_fab2(sch_1):page205_i5" )
				( pin "C6N7.1"
					( objectStatus "a" )
				)
				( pin "C6N7.2"
					( objectStatus "b" )
				)
			)
			( gate "L4C2"
				( objectStatus "@baseboard_fab2_lib.baseboard_fab2(sch_1):page205_i7" )
				( pin "L4C2.1"
					( objectStatus "ina" )
				)
				( pin "L4C2.2"
					( objectStatus "inb" )
				)
			)
			( gate "C6N1"
				( objectStatus "@baseboard_fab2_lib.baseboard_fab2(sch_1):page205_i12" )
				( pin "C6N1.1"
					( objectStatus "a" )
				)
				( pin "C6N1.2"
					( objectStatus "b" )
				)
			)
			( gate "C6N4"
				( objectStatus "@baseboard_fab2_lib.baseboard_fab2(sch_1):page205_i14" )
				( pin "C6N4.1"
					( objectStatus "a" )
				)
				( pin "C6N4.2"
					( objectStatus "b" )
				)
			)
			( gate "C4C5"
				( objectStatus "@baseboard_fab2_lib.baseboard_fab2(sch_1):page205_i16" )
				( pin "C4C5.1"
					( objectStatus "a" )
				)
				( pin "C4C5.2"
					( objectStatus "b" )
				)
			)
			( gate "C4C4"
				( objectStatus "@baseboard_fab2_lib.baseboard_fab2(sch_1):page205_i18" )
				( pin "C4C4.1"
					( objectStatus "a" )
				)
				( pin "C4C4.2"
					( objectStatus "b" )
				)
			)
			( gate "R6N3"
				( objectStatus "@baseboard_fab2_lib.baseboard_fab2(sch_1):page205_i19" )
				( pin "R6N3.1"
					( objectStatus "a" )
				)
				( pin "R6N3.2"
					( objectStatus "b" )
				)
			)
			( gate "C4C6"
				( objectStatus "@baseboard_fab2_lib.baseboard_fab2(sch_1):page205_i20" )
				( pin "C4C6.1"
					( objectStatus "a" )
				)
				( pin "C4C6.2"
					( objectStatus "b" )
				)
			)
			( gate "R4C5"
				( objectStatus "@baseboard_fab2_lib.baseboard_fab2(sch_1):page205_i24" )
				( pin "R4C5.1"
					( objectStatus "a" )
				)
				( pin "R4C5.2"
					( objectStatus "b" )
				)
			)
			( gate "C4C8"
				( objectStatus "@baseboard_fab2_lib.baseboard_fab2(sch_1):page205_i25" )
				( pin "C4C8.1"
					( objectStatus "a" )
				)
				( pin "C4C8.2"
					( objectStatus "b" )
				)
			)
			( gate "R4C4"
				( objectStatus "@baseboard_fab2_lib.baseboard_fab2(sch_1):page205_i26" )
				( pin "R4C4.1"
					( objectStatus "a" )
				)
				( pin "R4C4.2"
					( objectStatus "b" )
				)
			)
			( gate "R4C1"
				( objectStatus "@baseboard_fab2_lib.baseboard_fab2(sch_1):page205_i29" )
				( pin "R4C1.1"
					( objectStatus "a" )
				)
				( pin "R4C1.2"
					( objectStatus "b" )
				)
			)
			( gate "R4C2"
				( objectStatus "@baseboard_fab2_lib.baseboard_fab2(sch_1):page205_i30" )
				( pin "R4C2.1"
					( objectStatus "a" )
				)
				( pin "R4C2.2"
					( objectStatus "b" )
				)
			)
			( gate "C4C10"
				( objectStatus "@baseboard_fab2_lib.baseboard_fab2(sch_1):page205_i31" )
				( pin "C4C10.1"
					( objectStatus "a" )
				)
				( pin "C4C10.2"
					( objectStatus "b" )
				)
			)
			( gate "C4C9"
				( objectStatus "@baseboard_fab2_lib.baseboard_fab2(sch_1):page205_i32" )
				( pin "C4C9.1"
					( objectStatus "a" )
				)
				( pin "C4C9.2"
					( objectStatus "b" )
				)
			)
			( gate "C6N2"
				( objectStatus "@baseboard_fab2_lib.baseboard_fab2(sch_1):page205_i33" )
				( pin "C6N2.1"
					( objectStatus "a" )
				)
				( pin "C6N2.2"
					( objectStatus "b" )
				)
			)
			( gate "C6N3"
				( objectStatus "@baseboard_fab2_lib.baseboard_fab2(sch_1):page205_i34" )
				( pin "C6N3.1"
					( objectStatus "a" )
				)
				( pin "C6N3.2"
					( objectStatus "b" )
				)
			)
			( gate "C6N6"
				( objectStatus "@baseboard_fab2_lib.baseboard_fab2(sch_1):page205_i35" )
				( pin "C6N6.1"
					( objectStatus "a" )
				)
				( pin "C6N6.2"
					( objectStatus "b" )
				)
			)
			( gate "R4C3"
				( objectStatus "@baseboard_fab2_lib.baseboard_fab2(sch_1):page205_i37" )
				( pin "R4C3.1"
					( objectStatus "a" )
				)
				( pin "R4C3.2"
					( objectStatus "b" )
				)
			)
			( gate "C4C11"
				( objectStatus "@baseboard_fab2_lib.baseboard_fab2(sch_1):page205_i43" )
				( pin "C4C11.1"
					( objectStatus "a" )
				)
				( pin "C4C11.2"
					( objectStatus "b" )
				)
			)
			( gate "R6N4"
				( objectStatus "@baseboard_fab2_lib.baseboard_fab2(sch_1):page205_i45" )
				( pin "R6N4.1"
					( objectStatus "a" )
				)
				( pin "R6N4.2"
					( objectStatus "b" )
				)
			)
			( gate "EU4C1"
				( objectStatus "@baseboard_fab2_lib.baseboard_fab2(sch_1):page205_i46" )
				( pin "EU4C1.33"
					( objectStatus "boost" )
				)
				( pin "EU4C1.35"
					( objectStatus "en" )
				)
				( pin "EU4C1.6"
					( objectStatus "gl(0)" )
				)
				( pin "EU4C1.41"
					( objectStatus "gl(1)" )
				)
				( pin "EU4C1.38"
					( objectStatus "iout" )
				)
				( pin "EU4C1.2"
					( objectStatus "lgnd" )
				)
				( pin "EU4C1.31"
					( objectStatus "nc" )
				)
				( pin "EU4C1.37"
					( objectStatus "ocset" )
				)
				( pin "EU4C1.5"
					( objectStatus "pgnd(0)" )
				)
				( pin "EU4C1.7"
					( objectStatus "pgnd(1)" )
				)
				( pin "EU4C1.40"
					( objectStatus "pgnd(2)" )
				)
				( pin "EU4C1.32"
					( objectStatus "phase" )
				)
				( pin "EU4C1.34"
					( objectStatus "pwm" )
				)
				( pin "EU4C1.39"
					( objectStatus "refin" )
				)
				( pin "EU4C1.10"
					( objectStatus "sw" )
				)
				( pin "EU4C1.36"
					( objectStatus "tout_flt" )
				)
				( pin "EU4C1.3"
					( objectStatus "vcc" )
				)
				( pin "EU4C1.4"
					( objectStatus "vdrv" )
				)
				( pin "EU4C1.25"
					( objectStatus "vin(0)" )
				)
				( pin "EU4C1.30"
					( objectStatus "vin(1)" )
				)
				( pin "EU4C1.1"
					( objectStatus "vos" )
				)
			)
			( gate "R29"
				( objectStatus "@baseboard_fab2_lib.baseboard_fab2(sch_1):page205_i62" )
				( pin "R29.1"
					( objectStatus "a" )
				)
				( pin "R29.2"
					( objectStatus "b" )
				)
			)
			( gate "R9P1"
				( objectStatus "@baseboard_fab2_lib.baseboard_fab2(sch_1):page206_i4" )
				( pin "R9P1.1"
					( objectStatus "a" )
				)
				( pin "R9P1.2"
					( objectStatus "b" )
				)
			)
			( gate "R1D6"
				( objectStatus "@baseboard_fab2_lib.baseboard_fab2(sch_1):page206_i6" )
				( pin "R1D6.1"
					( objectStatus "a" )
				)
				( pin "R1D6.2"
					( objectStatus "b" )
				)
			)
			( gate "R1D7"
				( objectStatus "@baseboard_fab2_lib.baseboard_fab2(sch_1):page206_i7" )
				( pin "R1D7.1"
					( objectStatus "a" )
				)
				( pin "R1D7.2"
					( objectStatus "b" )
				)
			)
			( gate "R1C23"
				( objectStatus "@baseboard_fab2_lib.baseboard_fab2(sch_1):page206_i27" )
				( pin "R1C23.1"
					( objectStatus "a" )
				)
				( pin "R1C23.2"
					( objectStatus "b" )
				)
			)
			( gate "R1C25"
				( objectStatus "@baseboard_fab2_lib.baseboard_fab2(sch_1):page206_i28" )
				( pin "R1C25.1"
					( objectStatus "a" )
				)
				( pin "R1C25.2"
					( objectStatus "b" )
				)
			)
			( gate "C1C13"
				( objectStatus "@baseboard_fab2_lib.baseboard_fab2(sch_1):page206_i29" )
				( pin "C1C13.1"
					( objectStatus "a" )
				)
				( pin "C1C13.2"
					( objectStatus "b" )
				)
			)
			( gate "C1C14"
				( objectStatus "@baseboard_fab2_lib.baseboard_fab2(sch_1):page206_i31" )
				( pin "C1C14.1"
					( objectStatus "a" )
				)
				( pin "C1C14.2"
					( objectStatus "b" )
				)
			)
			( gate "R1C17"
				( objectStatus "@baseboard_fab2_lib.baseboard_fab2(sch_1):page206_i33" )
				( pin "R1C17.1"
					( objectStatus "a" )
				)
				( pin "R1C17.2"
					( objectStatus "b" )
				)
			)
			( gate "R1C18"
				( objectStatus "@baseboard_fab2_lib.baseboard_fab2(sch_1):page206_i34" )
				( pin "R1C18.1"
					( objectStatus "a" )
				)
				( pin "R1C18.2"
					( objectStatus "b" )
				)
			)
			( gate "R1C28"
				( objectStatus "@baseboard_fab2_lib.baseboard_fab2(sch_1):page206_i35" )
				( pin "R1C28.1"
					( objectStatus "a" )
				)
				( pin "R1C28.2"
					( objectStatus "b" )
				)
			)
			( gate "R1D8"
				( objectStatus "@baseboard_fab2_lib.baseboard_fab2(sch_1):page206_i36" )
				( pin "R1D8.1"
					( objectStatus "a" )
				)
				( pin "R1D8.2"
					( objectStatus "b" )
				)
			)
			( gate "R1D3"
				( objectStatus "@baseboard_fab2_lib.baseboard_fab2(sch_1):page206_i37" )
				( pin "R1D3.1"
					( objectStatus "a" )
				)
				( pin "R1D3.2"
					( objectStatus "b" )
				)
			)
			( gate "R1D2"
				( objectStatus "@baseboard_fab2_lib.baseboard_fab2(sch_1):page206_i38" )
				( pin "R1D2.1"
					( objectStatus "a" )
				)
				( pin "R1D2.2"
					( objectStatus "b" )
				)
			)
			( gate "C1C7"
				( objectStatus "@baseboard_fab2_lib.baseboard_fab2(sch_1):page206_i41" )
				( pin "C1C7.1"
					( objectStatus "a" )
				)
				( pin "C1C7.2"
					( objectStatus "b" )
				)
			)
			( gate "C1C9"
				( objectStatus "@baseboard_fab2_lib.baseboard_fab2(sch_1):page206_i42" )
				( pin "C1C9.1"
					( objectStatus "a" )
				)
				( pin "C1C9.2"
					( objectStatus "b" )
				)
			)
			( gate "R1C14"
				( objectStatus "@baseboard_fab2_lib.baseboard_fab2(sch_1):page206_i46" )
				( pin "R1C14.1"
					( objectStatus "a" )
				)
				( pin "R1C14.2"
					( objectStatus "b" )
				)
			)
			( gate "R1C13"
				( objectStatus "@baseboard_fab2_lib.baseboard_fab2(sch_1):page206_i49" )
				( pin "R1C13.1"
					( objectStatus "a" )
				)
				( pin "R1C13.2"
					( objectStatus "b" )
				)
			)
			( gate "R9P2"
				( objectStatus "@baseboard_fab2_lib.baseboard_fab2(sch_1):page206_i53" )
				( pin "R9P2.1"
					( objectStatus "a" )
				)
				( pin "R9P2.2"
					( objectStatus "b" )
				)
			)
			( gate "R1D9"
				( objectStatus "@baseboard_fab2_lib.baseboard_fab2(sch_1):page206_i54" )
				( pin "R1D9.1"
					( objectStatus "a" )
				)
				( pin "R1D9.2"
					( objectStatus "b" )
				)
			)
			( gate "R1C16"
				( objectStatus "@baseboard_fab2_lib.baseboard_fab2(sch_1):page206_i56" )
				( pin "R1C16.1"
					( objectStatus "a" )
				)
				( pin "R1C16.2"
					( objectStatus "b" )
				)
			)
			( gate "C1C16"
				( objectStatus "@baseboard_fab2_lib.baseboard_fab2(sch_1):page206_i68" )
				( pin "C1C16.1"
					( objectStatus "a" )
				)
				( pin "C1C16.2"
					( objectStatus "b" )
				)
			)
			( gate "C1C10"
				( objectStatus "@baseboard_fab2_lib.baseboard_fab2(sch_1):page206_i69" )
				( pin "C1C10.1"
					( objectStatus "a" )
				)
				( pin "C1C10.2"
					( objectStatus "b" )
				)
			)
			( gate "C1C11"
				( objectStatus "@baseboard_fab2_lib.baseboard_fab2(sch_1):page206_i71" )
				( pin "C1C11.1"
					( objectStatus "a" )
				)
				( pin "C1C11.2"
					( objectStatus "b" )
				)
			)
			( gate "C1C8"
				( objectStatus "@baseboard_fab2_lib.baseboard_fab2(sch_1):page206_i73" )
				( pin "C1C8.1"
					( objectStatus "a" )
				)
				( pin "C1C8.2"
					( objectStatus "b" )
				)
			)
			( gate "R1C21"
				( objectStatus "@baseboard_fab2_lib.baseboard_fab2(sch_1):page206_i77" )
				( pin "R1C21.1"
					( objectStatus "a" )
				)
				( pin "R1C21.2"
					( objectStatus "b" )
				)
			)
			( gate "C1D1"
				( objectStatus "@baseboard_fab2_lib.baseboard_fab2(sch_1):page206_i78" )
				( pin "C1D1.1"
					( objectStatus "a" )
				)
				( pin "C1D1.2"
					( objectStatus "b" )
				)
			)
			( gate "R1D4"
				( objectStatus "@baseboard_fab2_lib.baseboard_fab2(sch_1):page206_i79" )
				( pin "R1D4.1"
					( objectStatus "a" )
				)
				( pin "R1D4.2"
					( objectStatus "b" )
				)
			)
			( gate "R9N7"
				( objectStatus "@baseboard_fab2_lib.baseboard_fab2(sch_1):page206_i111" )
				( pin "R9N7.1"
					( objectStatus "a" )
				)
				( pin "R9N7.2"
					( objectStatus "b" )
				)
			)
			( gate "R9N8"
				( objectStatus "@baseboard_fab2_lib.baseboard_fab2(sch_1):page206_i112" )
				( pin "R9N8.1"
					( objectStatus "a" )
				)
				( pin "R9N8.2"
					( objectStatus "b" )
				)
			)
			( gate "R1C30"
				( objectStatus "@baseboard_fab2_lib.baseboard_fab2(sch_1):page206_i113" )
				( pin "R1C30.1"
					( objectStatus "a" )
				)
				( pin "R1C30.2"
					( objectStatus "b" )
				)
			)
			( gate "C1C23"
				( objectStatus "@baseboard_fab2_lib.baseboard_fab2(sch_1):page206_i114" )
				( pin "C1C23.1"
					( objectStatus "a" )
				)
				( pin "C1C23.2"
					( objectStatus "b" )
				)
			)
			( gate "R1D1"
				( objectStatus "@baseboard_fab2_lib.baseboard_fab2(sch_1):page206_i116" )
				( pin "R1D1.1"
					( objectStatus "a" )
				)
				( pin "R1D1.2"
					( objectStatus "b" )
				)
			)
			( gate "R9P3"
				( objectStatus "@baseboard_fab2_lib.baseboard_fab2(sch_1):page206_i117" )
				( pin "R9P3.1"
					( objectStatus "a" )
				)
				( pin "R9P3.2"
					( objectStatus "b" )
				)
			)
			( gate "R9N16"
				( objectStatus "@baseboard_fab2_lib.baseboard_fab2(sch_1):page206_i119" )
				( pin "R9N16.1"
					( objectStatus "a" )
				)
				( pin "R9N16.2"
					( objectStatus "b" )
				)
			)
			( gate "R9N14"
				( objectStatus "@baseboard_fab2_lib.baseboard_fab2(sch_1):page206_i120" )
				( pin "R9N14.1"
					( objectStatus "a" )
				)
				( pin "R9N14.2"
					( objectStatus "b" )
				)
			)
			( gate "R9N15"
				( objectStatus "@baseboard_fab2_lib.baseboard_fab2(sch_1):page206_i122" )
				( pin "R9N15.1"
					( objectStatus "a" )
				)
				( pin "R9N15.2"
					( objectStatus "b" )
				)
			)
			( gate "R9N17"
				( objectStatus "@baseboard_fab2_lib.baseboard_fab2(sch_1):page206_i123" )
				( pin "R9N17.1"
					( objectStatus "a" )
				)
				( pin "R9N17.2"
					( objectStatus "b" )
				)
			)
			( gate "R9N12"
				( objectStatus "@baseboard_fab2_lib.baseboard_fab2(sch_1):page206_i124" )
				( pin "R9N12.1"
					( objectStatus "a" )
				)
				( pin "R9N12.2"
					( objectStatus "b" )
				)
			)
			( gate "R9N10"
				( objectStatus "@baseboard_fab2_lib.baseboard_fab2(sch_1):page206_i125" )
				( pin "R9N10.1"
					( objectStatus "a" )
				)
				( pin "R9N10.2"
					( objectStatus "b" )
				)
			)
			( gate "R9N9"
				( objectStatus "@baseboard_fab2_lib.baseboard_fab2(sch_1):page206_i126" )
				( pin "R9N9.1"
					( objectStatus "a" )
				)
				( pin "R9N9.2"
					( objectStatus "b" )
				)
			)
			( gate "R9N5"
				( objectStatus "@baseboard_fab2_lib.baseboard_fab2(sch_1):page206_i128" )
				( pin "R9N5.1"
					( objectStatus "a" )
				)
				( pin "R9N5.2"
					( objectStatus "b" )
				)
			)
			( gate "EU1C2"
				( objectStatus "@baseboard_fab2_lib.baseboard_fab2(sch_1):page206_i130" )
				( pin "EU1C2.23"
					( objectStatus "airef1" )
				)
				( pin "EU1C2.25"
					( objectStatus "airef2" )
				)
				( pin "EU1C2.27"
					( objectStatus "airef3" )
				)
				( pin "EU1C2.29"
					( objectStatus "airef4" )
				)
				( pin "EU1C2.31"
					( objectStatus "airef5" )
				)
				( pin "EU1C2.33"
					( objectStatus "airef6" )
				)
				( pin "EU1C2.24"
					( objectStatus "aisen1" )
				)
				( pin "EU1C2.26"
					( objectStatus "aisen2" )
				)
				( pin "EU1C2.28"
					( objectStatus "aisen3" )
				)
				( pin "EU1C2.30"
					( objectStatus "aisen4" )
				)
				( pin "EU1C2.32"
					( objectStatus "aisen5" )
				)
				( pin "EU1C2.34"
					( objectStatus "aisen6" )
				)
				( pin "EU1C2.7"
					( objectStatus "apwm1" )
				)
				( pin "EU1C2.6"
					( objectStatus "apwm2" )
				)
				( pin "EU1C2.5"
					( objectStatus "apwm3" )
				)
				( pin "EU1C2.4"
					( objectStatus "apwm4" )
				)
				( pin "EU1C2.3"
					( objectStatus "apwm5" )
				)
				( pin "EU1C2.2"
					( objectStatus "apwm6" )
				)
				( pin "EU1C2.43"
					( objectStatus "atsen" )
				)
				( pin "EU1C2.22"
					( objectStatus "avref" )
				)
				( pin "EU1C2.12"
					( objectStatus "avren" )
				)
				( pin "EU1C2.11"
					( objectStatus "avrrdy" )
				)
				( pin "EU1C2.21"
					( objectStatus "avsen" )
				)
				( pin "EU1C2.37"
					( objectStatus "biref1" )
				)
				( pin "EU1C2.38"
					( objectStatus "bisen1" )
				)
				( pin "EU1C2.1"
					( objectStatus "bpwm1" )
				)
				( pin "EU1C2.42"
					( objectStatus "btsen" )
				)
				( pin "EU1C2.36"
					( objectStatus "bvref" )
				)
				( pin "EU1C2.35"
					( objectStatus "bvsen" )
				)
				( pin "EU1C2.46"
					( objectStatus "iinsen" )
				)
				( pin "EU1C2.15"
					( objectStatus "mp0" )
				)
				( pin "EU1C2.16"
					( objectStatus "mp1" )
				)
				( pin "EU1C2.20"
					( objectStatus "mp2" )
				)
				( pin "EU1C2.39"
					( objectStatus "mp3" )
				)
				( pin "EU1C2.40"
					( objectStatus "mp4" )
				)
				( pin "EU1C2.14"
					( objectStatus "pinalrt_n" )
				)
				( pin "EU1C2.10"
					( objectStatus "reset_n" )
				)
				( pin "EU1C2.9"
					( objectStatus "scl" )
				)
				( pin "EU1C2.8"
					( objectStatus "sda" )
				)
				( pin "EU1C2.49"
					( objectStatus "thpad" )
				)
				( pin "EU1C2.19"
					( objectStatus "valrt_n" )
				)
				( pin "EU1C2.17"
					( objectStatus "vclk" )
				)
				( pin "EU1C2.48"
					( objectStatus "vd12" )
				)
				( pin "EU1C2.47"
					( objectStatus "vdd" )
				)
				( pin "EU1C2.18"
					( objectStatus "vdio" )
				)
				( pin "EU1C2.45"
					( objectStatus "vinsen" )
				)
				( pin "EU1C2.13"
					( objectStatus "vrhot_n" )
				)
				( pin "EU1C2.44"
					( objectStatus "xaddr1" )
				)
				( pin "EU1C2.41"
					( objectStatus "xaddr2" )
				)
			)
			( gate "C9R8"
				( objectStatus "@baseboard_fab2_lib.baseboard_fab2(sch_1):page207_i8" )
				( pin "C9R8.1"
					( objectStatus "a" )
				)
				( pin "C9R8.2"
					( objectStatus "b" )
				)
			)
			( gate "L1E1"
				( objectStatus "@baseboard_fab2_lib.baseboard_fab2(sch_1):page207_i10" )
				( pin "L1E1.1"
					( objectStatus "ina" )
				)
				( pin "L1E1.2"
					( objectStatus "inb" )
				)
			)
			( gate "L1D3"
				( objectStatus "@baseboard_fab2_lib.baseboard_fab2(sch_1):page207_i16" )
				( pin "L1D3.1"
					( objectStatus "ina" )
				)
				( pin "L1D3.2"
					( objectStatus "inb" )
				)
			)
			( gate "C1E3"
				( objectStatus "@baseboard_fab2_lib.baseboard_fab2(sch_1):page207_i18" )
				( pin "C1E3.1"
					( objectStatus "a" )
				)
				( pin "C1E3.2"
					( objectStatus "b" )
				)
			)
			( gate "EU1E2"
				( objectStatus "@baseboard_fab2_lib.baseboard_fab2(sch_1):page207_i20" )
				( pin "EU1E2.33"
					( objectStatus "boost" )
				)
				( pin "EU1E2.35"
					( objectStatus "en" )
				)
				( pin "EU1E2.6"
					( objectStatus "gl(0)" )
				)
				( pin "EU1E2.41"
					( objectStatus "gl(1)" )
				)
				( pin "EU1E2.38"
					( objectStatus "iout" )
				)
				( pin "EU1E2.2"
					( objectStatus "lgnd" )
				)
				( pin "EU1E2.31"
					( objectStatus "nc" )
				)
				( pin "EU1E2.37"
					( objectStatus "ocset" )
				)
				( pin "EU1E2.5"
					( objectStatus "pgnd(0)" )
				)
				( pin "EU1E2.7"
					( objectStatus "pgnd(1)" )
				)
				( pin "EU1E2.40"
					( objectStatus "pgnd(2)" )
				)
				( pin "EU1E2.32"
					( objectStatus "phase" )
				)
				( pin "EU1E2.34"
					( objectStatus "pwm" )
				)
				( pin "EU1E2.39"
					( objectStatus "refin" )
				)
				( pin "EU1E2.10"
					( objectStatus "sw" )
				)
				( pin "EU1E2.36"
					( objectStatus "tout_flt" )
				)
				( pin "EU1E2.3"
					( objectStatus "vcc" )
				)
				( pin "EU1E2.4"
					( objectStatus "vdrv" )
				)
				( pin "EU1E2.25"
					( objectStatus "vin(0)" )
				)
				( pin "EU1E2.30"
					( objectStatus "vin(1)" )
				)
				( pin "EU1E2.1"
					( objectStatus "vos" )
				)
			)
			( gate "EU1D4"
				( objectStatus "@baseboard_fab2_lib.baseboard_fab2(sch_1):page207_i24" )
				( pin "EU1D4.33"
					( objectStatus "boost" )
				)
				( pin "EU1D4.35"
					( objectStatus "en" )
				)
				( pin "EU1D4.6"
					( objectStatus "gl(0)" )
				)
				( pin "EU1D4.41"
					( objectStatus "gl(1)" )
				)
				( pin "EU1D4.38"
					( objectStatus "iout" )
				)
				( pin "EU1D4.2"
					( objectStatus "lgnd" )
				)
				( pin "EU1D4.31"
					( objectStatus "nc" )
				)
				( pin "EU1D4.37"
					( objectStatus "ocset" )
				)
				( pin "EU1D4.5"
					( objectStatus "pgnd(0)" )
				)
				( pin "EU1D4.7"
					( objectStatus "pgnd(1)" )
				)
				( pin "EU1D4.40"
					( objectStatus "pgnd(2)" )
				)
				( pin "EU1D4.32"
					( objectStatus "phase" )
				)
				( pin "EU1D4.34"
					( objectStatus "pwm" )
				)
				( pin "EU1D4.39"
					( objectStatus "refin" )
				)
				( pin "EU1D4.10"
					( objectStatus "sw" )
				)
				( pin "EU1D4.36"
					( objectStatus "tout_flt" )
				)
				( pin "EU1D4.3"
					( objectStatus "vcc" )
				)
				( pin "EU1D4.4"
					( objectStatus "vdrv" )
				)
				( pin "EU1D4.25"
					( objectStatus "vin(0)" )
				)
				( pin "EU1D4.30"
					( objectStatus "vin(1)" )
				)
				( pin "EU1D4.1"
					( objectStatus "vos" )
				)
			)
			( gate "R9R2"
				( objectStatus "@baseboard_fab2_lib.baseboard_fab2(sch_1):page207_i26" )
				( pin "R9R2.1"
					( objectStatus "a" )
				)
				( pin "R9R2.2"
					( objectStatus "b" )
				)
			)
			( gate "C1E7"
				( objectStatus "@baseboard_fab2_lib.baseboard_fab2(sch_1):page207_i28" )
				( pin "C1E7.1"
					( objectStatus "a" )
				)
				( pin "C1E7.2"
					( objectStatus "b" )
				)
			)
			( gate "C1E6"
				( objectStatus "@baseboard_fab2_lib.baseboard_fab2(sch_1):page207_i29" )
				( pin "C1E6.1"
					( objectStatus "a" )
				)
				( pin "C1E6.2"
					( objectStatus "b" )
				)
			)
			( gate "C1E11"
				( objectStatus "@baseboard_fab2_lib.baseboard_fab2(sch_1):page207_i30" )
				( pin "C1E11.1"
					( objectStatus "a" )
				)
				( pin "C1E11.2"
					( objectStatus "b" )
				)
			)
			( gate "C1E8"
				( objectStatus "@baseboard_fab2_lib.baseboard_fab2(sch_1):page207_i32" )
				( pin "C1E8.1"
					( objectStatus "a" )
				)
				( pin "C1E8.2"
					( objectStatus "b" )
				)
			)
			( gate "C1E14"
				( objectStatus "@baseboard_fab2_lib.baseboard_fab2(sch_1):page207_i33" )
				( pin "C1E14.1"
					( objectStatus "a" )
				)
				( pin "C1E14.2"
					( objectStatus "b" )
				)
			)
			( gate "C1E13"
				( objectStatus "@baseboard_fab2_lib.baseboard_fab2(sch_1):page207_i34" )
				( pin "C1E13.1"
					( objectStatus "a" )
				)
				( pin "C1E13.2"
					( objectStatus "b" )
				)
			)
			( gate "C1D30"
				( objectStatus "@baseboard_fab2_lib.baseboard_fab2(sch_1):page207_i36" )
				( pin "C1D30.1"
					( objectStatus "a" )
				)
				( pin "C1D30.2"
					( objectStatus "b" )
				)
			)
			( gate "C1D29"
				( objectStatus "@baseboard_fab2_lib.baseboard_fab2(sch_1):page207_i37" )
				( pin "C1D29.1"
					( objectStatus "a" )
				)
				( pin "C1D29.2"
					( objectStatus "b" )
				)
			)
			( gate "C1E1"
				( objectStatus "@baseboard_fab2_lib.baseboard_fab2(sch_1):page207_i38" )
				( pin "C1E1.1"
					( objectStatus "a" )
				)
				( pin "C1E1.2"
					( objectStatus "b" )
				)
			)
			( gate "R9P31"
				( objectStatus "@baseboard_fab2_lib.baseboard_fab2(sch_1):page207_i39" )
				( pin "R9P31.1"
					( objectStatus "a" )
				)
				( pin "R9P31.2"
					( objectStatus "b" )
				)
			)
			( gate "C1D31"
				( objectStatus "@baseboard_fab2_lib.baseboard_fab2(sch_1):page207_i40" )
				( pin "C1D31.1"
					( objectStatus "a" )
				)
				( pin "C1D31.2"
					( objectStatus "b" )
				)
			)
			( gate "C1E5"
				( objectStatus "@baseboard_fab2_lib.baseboard_fab2(sch_1):page207_i41" )
				( pin "C1E5.1"
					( objectStatus "a" )
				)
				( pin "C1E5.2"
					( objectStatus "b" )
				)
			)
			( gate "C1E4"
				( objectStatus "@baseboard_fab2_lib.baseboard_fab2(sch_1):page207_i42" )
				( pin "C1E4.1"
					( objectStatus "a" )
				)
				( pin "C1E4.2"
					( objectStatus "b" )
				)
			)
			( gate "C9R7"
				( objectStatus "@baseboard_fab2_lib.baseboard_fab2(sch_1):page207_i43" )
				( pin "C9R7.1"
					( objectStatus "a" )
				)
				( pin "C9R7.2"
					( objectStatus "b" )
				)
			)
			( gate "C9R10"
				( objectStatus "@baseboard_fab2_lib.baseboard_fab2(sch_1):page207_i44" )
				( pin "C9R10.1"
					( objectStatus "a" )
				)
				( pin "C9R10.2"
					( objectStatus "b" )
				)
			)
			( gate "C9R11"
				( objectStatus "@baseboard_fab2_lib.baseboard_fab2(sch_1):page207_i48" )
				( pin "C9R11.1"
					( objectStatus "a" )
				)
				( pin "C9R11.2"
					( objectStatus "b" )
				)
			)
			( gate "C9P22"
				( objectStatus "@baseboard_fab2_lib.baseboard_fab2(sch_1):page207_i50" )
				( pin "C9P22.1"
					( objectStatus "a" )
				)
				( pin "C9P22.2"
					( objectStatus "b" )
				)
			)
			( gate "C9R1"
				( objectStatus "@baseboard_fab2_lib.baseboard_fab2(sch_1):page207_i51" )
				( pin "C9R1.1"
					( objectStatus "a" )
				)
				( pin "C9R1.2"
					( objectStatus "b" )
				)
			)
			( gate "C9R4"
				( objectStatus "@baseboard_fab2_lib.baseboard_fab2(sch_1):page207_i54" )
				( pin "C9R4.1"
					( objectStatus "a" )
				)
				( pin "C9R4.2"
					( objectStatus "b" )
				)
			)
			( gate "C1E9"
				( objectStatus "@baseboard_fab2_lib.baseboard_fab2(sch_1):page207_i58" )
				( pin "C1E9.1"
					( objectStatus "a" )
				)
				( pin "C1E9.2"
					( objectStatus "b" )
				)
			)
			( gate "C9P3"
				( objectStatus "@baseboard_fab2_lib.baseboard_fab2(sch_1):page207_i59" )
				( pin "C9P3.1"
					( objectStatus "a" )
				)
				( pin "C9P3.2"
					( objectStatus "b" )
				)
			)
			( gate "R23"
				( objectStatus "@baseboard_fab2_lib.baseboard_fab2(sch_1):page207_i67" )
				( pin "R23.1"
					( objectStatus "a" )
				)
				( pin "R23.2"
					( objectStatus "b" )
				)
			)
			( gate "R24"
				( objectStatus "@baseboard_fab2_lib.baseboard_fab2(sch_1):page207_i68" )
				( pin "R24.1"
					( objectStatus "a" )
				)
				( pin "R24.2"
					( objectStatus "b" )
				)
			)
			( gate "R1E3"
				( objectStatus "@baseboard_fab2_lib.baseboard_fab2(sch_1):page208_i7" )
				( pin "R1E3.1"
					( objectStatus "a" )
				)
				( pin "R1E3.2"
					( objectStatus "b" )
				)
			)
			( gate "C1D14"
				( objectStatus "@baseboard_fab2_lib.baseboard_fab2(sch_1):page208_i9" )
				( pin "C1D14.1"
					( objectStatus "a" )
				)
				( pin "C1D14.2"
					( objectStatus "b" )
				)
			)
			( gate "L1D2"
				( objectStatus "@baseboard_fab2_lib.baseboard_fab2(sch_1):page208_i11" )
				( pin "L1D2.1"
					( objectStatus "ina" )
				)
				( pin "L1D2.2"
					( objectStatus "inb" )
				)
			)
			( gate "C9P8"
				( objectStatus "@baseboard_fab2_lib.baseboard_fab2(sch_1):page208_i12" )
				( pin "C9P8.1"
					( objectStatus "a" )
				)
				( pin "C9P8.2"
					( objectStatus "b" )
				)
			)
			( gate "C9P5"
				( objectStatus "@baseboard_fab2_lib.baseboard_fab2(sch_1):page208_i14" )
				( pin "C9P5.1"
					( objectStatus "a" )
				)
				( pin "C9P5.2"
					( objectStatus "b" )
				)
			)
			( gate "L1D1"
				( objectStatus "@baseboard_fab2_lib.baseboard_fab2(sch_1):page208_i20" )
				( pin "L1D1.1"
					( objectStatus "ina" )
				)
				( pin "L1D1.2"
					( objectStatus "inb" )
				)
			)
			( gate "C1D3"
				( objectStatus "@baseboard_fab2_lib.baseboard_fab2(sch_1):page208_i22" )
				( pin "C1D3.1"
					( objectStatus "a" )
				)
				( pin "C1D3.2"
					( objectStatus "b" )
				)
			)
			( gate "C9N24"
				( objectStatus "@baseboard_fab2_lib.baseboard_fab2(sch_1):page208_i24" )
				( pin "C9N24.1"
					( objectStatus "a" )
				)
				( pin "C9N24.2"
					( objectStatus "b" )
				)
			)
			( gate "C9R9"
				( objectStatus "@baseboard_fab2_lib.baseboard_fab2(sch_1):page208_i25" )
				( pin "C9R9.1"
					( objectStatus "a" )
				)
				( pin "C9R9.2"
					( objectStatus "b" )
				)
			)
			( gate "C9R3"
				( objectStatus "@baseboard_fab2_lib.baseboard_fab2(sch_1):page208_i26" )
				( pin "C9R3.1"
					( objectStatus "a" )
				)
				( pin "C9R3.2"
					( objectStatus "b" )
				)
			)
			( gate "EU1D3"
				( objectStatus "@baseboard_fab2_lib.baseboard_fab2(sch_1):page208_i27" )
				( pin "EU1D3.33"
					( objectStatus "boost" )
				)
				( pin "EU1D3.35"
					( objectStatus "en" )
				)
				( pin "EU1D3.6"
					( objectStatus "gl(0)" )
				)
				( pin "EU1D3.41"
					( objectStatus "gl(1)" )
				)
				( pin "EU1D3.38"
					( objectStatus "iout" )
				)
				( pin "EU1D3.2"
					( objectStatus "lgnd" )
				)
				( pin "EU1D3.31"
					( objectStatus "nc" )
				)
				( pin "EU1D3.37"
					( objectStatus "ocset" )
				)
				( pin "EU1D3.5"
					( objectStatus "pgnd(0)" )
				)
				( pin "EU1D3.7"
					( objectStatus "pgnd(1)" )
				)
				( pin "EU1D3.40"
					( objectStatus "pgnd(2)" )
				)
				( pin "EU1D3.32"
					( objectStatus "phase" )
				)
				( pin "EU1D3.34"
					( objectStatus "pwm" )
				)
				( pin "EU1D3.39"
					( objectStatus "refin" )
				)
				( pin "EU1D3.10"
					( objectStatus "sw" )
				)
				( pin "EU1D3.36"
					( objectStatus "tout_flt" )
				)
				( pin "EU1D3.3"
					( objectStatus "vcc" )
				)
				( pin "EU1D3.4"
					( objectStatus "vdrv" )
				)
				( pin "EU1D3.25"
					( objectStatus "vin(0)" )
				)
				( pin "EU1D3.30"
					( objectStatus "vin(1)" )
				)
				( pin "EU1D3.1"
					( objectStatus "vos" )
				)
			)
			( gate "C9P23"
				( objectStatus "@baseboard_fab2_lib.baseboard_fab2(sch_1):page208_i28" )
				( pin "C9P23.1"
					( objectStatus "a" )
				)
				( pin "C9P23.2"
					( objectStatus "b" )
				)
			)
			( gate "C9P18"
				( objectStatus "@baseboard_fab2_lib.baseboard_fab2(sch_1):page208_i30" )
				( pin "C9P18.1"
					( objectStatus "a" )
				)
				( pin "C9P18.2"
					( objectStatus "b" )
				)
			)
			( gate "R9P22"
				( objectStatus "@baseboard_fab2_lib.baseboard_fab2(sch_1):page208_i36" )
				( pin "R9P22.1"
					( objectStatus "a" )
				)
				( pin "R9P22.2"
					( objectStatus "b" )
				)
			)
			( gate "C1D16"
				( objectStatus "@baseboard_fab2_lib.baseboard_fab2(sch_1):page208_i38" )
				( pin "C1D16.1"
					( objectStatus "a" )
				)
				( pin "C1D16.2"
					( objectStatus "b" )
				)
			)
			( gate "C1D15"
				( objectStatus "@baseboard_fab2_lib.baseboard_fab2(sch_1):page208_i39" )
				( pin "C1D15.1"
					( objectStatus "a" )
				)
				( pin "C1D15.2"
					( objectStatus "b" )
				)
			)
			( gate "C1D20"
				( objectStatus "@baseboard_fab2_lib.baseboard_fab2(sch_1):page208_i40" )
				( pin "C1D20.1"
					( objectStatus "a" )
				)
				( pin "C1D20.2"
					( objectStatus "b" )
				)
			)
			( gate "C1D17"
				( objectStatus "@baseboard_fab2_lib.baseboard_fab2(sch_1):page208_i43" )
				( pin "C1D17.1"
					( objectStatus "a" )
				)
				( pin "C1D17.2"
					( objectStatus "b" )
				)
			)
			( gate "C1D28"
				( objectStatus "@baseboard_fab2_lib.baseboard_fab2(sch_1):page208_i44" )
				( pin "C1D28.1"
					( objectStatus "a" )
				)
				( pin "C1D28.2"
					( objectStatus "b" )
				)
			)
			( gate "C1D23"
				( objectStatus "@baseboard_fab2_lib.baseboard_fab2(sch_1):page208_i45" )
				( pin "C1D23.1"
					( objectStatus "a" )
				)
				( pin "C1D23.2"
					( objectStatus "b" )
				)
			)
			( gate "C1D6"
				( objectStatus "@baseboard_fab2_lib.baseboard_fab2(sch_1):page208_i46" )
				( pin "C1D6.1"
					( objectStatus "a" )
				)
				( pin "C1D6.2"
					( objectStatus "b" )
				)
			)
			( gate "C1D5"
				( objectStatus "@baseboard_fab2_lib.baseboard_fab2(sch_1):page208_i47" )
				( pin "C1D5.1"
					( objectStatus "a" )
				)
				( pin "C1D5.2"
					( objectStatus "b" )
				)
			)
			( gate "C1D10"
				( objectStatus "@baseboard_fab2_lib.baseboard_fab2(sch_1):page208_i48" )
				( pin "C1D10.1"
					( objectStatus "a" )
				)
				( pin "C1D10.2"
					( objectStatus "b" )
				)
			)
			( gate "R9P8"
				( objectStatus "@baseboard_fab2_lib.baseboard_fab2(sch_1):page208_i49" )
				( pin "R9P8.1"
					( objectStatus "a" )
				)
				( pin "R9P8.2"
					( objectStatus "b" )
				)
			)
			( gate "C1D7"
				( objectStatus "@baseboard_fab2_lib.baseboard_fab2(sch_1):page208_i50" )
				( pin "C1D7.1"
					( objectStatus "a" )
				)
				( pin "C1D7.2"
					( objectStatus "b" )
				)
			)
			( gate "C1D13"
				( objectStatus "@baseboard_fab2_lib.baseboard_fab2(sch_1):page208_i51" )
				( pin "C1D13.1"
					( objectStatus "a" )
				)
				( pin "C1D13.2"
					( objectStatus "b" )
				)
			)
			( gate "C1D12"
				( objectStatus "@baseboard_fab2_lib.baseboard_fab2(sch_1):page208_i52" )
				( pin "C1D12.1"
					( objectStatus "a" )
				)
				( pin "C1D12.2"
					( objectStatus "b" )
				)
			)
			( gate "C9P4"
				( objectStatus "@baseboard_fab2_lib.baseboard_fab2(sch_1):page208_i53" )
				( pin "C9P4.1"
					( objectStatus "a" )
				)
				( pin "C9P4.2"
					( objectStatus "b" )
				)
			)
			( gate "C9P7"
				( objectStatus "@baseboard_fab2_lib.baseboard_fab2(sch_1):page208_i54" )
				( pin "C9P7.1"
					( objectStatus "a" )
				)
				( pin "C9P7.2"
					( objectStatus "b" )
				)
			)
			( gate "C9P9"
				( objectStatus "@baseboard_fab2_lib.baseboard_fab2(sch_1):page208_i55" )
				( pin "C9P9.1"
					( objectStatus "a" )
				)
				( pin "C9P9.2"
					( objectStatus "b" )
				)
			)
			( gate "C9N23"
				( objectStatus "@baseboard_fab2_lib.baseboard_fab2(sch_1):page208_i58" )
				( pin "C9N23.1"
					( objectStatus "a" )
				)
				( pin "C9N23.2"
					( objectStatus "b" )
				)
			)
			( gate "C9P1"
				( objectStatus "@baseboard_fab2_lib.baseboard_fab2(sch_1):page208_i59" )
				( pin "C9P1.1"
					( objectStatus "a" )
				)
				( pin "C9P1.2"
					( objectStatus "b" )
				)
			)
			( gate "C9P2"
				( objectStatus "@baseboard_fab2_lib.baseboard_fab2(sch_1):page208_i60" )
				( pin "C9P2.1"
					( objectStatus "a" )
				)
				( pin "C9P2.2"
					( objectStatus "b" )
				)
			)
			( gate "C9P10"
				( objectStatus "@baseboard_fab2_lib.baseboard_fab2(sch_1):page208_i66" )
				( pin "C9P10.1"
					( objectStatus "a" )
				)
				( pin "C9P10.2"
					( objectStatus "b" )
				)
			)
			( gate "C9R2"
				( objectStatus "@baseboard_fab2_lib.baseboard_fab2(sch_1):page208_i67" )
				( pin "C9R2.1"
					( objectStatus "a" )
				)
				( pin "C9R2.2"
					( objectStatus "b" )
				)
			)
			( gate "EU1D1"
				( objectStatus "@baseboard_fab2_lib.baseboard_fab2(sch_1):page208_i71" )
				( pin "EU1D1.33"
					( objectStatus "boost" )
				)
				( pin "EU1D1.35"
					( objectStatus "en" )
				)
				( pin "EU1D1.6"
					( objectStatus "gl(0)" )
				)
				( pin "EU1D1.41"
					( objectStatus "gl(1)" )
				)
				( pin "EU1D1.38"
					( objectStatus "iout" )
				)
				( pin "EU1D1.2"
					( objectStatus "lgnd" )
				)
				( pin "EU1D1.31"
					( objectStatus "nc" )
				)
				( pin "EU1D1.37"
					( objectStatus "ocset" )
				)
				( pin "EU1D1.5"
					( objectStatus "pgnd(0)" )
				)
				( pin "EU1D1.7"
					( objectStatus "pgnd(1)" )
				)
				( pin "EU1D1.40"
					( objectStatus "pgnd(2)" )
				)
				( pin "EU1D1.32"
					( objectStatus "phase" )
				)
				( pin "EU1D1.34"
					( objectStatus "pwm" )
				)
				( pin "EU1D1.39"
					( objectStatus "refin" )
				)
				( pin "EU1D1.10"
					( objectStatus "sw" )
				)
				( pin "EU1D1.36"
					( objectStatus "tout_flt" )
				)
				( pin "EU1D1.3"
					( objectStatus "vcc" )
				)
				( pin "EU1D1.4"
					( objectStatus "vdrv" )
				)
				( pin "EU1D1.25"
					( objectStatus "vin(0)" )
				)
				( pin "EU1D1.30"
					( objectStatus "vin(1)" )
				)
				( pin "EU1D1.1"
					( objectStatus "vos" )
				)
			)
			( gate "R26"
				( objectStatus "@baseboard_fab2_lib.baseboard_fab2(sch_1):page208_i75" )
				( pin "R26.1"
					( objectStatus "a" )
				)
				( pin "R26.2"
					( objectStatus "b" )
				)
			)
			( gate "R25"
				( objectStatus "@baseboard_fab2_lib.baseboard_fab2(sch_1):page208_i76" )
				( pin "R25.1"
					( objectStatus "a" )
				)
				( pin "R25.2"
					( objectStatus "b" )
				)
			)
			( gate "R1E5"
				( objectStatus "@baseboard_fab2_lib.baseboard_fab2(sch_1):page209_i3" )
				( pin "R1E5.1"
					( objectStatus "a" )
				)
				( pin "R1E5.2"
					( objectStatus "b" )
				)
			)
			( gate "C9P21"
				( objectStatus "@baseboard_fab2_lib.baseboard_fab2(sch_1):page209_i5" )
				( pin "C9P21.1"
					( objectStatus "a" )
				)
				( pin "C9P21.2"
					( objectStatus "b" )
				)
			)
			( gate "C9P19"
				( objectStatus "@baseboard_fab2_lib.baseboard_fab2(sch_1):page209_i7" )
				( pin "C9P19.1"
					( objectStatus "a" )
				)
				( pin "C9P19.2"
					( objectStatus "b" )
				)
			)
			( gate "C9P13"
				( objectStatus "@baseboard_fab2_lib.baseboard_fab2(sch_1):page209_i8" )
				( pin "C9P13.1"
					( objectStatus "a" )
				)
				( pin "C9P13.2"
					( objectStatus "b" )
				)
			)
			( gate "R1E8"
				( objectStatus "@baseboard_fab2_lib.baseboard_fab2(sch_1):page209_i9" )
				( pin "R1E8.1"
					( objectStatus "a" )
				)
				( pin "R1E8.2"
					( objectStatus "b" )
				)
			)
			( gate "R1E7"
				( objectStatus "@baseboard_fab2_lib.baseboard_fab2(sch_1):page209_i10" )
				( pin "R1E7.1"
					( objectStatus "a" )
				)
				( pin "R1E7.2"
					( objectStatus "b" )
				)
			)
			( gate "R1E6"
				( objectStatus "@baseboard_fab2_lib.baseboard_fab2(sch_1):page209_i11" )
				( pin "R1E6.1"
					( objectStatus "a" )
				)
				( pin "R1E6.2"
					( objectStatus "b" )
				)
			)
			( gate "R1E4"
				( objectStatus "@baseboard_fab2_lib.baseboard_fab2(sch_1):page209_i15" )
				( pin "R1E4.1"
					( objectStatus "a" )
				)
				( pin "R1E4.2"
					( objectStatus "b" )
				)
			)
			( gate "C1D2"
				( objectStatus "@baseboard_fab2_lib.baseboard_fab2(sch_1):page209_i16" )
				( pin "C1D2.1"
					( objectStatus "a" )
				)
				( pin "C1D2.2"
					( objectStatus "b" )
				)
			)
			( gate "C1D4"
				( objectStatus "@baseboard_fab2_lib.baseboard_fab2(sch_1):page209_i17" )
				( pin "C1D4.1"
					( objectStatus "a" )
				)
				( pin "C1D4.2"
					( objectStatus "b" )
				)
			)
			( gate "C1C21"
				( objectStatus "@baseboard_fab2_lib.baseboard_fab2(sch_1):page209_i18" )
				( pin "C1C21.1"
					( objectStatus "a" )
				)
				( pin "C1C21.2"
					( objectStatus "b" )
				)
			)
			( gate "C1C24"
				( objectStatus "@baseboard_fab2_lib.baseboard_fab2(sch_1):page209_i20" )
				( pin "C1C24.1"
					( objectStatus "a" )
				)
				( pin "C1C24.2"
					( objectStatus "b" )
				)
			)
			( gate "C1C18"
				( objectStatus "@baseboard_fab2_lib.baseboard_fab2(sch_1):page209_i21" )
				( pin "C1C18.1"
					( objectStatus "a" )
				)
				( pin "C1C18.2"
					( objectStatus "b" )
				)
			)
			( gate "C1C20"
				( objectStatus "@baseboard_fab2_lib.baseboard_fab2(sch_1):page209_i22" )
				( pin "C1C20.1"
					( objectStatus "a" )
				)
				( pin "C1C20.2"
					( objectStatus "b" )
				)
			)
			( gate "R9N11"
				( objectStatus "@baseboard_fab2_lib.baseboard_fab2(sch_1):page209_i24" )
				( pin "R9N11.1"
					( objectStatus "a" )
				)
				( pin "R9N11.2"
					( objectStatus "b" )
				)
			)
			( gate "C1B16"
				( objectStatus "@baseboard_fab2_lib.baseboard_fab2(sch_1):page209_i30" )
				( pin "C1B16.1"
					( objectStatus "a" )
				)
				( pin "C1B16.2"
					( objectStatus "b" )
				)
			)
			( gate "L1B2"
				( objectStatus "@baseboard_fab2_lib.baseboard_fab2(sch_1):page209_i32" )
				( pin "L1B2.1"
					( objectStatus "ina" )
				)
				( pin "L1B2.2"
					( objectStatus "inb" )
				)
			)
			( gate "C1C1"
				( objectStatus "@baseboard_fab2_lib.baseboard_fab2(sch_1):page209_i35" )
				( pin "C1C1.1"
					( objectStatus "a" )
				)
				( pin "C1C1.2"
					( objectStatus "b" )
				)
			)
			( gate "C1E18"
				( objectStatus "@baseboard_fab2_lib.baseboard_fab2(sch_1):page209_i37" )
				( pin "C1E18.1"
					( objectStatus "a" )
				)
				( pin "C1E18.2"
					( objectStatus "b" )
				)
			)
			( gate "C1C2"
				( objectStatus "@baseboard_fab2_lib.baseboard_fab2(sch_1):page209_i38" )
				( pin "C1C2.1"
					( objectStatus "a" )
				)
				( pin "C1C2.2"
					( objectStatus "b" )
				)
			)
			( gate "R1B20"
				( objectStatus "@baseboard_fab2_lib.baseboard_fab2(sch_1):page209_i39" )
				( pin "R1B20.1"
					( objectStatus "a" )
				)
				( pin "R1B20.2"
					( objectStatus "b" )
				)
			)
			( gate "L1C2"
				( objectStatus "@baseboard_fab2_lib.baseboard_fab2(sch_1):page209_i40" )
				( pin "L1C2.1"
					( objectStatus "ina" )
				)
				( pin "L1C2.2"
					( objectStatus "inb" )
				)
			)
			( gate "C1D24"
				( objectStatus "@baseboard_fab2_lib.baseboard_fab2(sch_1):page209_i42" )
				( pin "C1D24.1"
					( objectStatus "a" )
				)
				( pin "C1D24.2"
					( objectStatus "b" )
				)
			)
			( gate "U1B3"
				( objectStatus "@baseboard_fab2_lib.baseboard_fab2(sch_1):page209_i52" )
				( pin "U1B3.1"
					( objectStatus "gnd(0)" )
				)
				( pin "U1B3.2"
					( objectStatus "gnd(1)" )
				)
				( pin "U1B3.6"
					( objectStatus "\out\" )
				)
				( pin "U1B3.5"
					( objectStatus "rsn" )
				)
				( pin "U1B3.4"
					( objectStatus "rsp" )
				)
				( pin "U1B3.3"
					( objectStatus "vcc" )
				)
			)
			( gate "C9P20"
				( objectStatus "@baseboard_fab2_lib.baseboard_fab2(sch_1):page209_i55" )
				( pin "C9P20.1"
					( objectStatus "a" )
				)
				( pin "C9P20.2"
					( objectStatus "b" )
				)
			)
			( gate "EU1C3"
				( objectStatus "@baseboard_fab2_lib.baseboard_fab2(sch_1):page209_i56" )
				( pin "EU1C3.33"
					( objectStatus "boost" )
				)
				( pin "EU1C3.35"
					( objectStatus "en" )
				)
				( pin "EU1C3.6"
					( objectStatus "gl(0)" )
				)
				( pin "EU1C3.41"
					( objectStatus "gl(1)" )
				)
				( pin "EU1C3.38"
					( objectStatus "iout" )
				)
				( pin "EU1C3.2"
					( objectStatus "lgnd" )
				)
				( pin "EU1C3.31"
					( objectStatus "nc" )
				)
				( pin "EU1C3.37"
					( objectStatus "ocset" )
				)
				( pin "EU1C3.5"
					( objectStatus "pgnd(0)" )
				)
				( pin "EU1C3.7"
					( objectStatus "pgnd(1)" )
				)
				( pin "EU1C3.40"
					( objectStatus "pgnd(2)" )
				)
				( pin "EU1C3.32"
					( objectStatus "phase" )
				)
				( pin "EU1C3.34"
					( objectStatus "pwm" )
				)
				( pin "EU1C3.39"
					( objectStatus "refin" )
				)
				( pin "EU1C3.10"
					( objectStatus "sw" )
				)
				( pin "EU1C3.36"
					( objectStatus "tout_flt" )
				)
				( pin "EU1C3.3"
					( objectStatus "vcc" )
				)
				( pin "EU1C3.4"
					( objectStatus "vdrv" )
				)
				( pin "EU1C3.25"
					( objectStatus "vin(0)" )
				)
				( pin "EU1C3.30"
					( objectStatus "vin(1)" )
				)
				( pin "EU1C3.1"
					( objectStatus "vos" )
				)
			)
			( gate "R27"
				( objectStatus "@baseboard_fab2_lib.baseboard_fab2(sch_1):page209_i59" )
				( pin "R27.1"
					( objectStatus "a" )
				)
				( pin "R27.2"
					( objectStatus "b" )
				)
			)
			( gate "C1C19"
				( objectStatus "@baseboard_fab2_lib.baseboard_fab2(sch_1):page210_i8" )
				( pin "C1C19.1"
					( objectStatus "a" )
				)
				( pin "C1C19.2"
					( objectStatus "b" )
				)
			)
			( gate "L1C1"
				( objectStatus "@baseboard_fab2_lib.baseboard_fab2(sch_1):page210_i10" )
				( pin "L1C1.1"
					( objectStatus "ina" )
				)
				( pin "L1C1.2"
					( objectStatus "inb" )
				)
			)
			( gate "C9N11"
				( objectStatus "@baseboard_fab2_lib.baseboard_fab2(sch_1):page210_i12" )
				( pin "C9N11.1"
					( objectStatus "a" )
				)
				( pin "C9N11.2"
					( objectStatus "b" )
				)
			)
			( gate "C9N20"
				( objectStatus "@baseboard_fab2_lib.baseboard_fab2(sch_1):page210_i14" )
				( pin "C9N20.1"
					( objectStatus "a" )
				)
				( pin "C9N20.2"
					( objectStatus "b" )
				)
			)
			( gate "R9N3"
				( objectStatus "@baseboard_fab2_lib.baseboard_fab2(sch_1):page210_i20" )
				( pin "R9N3.1"
					( objectStatus "a" )
				)
				( pin "R9N3.2"
					( objectStatus "b" )
				)
			)
			( gate "C1C4"
				( objectStatus "@baseboard_fab2_lib.baseboard_fab2(sch_1):page210_i22" )
				( pin "C1C4.1"
					( objectStatus "a" )
				)
				( pin "C1C4.2"
					( objectStatus "b" )
				)
			)
			( gate "C1C3"
				( objectStatus "@baseboard_fab2_lib.baseboard_fab2(sch_1):page210_i23" )
				( pin "C1C3.1"
					( objectStatus "a" )
				)
				( pin "C1C3.2"
					( objectStatus "b" )
				)
			)
			( gate "C1C12"
				( objectStatus "@baseboard_fab2_lib.baseboard_fab2(sch_1):page210_i24" )
				( pin "C1C12.1"
					( objectStatus "a" )
				)
				( pin "C1C12.2"
					( objectStatus "b" )
				)
			)
			( gate "C1C5"
				( objectStatus "@baseboard_fab2_lib.baseboard_fab2(sch_1):page210_i26" )
				( pin "C1C5.1"
					( objectStatus "a" )
				)
				( pin "C1C5.2"
					( objectStatus "b" )
				)
			)
			( gate "C1C17"
				( objectStatus "@baseboard_fab2_lib.baseboard_fab2(sch_1):page210_i27" )
				( pin "C1C17.1"
					( objectStatus "a" )
				)
				( pin "C1C17.2"
					( objectStatus "b" )
				)
			)
			( gate "C1C15"
				( objectStatus "@baseboard_fab2_lib.baseboard_fab2(sch_1):page210_i28" )
				( pin "C1C15.1"
					( objectStatus "a" )
				)
				( pin "C1C15.2"
					( objectStatus "b" )
				)
			)
			( gate "R1C12"
				( objectStatus "@baseboard_fab2_lib.baseboard_fab2(sch_1):page210_i29" )
				( pin "R1C12.1"
					( objectStatus "a" )
				)
				( pin "R1C12.2"
					( objectStatus "b" )
				)
			)
			( gate "R1C7"
				( objectStatus "@baseboard_fab2_lib.baseboard_fab2(sch_1):page210_i31" )
				( pin "R1C7.1"
					( objectStatus "a" )
				)
				( pin "R1C7.2"
					( objectStatus "b" )
				)
			)
			( gate "R1C5"
				( objectStatus "@baseboard_fab2_lib.baseboard_fab2(sch_1):page210_i32" )
				( pin "R1C5.1"
					( objectStatus "a" )
				)
				( pin "R1C5.2"
					( objectStatus "b" )
				)
			)
			( gate "R1C4"
				( objectStatus "@baseboard_fab2_lib.baseboard_fab2(sch_1):page210_i33" )
				( pin "R1C4.1"
					( objectStatus "a" )
				)
				( pin "R1C4.2"
					( objectStatus "b" )
				)
			)
			( gate "R1C6"
				( objectStatus "@baseboard_fab2_lib.baseboard_fab2(sch_1):page210_i34" )
				( pin "R1C6.1"
					( objectStatus "a" )
				)
				( pin "R1C6.2"
					( objectStatus "b" )
				)
			)
			( gate "C9N13"
				( objectStatus "@baseboard_fab2_lib.baseboard_fab2(sch_1):page210_i35" )
				( pin "C9N13.1"
					( objectStatus "a" )
				)
				( pin "C9N13.2"
					( objectStatus "b" )
				)
			)
			( gate "C9N19"
				( objectStatus "@baseboard_fab2_lib.baseboard_fab2(sch_1):page210_i36" )
				( pin "C9N19.1"
					( objectStatus "a" )
				)
				( pin "C9N19.2"
					( objectStatus "b" )
				)
			)
			( gate "C9N21"
				( objectStatus "@baseboard_fab2_lib.baseboard_fab2(sch_1):page210_i38" )
				( pin "C9N21.1"
					( objectStatus "a" )
				)
				( pin "C9N21.2"
					( objectStatus "b" )
				)
			)
			( gate "C9N22"
				( objectStatus "@baseboard_fab2_lib.baseboard_fab2(sch_1):page210_i44" )
				( pin "C9N22.1"
					( objectStatus "a" )
				)
				( pin "C9N22.2"
					( objectStatus "b" )
				)
			)
			( gate "R9N4"
				( objectStatus "@baseboard_fab2_lib.baseboard_fab2(sch_1):page210_i45" )
				( pin "R9N4.1"
					( objectStatus "a" )
				)
				( pin "R9N4.2"
					( objectStatus "b" )
				)
			)
			( gate "EU1C1"
				( objectStatus "@baseboard_fab2_lib.baseboard_fab2(sch_1):page210_i51" )
				( pin "EU1C1.33"
					( objectStatus "boost" )
				)
				( pin "EU1C1.35"
					( objectStatus "en" )
				)
				( pin "EU1C1.6"
					( objectStatus "gl(0)" )
				)
				( pin "EU1C1.41"
					( objectStatus "gl(1)" )
				)
				( pin "EU1C1.38"
					( objectStatus "iout" )
				)
				( pin "EU1C1.2"
					( objectStatus "lgnd" )
				)
				( pin "EU1C1.31"
					( objectStatus "nc" )
				)
				( pin "EU1C1.37"
					( objectStatus "ocset" )
				)
				( pin "EU1C1.5"
					( objectStatus "pgnd(0)" )
				)
				( pin "EU1C1.7"
					( objectStatus "pgnd(1)" )
				)
				( pin "EU1C1.40"
					( objectStatus "pgnd(2)" )
				)
				( pin "EU1C1.32"
					( objectStatus "phase" )
				)
				( pin "EU1C1.34"
					( objectStatus "pwm" )
				)
				( pin "EU1C1.39"
					( objectStatus "refin" )
				)
				( pin "EU1C1.10"
					( objectStatus "sw" )
				)
				( pin "EU1C1.36"
					( objectStatus "tout_flt" )
				)
				( pin "EU1C1.3"
					( objectStatus "vcc" )
				)
				( pin "EU1C1.4"
					( objectStatus "vdrv" )
				)
				( pin "EU1C1.25"
					( objectStatus "vin(0)" )
				)
				( pin "EU1C1.30"
					( objectStatus "vin(1)" )
				)
				( pin "EU1C1.1"
					( objectStatus "vos" )
				)
			)
			( gate "R28"
				( objectStatus "@baseboard_fab2_lib.baseboard_fab2(sch_1):page210_i52" )
				( pin "R28.1"
					( objectStatus "a" )
				)
				( pin "R28.2"
					( objectStatus "b" )
				)
			)
			( gate "C3P4"
				( objectStatus "@baseboard_fab2_lib.baseboard_fab2(sch_1):page211_i11" )
				( pin "C3P4.1"
					( objectStatus "a" )
				)
				( pin "C3P4.2"
					( objectStatus "b" )
				)
			)
			( gate "C3P5"
				( objectStatus "@baseboard_fab2_lib.baseboard_fab2(sch_1):page211_i13" )
				( pin "C3P5.1"
					( objectStatus "a" )
				)
				( pin "C3P5.2"
					( objectStatus "b" )
				)
			)
			( gate "R3P11"
				( objectStatus "@baseboard_fab2_lib.baseboard_fab2(sch_1):page211_i16" )
				( pin "R3P11.1"
					( objectStatus "a" )
				)
				( pin "R3P11.2"
					( objectStatus "b" )
				)
			)
			( gate "R3P13"
				( objectStatus "@baseboard_fab2_lib.baseboard_fab2(sch_1):page211_i17" )
				( pin "R3P13.1"
					( objectStatus "a" )
				)
				( pin "R3P13.2"
					( objectStatus "b" )
				)
			)
			( gate "C3P3"
				( objectStatus "@baseboard_fab2_lib.baseboard_fab2(sch_1):page211_i20" )
				( pin "C3P3.1"
					( objectStatus "a" )
				)
				( pin "C3P3.2"
					( objectStatus "b" )
				)
			)
			( gate "C3P7"
				( objectStatus "@baseboard_fab2_lib.baseboard_fab2(sch_1):page211_i22" )
				( pin "C3P7.1"
					( objectStatus "a" )
				)
				( pin "C3P7.2"
					( objectStatus "b" )
				)
			)
			( gate "R3P22"
				( objectStatus "@baseboard_fab2_lib.baseboard_fab2(sch_1):page211_i24" )
				( pin "R3P22.1"
					( objectStatus "a" )
				)
				( pin "R3P22.2"
					( objectStatus "b" )
				)
			)
			( gate "R3P17"
				( objectStatus "@baseboard_fab2_lib.baseboard_fab2(sch_1):page211_i28" )
				( pin "R3P17.1"
					( objectStatus "a" )
				)
				( pin "R3P17.2"
					( objectStatus "b" )
				)
			)
			( gate "R3P15"
				( objectStatus "@baseboard_fab2_lib.baseboard_fab2(sch_1):page211_i29" )
				( pin "R3P15.1"
					( objectStatus "a" )
				)
				( pin "R3P15.2"
					( objectStatus "b" )
				)
			)
			( gate "R3P12"
				( objectStatus "@baseboard_fab2_lib.baseboard_fab2(sch_1):page211_i31" )
				( pin "R3P12.1"
					( objectStatus "a" )
				)
				( pin "R3P12.2"
					( objectStatus "b" )
				)
			)
			( gate "R3P16"
				( objectStatus "@baseboard_fab2_lib.baseboard_fab2(sch_1):page211_i32" )
				( pin "R3P16.1"
					( objectStatus "a" )
				)
				( pin "R3P16.2"
					( objectStatus "b" )
				)
			)
			( gate "C3P2"
				( objectStatus "@baseboard_fab2_lib.baseboard_fab2(sch_1):page211_i33" )
				( pin "C3P2.1"
					( objectStatus "a" )
				)
				( pin "C3P2.2"
					( objectStatus "b" )
				)
			)
			( gate "R3P24"
				( objectStatus "@baseboard_fab2_lib.baseboard_fab2(sch_1):page211_i46" )
				( pin "R3P24.1"
					( objectStatus "a" )
				)
				( pin "R3P24.2"
					( objectStatus "b" )
				)
			)
			( gate "R3P23"
				( objectStatus "@baseboard_fab2_lib.baseboard_fab2(sch_1):page211_i47" )
				( pin "R3P23.1"
					( objectStatus "a" )
				)
				( pin "R3P23.2"
					( objectStatus "b" )
				)
			)
			( gate "R3P4"
				( objectStatus "@baseboard_fab2_lib.baseboard_fab2(sch_1):page211_i52" )
				( pin "R3P4.1"
					( objectStatus "a" )
				)
				( pin "R3P4.2"
					( objectStatus "b" )
				)
			)
			( gate "R3P25"
				( objectStatus "@baseboard_fab2_lib.baseboard_fab2(sch_1):page211_i56" )
				( pin "R3P25.1"
					( objectStatus "a" )
				)
				( pin "R3P25.2"
					( objectStatus "b" )
				)
			)
			( gate "R3P20"
				( objectStatus "@baseboard_fab2_lib.baseboard_fab2(sch_1):page211_i58" )
				( pin "R3P20.1"
					( objectStatus "a" )
				)
				( pin "R3P20.2"
					( objectStatus "b" )
				)
			)
			( gate "R3N23"
				( objectStatus "@baseboard_fab2_lib.baseboard_fab2(sch_1):page211_i60" )
				( pin "R3N23.1"
					( objectStatus "a" )
				)
				( pin "R3N23.2"
					( objectStatus "b" )
				)
			)
			( gate "R3P1"
				( objectStatus "@baseboard_fab2_lib.baseboard_fab2(sch_1):page211_i61" )
				( pin "R3P1.1"
					( objectStatus "a" )
				)
				( pin "R3P1.2"
					( objectStatus "b" )
				)
			)
			( gate "R3P18"
				( objectStatus "@baseboard_fab2_lib.baseboard_fab2(sch_1):page211_i64" )
				( pin "R3P18.1"
					( objectStatus "a" )
				)
				( pin "R3P18.2"
					( objectStatus "b" )
				)
			)
			( gate "R3N22"
				( objectStatus "@baseboard_fab2_lib.baseboard_fab2(sch_1):page211_i65" )
				( pin "R3N22.1"
					( objectStatus "a" )
				)
				( pin "R3N22.2"
					( objectStatus "b" )
				)
			)
			( gate "C3P6"
				( objectStatus "@baseboard_fab2_lib.baseboard_fab2(sch_1):page211_i71" )
				( pin "C3P6.1"
					( objectStatus "a" )
				)
				( pin "C3P6.2"
					( objectStatus "b" )
				)
			)
			( gate "R3N19"
				( objectStatus "@baseboard_fab2_lib.baseboard_fab2(sch_1):page211_i81" )
				( pin "R3N19.1"
					( objectStatus "a" )
				)
				( pin "R3N19.2"
					( objectStatus "b" )
				)
			)
			( gate "C3N39"
				( objectStatus "@baseboard_fab2_lib.baseboard_fab2(sch_1):page211_i83" )
				( pin "C3N39.1"
					( objectStatus "a" )
				)
				( pin "C3N39.2"
					( objectStatus "b" )
				)
			)
			( gate "R3P26"
				( objectStatus "@baseboard_fab2_lib.baseboard_fab2(sch_1):page211_i87" )
				( pin "R3P26.1"
					( objectStatus "a" )
				)
				( pin "R3P26.2"
					( objectStatus "b" )
				)
			)
			( gate "R3P21"
				( objectStatus "@baseboard_fab2_lib.baseboard_fab2(sch_1):page211_i88" )
				( pin "R3P21.1"
					( objectStatus "a" )
				)
				( pin "R3P21.2"
					( objectStatus "b" )
				)
			)
			( gate "R3N6"
				( objectStatus "@baseboard_fab2_lib.baseboard_fab2(sch_1):page211_i91" )
				( pin "R3N6.1"
					( objectStatus "a" )
				)
				( pin "R3N6.2"
					( objectStatus "b" )
				)
			)
			( gate "EU3P1"
				( objectStatus "@baseboard_fab2_lib.baseboard_fab2(sch_1):page211_i93" )
				( pin "EU3P1.21"
					( objectStatus "airef1" )
				)
				( pin "EU3P1.22"
					( objectStatus "aisen1" )
				)
				( pin "EU3P1.5"
					( objectStatus "apwm1" )
				)
				( pin "EU3P1.35"
					( objectStatus "atsen" )
				)
				( pin "EU3P1.20"
					( objectStatus "avref" )
				)
				( pin "EU3P1.10"
					( objectStatus "avren" )
				)
				( pin "EU3P1.9"
					( objectStatus "avrrdy" )
				)
				( pin "EU3P1.19"
					( objectStatus "avsen" )
				)
				( pin "EU3P1.25"
					( objectStatus "biref1" )
				)
				( pin "EU3P1.26"
					( objectStatus "bisen1" )
				)
				( pin "EU3P1.3"
					( objectStatus "bpwm1" )
				)
				( pin "EU3P1.34"
					( objectStatus "btsen" )
				)
				( pin "EU3P1.30"
					( objectStatus "bvref" )
				)
				( pin "EU3P1.29"
					( objectStatus "bvsen" )
				)
				( pin "EU3P1.1"
					( objectStatus "dnc(0)" )
				)
				( pin "EU3P1.2"
					( objectStatus "dnc(1)" )
				)
				( pin "EU3P1.4"
					( objectStatus "dnc(2)" )
				)
				( pin "EU3P1.24"
					( objectStatus "dnc(3)" )
				)
				( pin "EU3P1.28"
					( objectStatus "dnc(4)" )
				)
				( pin "EU3P1.27"
					( objectStatus "gnd(0)" )
				)
				( pin "EU3P1.23"
					( objectStatus "gnd(1)" )
				)
				( pin "EU3P1.38"
					( objectStatus "iinsen" )
				)
				( pin "EU3P1.13"
					( objectStatus "mp0" )
				)
				( pin "EU3P1.14"
					( objectStatus "mp1" )
				)
				( pin "EU3P1.18"
					( objectStatus "mp2" )
				)
				( pin "EU3P1.31"
					( objectStatus "mp3" )
				)
				( pin "EU3P1.32"
					( objectStatus "mp4" )
				)
				( pin "EU3P1.12"
					( objectStatus "pinalrt_n" )
				)
				( pin "EU3P1.8"
					( objectStatus "reset_n" )
				)
				( pin "EU3P1.7"
					( objectStatus "scl" )
				)
				( pin "EU3P1.6"
					( objectStatus "sda" )
				)
				( pin "EU3P1.41"
					( objectStatus "thpad" )
				)
				( pin "EU3P1.17"
					( objectStatus "valrt_n" )
				)
				( pin "EU3P1.15"
					( objectStatus "vclk" )
				)
				( pin "EU3P1.40"
					( objectStatus "vd12" )
				)
				( pin "EU3P1.39"
					( objectStatus "vdd" )
				)
				( pin "EU3P1.16"
					( objectStatus "vdio" )
				)
				( pin "EU3P1.37"
					( objectStatus "vinsen" )
				)
				( pin "EU3P1.11"
					( objectStatus "vrhot_n" )
				)
				( pin "EU3P1.36"
					( objectStatus "xaddr1" )
				)
				( pin "EU3P1.33"
					( objectStatus "xaddr2" )
				)
			)
			( gate "C3N38"
				( objectStatus "@baseboard_fab2_lib.baseboard_fab2(sch_1):page212_i16" )
				( pin "C3N38.1"
					( objectStatus "a" )
				)
				( pin "C3N38.2"
					( objectStatus "b" )
				)
			)
			( gate "C3N26"
				( objectStatus "@baseboard_fab2_lib.baseboard_fab2(sch_1):page212_i17" )
				( pin "C3N26.1"
					( objectStatus "a" )
				)
				( pin "C3N26.2"
					( objectStatus "b" )
				)
			)
			( gate "C3N35"
				( objectStatus "@baseboard_fab2_lib.baseboard_fab2(sch_1):page212_i18" )
				( pin "C3N35.1"
					( objectStatus "a" )
				)
				( pin "C3N35.2"
					( objectStatus "b" )
				)
			)
			( gate "C7C6"
				( objectStatus "@baseboard_fab2_lib.baseboard_fab2(sch_1):page212_i23" )
				( pin "C7C6.1"
					( objectStatus "a" )
				)
				( pin "C7C6.2"
					( objectStatus "b" )
				)
			)
			( gate "L7C2"
				( objectStatus "@baseboard_fab2_lib.baseboard_fab2(sch_1):page212_i25" )
				( pin "L7C2.1"
					( objectStatus "ina" )
				)
				( pin "L7C2.2"
					( objectStatus "inb" )
				)
			)
			( gate "R3N7"
				( objectStatus "@baseboard_fab2_lib.baseboard_fab2(sch_1):page212_i32" )
				( pin "R3N7.1"
					( objectStatus "a" )
				)
				( pin "R3N7.2"
					( objectStatus "b" )
				)
			)
			( gate "C7C18"
				( objectStatus "@baseboard_fab2_lib.baseboard_fab2(sch_1):page212_i33" )
				( pin "C7C18.1"
					( objectStatus "a" )
				)
				( pin "C7C18.2"
					( objectStatus "b" )
				)
			)
			( gate "C3N37"
				( objectStatus "@baseboard_fab2_lib.baseboard_fab2(sch_1):page212_i34" )
				( pin "C3N37.1"
					( objectStatus "a" )
				)
				( pin "C3N37.2"
					( objectStatus "b" )
				)
			)
			( gate "C7C17"
				( objectStatus "@baseboard_fab2_lib.baseboard_fab2(sch_1):page212_i36" )
				( pin "C7C17.1"
					( objectStatus "a" )
				)
				( pin "C7C17.2"
					( objectStatus "b" )
				)
			)
			( gate "C7C14"
				( objectStatus "@baseboard_fab2_lib.baseboard_fab2(sch_1):page212_i37" )
				( pin "C7C14.1"
					( objectStatus "a" )
				)
				( pin "C7C14.2"
					( objectStatus "b" )
				)
			)
			( gate "C7C11"
				( objectStatus "@baseboard_fab2_lib.baseboard_fab2(sch_1):page212_i38" )
				( pin "C7C11.1"
					( objectStatus "a" )
				)
				( pin "C7C11.2"
					( objectStatus "b" )
				)
			)
			( gate "C7C12"
				( objectStatus "@baseboard_fab2_lib.baseboard_fab2(sch_1):page212_i39" )
				( pin "C7C12.1"
					( objectStatus "a" )
				)
				( pin "C7C12.2"
					( objectStatus "b" )
				)
			)
			( gate "C3N36"
				( objectStatus "@baseboard_fab2_lib.baseboard_fab2(sch_1):page212_i40" )
				( pin "C3N36.1"
					( objectStatus "a" )
				)
				( pin "C3N36.2"
					( objectStatus "b" )
				)
			)
			( gate "C3N33"
				( objectStatus "@baseboard_fab2_lib.baseboard_fab2(sch_1):page212_i41" )
				( pin "C3N33.1"
					( objectStatus "a" )
				)
				( pin "C3N33.2"
					( objectStatus "b" )
				)
			)
			( gate "C3N34"
				( objectStatus "@baseboard_fab2_lib.baseboard_fab2(sch_1):page212_i43" )
				( pin "C3N34.1"
					( objectStatus "a" )
				)
				( pin "C3N34.2"
					( objectStatus "b" )
				)
			)
			( gate "C7C8"
				( objectStatus "@baseboard_fab2_lib.baseboard_fab2(sch_1):page212_i51" )
				( pin "C7C8.1"
					( objectStatus "a" )
				)
				( pin "C7C8.2"
					( objectStatus "b" )
				)
			)
			( gate "C7C7"
				( objectStatus "@baseboard_fab2_lib.baseboard_fab2(sch_1):page212_i54" )
				( pin "C7C7.1"
					( objectStatus "a" )
				)
				( pin "C7C7.2"
					( objectStatus "b" )
				)
			)
			( gate "L7C1"
				( objectStatus "@baseboard_fab2_lib.baseboard_fab2(sch_1):page212_i56" )
				( pin "L7C1.1"
					( objectStatus "ina" )
				)
				( pin "L7C1.2"
					( objectStatus "inb" )
				)
			)
			( gate "C3P1"
				( objectStatus "@baseboard_fab2_lib.baseboard_fab2(sch_1):page212_i60" )
				( pin "C3P1.1"
					( objectStatus "a" )
				)
				( pin "C3P1.2"
					( objectStatus "b" )
				)
			)
			( gate "R3P10"
				( objectStatus "@baseboard_fab2_lib.baseboard_fab2(sch_1):page212_i66" )
				( pin "R3P10.1"
					( objectStatus "a" )
				)
				( pin "R3P10.2"
					( objectStatus "b" )
				)
			)
			( gate "R3N20"
				( objectStatus "@baseboard_fab2_lib.baseboard_fab2(sch_1):page212_i68" )
				( pin "R3N20.1"
					( objectStatus "a" )
				)
				( pin "R3N20.2"
					( objectStatus "b" )
				)
			)
			( gate "R3P9"
				( objectStatus "@baseboard_fab2_lib.baseboard_fab2(sch_1):page212_i71" )
				( pin "R3P9.1"
					( objectStatus "a" )
				)
				( pin "R3P9.2"
					( objectStatus "b" )
				)
			)
			( gate "R3N21"
				( objectStatus "@baseboard_fab2_lib.baseboard_fab2(sch_1):page212_i74" )
				( pin "R3N21.1"
					( objectStatus "a" )
				)
				( pin "R3N21.2"
					( objectStatus "b" )
				)
			)
			( gate "C7C10"
				( objectStatus "@baseboard_fab2_lib.baseboard_fab2(sch_1):page212_i77" )
				( pin "C7C10.1"
					( objectStatus "a" )
				)
				( pin "C7C10.2"
					( objectStatus "b" )
				)
			)
			( gate "R7C3"
				( objectStatus "@baseboard_fab2_lib.baseboard_fab2(sch_1):page212_i78" )
				( pin "R7C3.1"
					( objectStatus "a" )
				)
				( pin "R7C3.2"
					( objectStatus "b" )
				)
			)
			( gate "EU7C1"
				( objectStatus "@baseboard_fab2_lib.baseboard_fab2(sch_1):page212_i101" )
				( pin "EU7C1.33"
					( objectStatus "boost" )
				)
				( pin "EU7C1.35"
					( objectStatus "en" )
				)
				( pin "EU7C1.6"
					( objectStatus "gl(0)" )
				)
				( pin "EU7C1.41"
					( objectStatus "gl(1)" )
				)
				( pin "EU7C1.38"
					( objectStatus "iout" )
				)
				( pin "EU7C1.2"
					( objectStatus "lgnd" )
				)
				( pin "EU7C1.31"
					( objectStatus "nc" )
				)
				( pin "EU7C1.37"
					( objectStatus "ocset" )
				)
				( pin "EU7C1.5"
					( objectStatus "pgnd(0)" )
				)
				( pin "EU7C1.7"
					( objectStatus "pgnd(1)" )
				)
				( pin "EU7C1.40"
					( objectStatus "pgnd(2)" )
				)
				( pin "EU7C1.32"
					( objectStatus "phase" )
				)
				( pin "EU7C1.34"
					( objectStatus "pwm" )
				)
				( pin "EU7C1.39"
					( objectStatus "refin" )
				)
				( pin "EU7C1.10"
					( objectStatus "sw" )
				)
				( pin "EU7C1.36"
					( objectStatus "tout_flt" )
				)
				( pin "EU7C1.3"
					( objectStatus "vcc" )
				)
				( pin "EU7C1.4"
					( objectStatus "vdrv" )
				)
				( pin "EU7C1.25"
					( objectStatus "vin(0)" )
				)
				( pin "EU7C1.30"
					( objectStatus "vin(1)" )
				)
				( pin "EU7C1.1"
					( objectStatus "vos" )
				)
			)
			( gate "R35"
				( objectStatus "@baseboard_fab2_lib.baseboard_fab2(sch_1):page212_i103" )
				( pin "R35.1"
					( objectStatus "a" )
				)
				( pin "R35.2"
					( objectStatus "b" )
				)
			)
			( gate "C4D31"
				( objectStatus "@baseboard_fab2_lib.baseboard_fab2(sch_1):page213_i9" )
				( pin "C4D31.1"
					( objectStatus "a" )
				)
				( pin "C4D31.2"
					( objectStatus "b" )
				)
			)
			( gate "C4D32"
				( objectStatus "@baseboard_fab2_lib.baseboard_fab2(sch_1):page213_i11" )
				( pin "C4D32.1"
					( objectStatus "a" )
				)
				( pin "C4D32.2"
					( objectStatus "b" )
				)
			)
			( gate "R4D46"
				( objectStatus "@baseboard_fab2_lib.baseboard_fab2(sch_1):page213_i13" )
				( pin "R4D46.1"
					( objectStatus "a" )
				)
				( pin "R4D46.2"
					( objectStatus "b" )
				)
			)
			( gate "R4D59"
				( objectStatus "@baseboard_fab2_lib.baseboard_fab2(sch_1):page213_i14" )
				( pin "R4D59.1"
					( objectStatus "a" )
				)
				( pin "R4D59.2"
					( objectStatus "b" )
				)
			)
			( gate "R4D42"
				( objectStatus "@baseboard_fab2_lib.baseboard_fab2(sch_1):page213_i15" )
				( pin "R4D42.1"
					( objectStatus "a" )
				)
				( pin "R4D42.2"
					( objectStatus "b" )
				)
			)
			( gate "R4D56"
				( objectStatus "@baseboard_fab2_lib.baseboard_fab2(sch_1):page213_i16" )
				( pin "R4D56.1"
					( objectStatus "a" )
				)
				( pin "R4D56.2"
					( objectStatus "b" )
				)
			)
			( gate "C4D36"
				( objectStatus "@baseboard_fab2_lib.baseboard_fab2(sch_1):page213_i17" )
				( pin "C4D36.1"
					( objectStatus "a" )
				)
				( pin "C4D36.2"
					( objectStatus "b" )
				)
			)
			( gate "R4D47"
				( objectStatus "@baseboard_fab2_lib.baseboard_fab2(sch_1):page213_i25" )
				( pin "R4D47.1"
					( objectStatus "a" )
				)
				( pin "R4D47.2"
					( objectStatus "b" )
				)
			)
			( gate "R6P35"
				( objectStatus "@baseboard_fab2_lib.baseboard_fab2(sch_1):page213_i27" )
				( pin "R6P35.1"
					( objectStatus "a" )
				)
				( pin "R6P35.2"
					( objectStatus "b" )
				)
			)
			( gate "R6P33"
				( objectStatus "@baseboard_fab2_lib.baseboard_fab2(sch_1):page213_i30" )
				( pin "R6P33.1"
					( objectStatus "a" )
				)
				( pin "R6P33.2"
					( objectStatus "b" )
				)
			)
			( gate "R4D60"
				( objectStatus "@baseboard_fab2_lib.baseboard_fab2(sch_1):page213_i31" )
				( pin "R4D60.1"
					( objectStatus "a" )
				)
				( pin "R4D60.2"
					( objectStatus "b" )
				)
			)
			( gate "R4D57"
				( objectStatus "@baseboard_fab2_lib.baseboard_fab2(sch_1):page213_i32" )
				( pin "R4D57.1"
					( objectStatus "a" )
				)
				( pin "R4D57.2"
					( objectStatus "b" )
				)
			)
			( gate "C4D40"
				( objectStatus "@baseboard_fab2_lib.baseboard_fab2(sch_1):page213_i33" )
				( pin "C4D40.1"
					( objectStatus "a" )
				)
				( pin "C4D40.2"
					( objectStatus "b" )
				)
			)
			( gate "C4D38"
				( objectStatus "@baseboard_fab2_lib.baseboard_fab2(sch_1):page213_i35" )
				( pin "C4D38.1"
					( objectStatus "a" )
				)
				( pin "C4D38.2"
					( objectStatus "b" )
				)
			)
			( gate "R4D54"
				( objectStatus "@baseboard_fab2_lib.baseboard_fab2(sch_1):page213_i37" )
				( pin "R4D54.1"
					( objectStatus "a" )
				)
				( pin "R4D54.2"
					( objectStatus "b" )
				)
			)
			( gate "R4D44"
				( objectStatus "@baseboard_fab2_lib.baseboard_fab2(sch_1):page213_i38" )
				( pin "R4D44.1"
					( objectStatus "a" )
				)
				( pin "R4D44.2"
					( objectStatus "b" )
				)
			)
			( gate "R4D43"
				( objectStatus "@baseboard_fab2_lib.baseboard_fab2(sch_1):page213_i39" )
				( pin "R4D43.1"
					( objectStatus "a" )
				)
				( pin "R4D43.2"
					( objectStatus "b" )
				)
			)
			( gate "R4D64"
				( objectStatus "@baseboard_fab2_lib.baseboard_fab2(sch_1):page213_i42" )
				( pin "R4D64.1"
					( objectStatus "a" )
				)
				( pin "R4D64.2"
					( objectStatus "b" )
				)
			)
			( gate "R4D51"
				( objectStatus "@baseboard_fab2_lib.baseboard_fab2(sch_1):page213_i46" )
				( pin "R4D51.1"
					( objectStatus "a" )
				)
				( pin "R4D51.2"
					( objectStatus "b" )
				)
			)
			( gate "R4D49"
				( objectStatus "@baseboard_fab2_lib.baseboard_fab2(sch_1):page213_i63" )
				( pin "R4D49.1"
					( objectStatus "a" )
				)
				( pin "R4D49.2"
					( objectStatus "b" )
				)
			)
			( gate "R4E2"
				( objectStatus "@baseboard_fab2_lib.baseboard_fab2(sch_1):page213_i65" )
				( pin "R4E2.1"
					( objectStatus "a" )
				)
				( pin "R4E2.2"
					( objectStatus "b" )
				)
			)
			( gate "C4D33"
				( objectStatus "@baseboard_fab2_lib.baseboard_fab2(sch_1):page213_i73" )
				( pin "C4D33.1"
					( objectStatus "a" )
				)
				( pin "C4D33.2"
					( objectStatus "b" )
				)
			)
			( gate "C4D44"
				( objectStatus "@baseboard_fab2_lib.baseboard_fab2(sch_1):page213_i83" )
				( pin "C4D44.1"
					( objectStatus "a" )
				)
				( pin "C4D44.2"
					( objectStatus "b" )
				)
			)
			( gate "R4E7"
				( objectStatus "@baseboard_fab2_lib.baseboard_fab2(sch_1):page213_i84" )
				( pin "R4E7.1"
					( objectStatus "a" )
				)
				( pin "R4E7.2"
					( objectStatus "b" )
				)
			)
			( gate "R6P41"
				( objectStatus "@baseboard_fab2_lib.baseboard_fab2(sch_1):page213_i90" )
				( pin "R6P41.1"
					( objectStatus "a" )
				)
				( pin "R6P41.2"
					( objectStatus "b" )
				)
			)
			( gate "R6P40"
				( objectStatus "@baseboard_fab2_lib.baseboard_fab2(sch_1):page213_i91" )
				( pin "R6P40.1"
					( objectStatus "a" )
				)
				( pin "R6P40.2"
					( objectStatus "b" )
				)
			)
			( gate "R4D45"
				( objectStatus "@baseboard_fab2_lib.baseboard_fab2(sch_1):page213_i94" )
				( pin "R4D45.1"
					( objectStatus "a" )
				)
				( pin "R4D45.2"
					( objectStatus "b" )
				)
			)
			( gate "EU4D5"
				( objectStatus "@baseboard_fab2_lib.baseboard_fab2(sch_1):page213_i96" )
				( pin "EU4D5.21"
					( objectStatus "airef1" )
				)
				( pin "EU4D5.22"
					( objectStatus "aisen1" )
				)
				( pin "EU4D5.5"
					( objectStatus "apwm1" )
				)
				( pin "EU4D5.35"
					( objectStatus "atsen" )
				)
				( pin "EU4D5.20"
					( objectStatus "avref" )
				)
				( pin "EU4D5.10"
					( objectStatus "avren" )
				)
				( pin "EU4D5.9"
					( objectStatus "avrrdy" )
				)
				( pin "EU4D5.19"
					( objectStatus "avsen" )
				)
				( pin "EU4D5.25"
					( objectStatus "biref1" )
				)
				( pin "EU4D5.26"
					( objectStatus "bisen1" )
				)
				( pin "EU4D5.3"
					( objectStatus "bpwm1" )
				)
				( pin "EU4D5.34"
					( objectStatus "btsen" )
				)
				( pin "EU4D5.30"
					( objectStatus "bvref" )
				)
				( pin "EU4D5.29"
					( objectStatus "bvsen" )
				)
				( pin "EU4D5.1"
					( objectStatus "dnc(0)" )
				)
				( pin "EU4D5.2"
					( objectStatus "dnc(1)" )
				)
				( pin "EU4D5.4"
					( objectStatus "dnc(2)" )
				)
				( pin "EU4D5.24"
					( objectStatus "dnc(3)" )
				)
				( pin "EU4D5.28"
					( objectStatus "dnc(4)" )
				)
				( pin "EU4D5.27"
					( objectStatus "gnd(0)" )
				)
				( pin "EU4D5.23"
					( objectStatus "gnd(1)" )
				)
				( pin "EU4D5.38"
					( objectStatus "iinsen" )
				)
				( pin "EU4D5.13"
					( objectStatus "mp0" )
				)
				( pin "EU4D5.14"
					( objectStatus "mp1" )
				)
				( pin "EU4D5.18"
					( objectStatus "mp2" )
				)
				( pin "EU4D5.31"
					( objectStatus "mp3" )
				)
				( pin "EU4D5.32"
					( objectStatus "mp4" )
				)
				( pin "EU4D5.12"
					( objectStatus "pinalrt_n" )
				)
				( pin "EU4D5.8"
					( objectStatus "reset_n" )
				)
				( pin "EU4D5.7"
					( objectStatus "scl" )
				)
				( pin "EU4D5.6"
					( objectStatus "sda" )
				)
				( pin "EU4D5.41"
					( objectStatus "thpad" )
				)
				( pin "EU4D5.17"
					( objectStatus "valrt_n" )
				)
				( pin "EU4D5.15"
					( objectStatus "vclk" )
				)
				( pin "EU4D5.40"
					( objectStatus "vd12" )
				)
				( pin "EU4D5.39"
					( objectStatus "vdd" )
				)
				( pin "EU4D5.16"
					( objectStatus "vdio" )
				)
				( pin "EU4D5.37"
					( objectStatus "vinsen" )
				)
				( pin "EU4D5.11"
					( objectStatus "vrhot_n" )
				)
				( pin "EU4D5.36"
					( objectStatus "xaddr1" )
				)
				( pin "EU4D5.33"
					( objectStatus "xaddr2" )
				)
			)
			( gate "C4E9"
				( objectStatus "@baseboard_fab2_lib.baseboard_fab2(sch_1):page214_i8" )
				( pin "C4E9.1"
					( objectStatus "a" )
				)
				( pin "C4E9.2"
					( objectStatus "b" )
				)
			)
			( gate "C4E7"
				( objectStatus "@baseboard_fab2_lib.baseboard_fab2(sch_1):page214_i20" )
				( pin "C4E7.1"
					( objectStatus "a" )
				)
				( pin "C4E7.2"
					( objectStatus "b" )
				)
			)
			( gate "C6R12"
				( objectStatus "@baseboard_fab2_lib.baseboard_fab2(sch_1):page214_i21" )
				( pin "C6R12.1"
					( objectStatus "a" )
				)
				( pin "C6R12.2"
					( objectStatus "b" )
				)
			)
			( gate "C6R5"
				( objectStatus "@baseboard_fab2_lib.baseboard_fab2(sch_1):page214_i24" )
				( pin "C6R5.1"
					( objectStatus "a" )
				)
				( pin "C6R5.2"
					( objectStatus "b" )
				)
			)
			( gate "C4E8"
				( objectStatus "@baseboard_fab2_lib.baseboard_fab2(sch_1):page214_i29" )
				( pin "C4E8.1"
					( objectStatus "a" )
				)
				( pin "C4E8.2"
					( objectStatus "b" )
				)
			)
			( gate "C4E14"
				( objectStatus "@baseboard_fab2_lib.baseboard_fab2(sch_1):page214_i31" )
				( pin "C4E14.1"
					( objectStatus "a" )
				)
				( pin "C4E14.2"
					( objectStatus "b" )
				)
			)
			( gate "C7R1"
				( objectStatus "@baseboard_fab2_lib.baseboard_fab2(sch_1):page214_i65" )
				( pin "C7R1.1"
					( objectStatus "a" )
				)
				( pin "C7R1.2"
					( objectStatus "b" )
				)
			)
			( gate "L4E2"
				( objectStatus "@baseboard_fab2_lib.baseboard_fab2(sch_1):page214_i67" )
				( pin "L4E2.1"
					( objectStatus "ina" )
				)
				( pin "L4E2.2"
					( objectStatus "inb" )
				)
			)
			( gate "R6R5"
				( objectStatus "@baseboard_fab2_lib.baseboard_fab2(sch_1):page214_i71" )
				( pin "R6R5.1"
					( objectStatus "a" )
				)
				( pin "R6R5.2"
					( objectStatus "b" )
				)
			)
			( gate "C4E23"
				( objectStatus "@baseboard_fab2_lib.baseboard_fab2(sch_1):page214_i73" )
				( pin "C4E23.1"
					( objectStatus "a" )
				)
				( pin "C4E23.2"
					( objectStatus "b" )
				)
			)
			( gate "C6R15"
				( objectStatus "@baseboard_fab2_lib.baseboard_fab2(sch_1):page214_i74" )
				( pin "C6R15.1"
					( objectStatus "a" )
				)
				( pin "C6R15.2"
					( objectStatus "b" )
				)
			)
			( gate "C4E22"
				( objectStatus "@baseboard_fab2_lib.baseboard_fab2(sch_1):page214_i76" )
				( pin "C4E22.1"
					( objectStatus "a" )
				)
				( pin "C4E22.2"
					( objectStatus "b" )
				)
			)
			( gate "C4E13"
				( objectStatus "@baseboard_fab2_lib.baseboard_fab2(sch_1):page214_i77" )
				( pin "C4E13.1"
					( objectStatus "a" )
				)
				( pin "C4E13.2"
					( objectStatus "b" )
				)
			)
			( gate "C4E18"
				( objectStatus "@baseboard_fab2_lib.baseboard_fab2(sch_1):page214_i78" )
				( pin "C4E18.1"
					( objectStatus "a" )
				)
				( pin "C4E18.2"
					( objectStatus "b" )
				)
			)
			( gate "C4E15"
				( objectStatus "@baseboard_fab2_lib.baseboard_fab2(sch_1):page214_i79" )
				( pin "C4E15.1"
					( objectStatus "a" )
				)
				( pin "C4E15.2"
					( objectStatus "b" )
				)
			)
			( gate "C6R14"
				( objectStatus "@baseboard_fab2_lib.baseboard_fab2(sch_1):page214_i80" )
				( pin "C6R14.1"
					( objectStatus "a" )
				)
				( pin "C6R14.2"
					( objectStatus "b" )
				)
			)
			( gate "C6R10"
				( objectStatus "@baseboard_fab2_lib.baseboard_fab2(sch_1):page214_i81" )
				( pin "C6R10.1"
					( objectStatus "a" )
				)
				( pin "C6R10.2"
					( objectStatus "b" )
				)
			)
			( gate "C6R8"
				( objectStatus "@baseboard_fab2_lib.baseboard_fab2(sch_1):page214_i83" )
				( pin "C6R8.1"
					( objectStatus "a" )
				)
				( pin "C6R8.2"
					( objectStatus "b" )
				)
			)
			( gate "C3D27"
				( objectStatus "@baseboard_fab2_lib.baseboard_fab2(sch_1):page214_i96" )
				( pin "C3D27.1"
					( objectStatus "a" )
				)
				( pin "C3D27.2"
					( objectStatus "b" )
				)
			)
			( gate "R3D29"
				( objectStatus "@baseboard_fab2_lib.baseboard_fab2(sch_1):page214_i99" )
				( pin "R3D29.1"
					( objectStatus "a" )
				)
				( pin "R3D29.2"
					( objectStatus "b" )
				)
			)
			( gate "R3D28"
				( objectStatus "@baseboard_fab2_lib.baseboard_fab2(sch_1):page214_i101" )
				( pin "R3D28.1"
					( objectStatus "a" )
				)
				( pin "R3D28.2"
					( objectStatus "b" )
				)
			)
			( gate "R3D30"
				( objectStatus "@baseboard_fab2_lib.baseboard_fab2(sch_1):page214_i104" )
				( pin "R3D30.1"
					( objectStatus "a" )
				)
				( pin "R3D30.2"
					( objectStatus "b" )
				)
			)
			( gate "R3E1"
				( objectStatus "@baseboard_fab2_lib.baseboard_fab2(sch_1):page214_i105" )
				( pin "R3E1.1"
					( objectStatus "a" )
				)
				( pin "R3E1.2"
					( objectStatus "b" )
				)
			)
			( gate "C3E1"
				( objectStatus "@baseboard_fab2_lib.baseboard_fab2(sch_1):page214_i108" )
				( pin "C3E1.1"
					( objectStatus "a" )
				)
				( pin "C3E1.2"
					( objectStatus "b" )
				)
			)
			( gate "R7R1"
				( objectStatus "@baseboard_fab2_lib.baseboard_fab2(sch_1):page214_i109" )
				( pin "R7R1.1"
					( objectStatus "a" )
				)
				( pin "R7R1.2"
					( objectStatus "b" )
				)
			)
			( gate "EU4E2"
				( objectStatus "@baseboard_fab2_lib.baseboard_fab2(sch_1):page214_i126" )
				( pin "EU4E2.33"
					( objectStatus "boost" )
				)
				( pin "EU4E2.35"
					( objectStatus "en" )
				)
				( pin "EU4E2.6"
					( objectStatus "gl(0)" )
				)
				( pin "EU4E2.41"
					( objectStatus "gl(1)" )
				)
				( pin "EU4E2.38"
					( objectStatus "iout" )
				)
				( pin "EU4E2.2"
					( objectStatus "lgnd" )
				)
				( pin "EU4E2.31"
					( objectStatus "nc" )
				)
				( pin "EU4E2.37"
					( objectStatus "ocset" )
				)
				( pin "EU4E2.5"
					( objectStatus "pgnd(0)" )
				)
				( pin "EU4E2.7"
					( objectStatus "pgnd(1)" )
				)
				( pin "EU4E2.40"
					( objectStatus "pgnd(2)" )
				)
				( pin "EU4E2.32"
					( objectStatus "phase" )
				)
				( pin "EU4E2.34"
					( objectStatus "pwm" )
				)
				( pin "EU4E2.39"
					( objectStatus "refin" )
				)
				( pin "EU4E2.10"
					( objectStatus "sw" )
				)
				( pin "EU4E2.36"
					( objectStatus "tout_flt" )
				)
				( pin "EU4E2.3"
					( objectStatus "vcc" )
				)
				( pin "EU4E2.4"
					( objectStatus "vdrv" )
				)
				( pin "EU4E2.25"
					( objectStatus "vin(0)" )
				)
				( pin "EU4E2.30"
					( objectStatus "vin(1)" )
				)
				( pin "EU4E2.1"
					( objectStatus "vos" )
				)
			)
			( gate "R36"
				( objectStatus "@baseboard_fab2_lib.baseboard_fab2(sch_1):page214_i127" )
				( pin "R36.1"
					( objectStatus "a" )
				)
				( pin "R36.2"
					( objectStatus "b" )
				)
			)
			( gate "R3U2"
				( objectStatus "@baseboard_fab2_lib.baseboard_fab2(sch_1):page215_i295" )
				( pin "R3U2.1"
					( objectStatus "a" )
				)
				( pin "R3U2.2"
					( objectStatus "b" )
				)
			)
			( gate "R7F24"
				( objectStatus "@baseboard_fab2_lib.baseboard_fab2(sch_1):page215_i296" )
				( pin "R7F24.1"
					( objectStatus "a" )
				)
				( pin "R7F24.2"
					( objectStatus "b" )
				)
			)
			( gate "R7F23"
				( objectStatus "@baseboard_fab2_lib.baseboard_fab2(sch_1):page215_i297" )
				( pin "R7F23.1"
					( objectStatus "a" )
				)
				( pin "R7F23.2"
					( objectStatus "b" )
				)
			)
			( gate "R7F25"
				( objectStatus "@baseboard_fab2_lib.baseboard_fab2(sch_1):page215_i298" )
				( pin "R7F25.1"
					( objectStatus "a" )
				)
				( pin "R7F25.2"
					( objectStatus "b" )
				)
			)
			( gate "R7G6"
				( objectStatus "@baseboard_fab2_lib.baseboard_fab2(sch_1):page215_i300" )
				( pin "R7G6.1"
					( objectStatus "a" )
				)
				( pin "R7G6.2"
					( objectStatus "b" )
				)
			)
			( gate "R7F22"
				( objectStatus "@baseboard_fab2_lib.baseboard_fab2(sch_1):page215_i301" )
				( pin "R7F22.1"
					( objectStatus "a" )
				)
				( pin "R7F22.2"
					( objectStatus "b" )
				)
			)
			( gate "R7G4"
				( objectStatus "@baseboard_fab2_lib.baseboard_fab2(sch_1):page215_i302" )
				( pin "R7G4.1"
					( objectStatus "a" )
				)
				( pin "R7G4.2"
					( objectStatus "b" )
				)
			)
			( gate "R7F27"
				( objectStatus "@baseboard_fab2_lib.baseboard_fab2(sch_1):page215_i303" )
				( pin "R7F27.1"
					( objectStatus "a" )
				)
				( pin "R7F27.2"
					( objectStatus "b" )
				)
			)
			( gate "R7F26"
				( objectStatus "@baseboard_fab2_lib.baseboard_fab2(sch_1):page215_i304" )
				( pin "R7F26.1"
					( objectStatus "a" )
				)
				( pin "R7F26.2"
					( objectStatus "b" )
				)
			)
			( gate "C7F14"
				( objectStatus "@baseboard_fab2_lib.baseboard_fab2(sch_1):page215_i305" )
				( pin "C7F14.1"
					( objectStatus "a" )
				)
				( pin "C7F14.2"
					( objectStatus "b" )
				)
			)
			( gate "R7G2"
				( objectStatus "@baseboard_fab2_lib.baseboard_fab2(sch_1):page215_i307" )
				( pin "R7G2.1"
					( objectStatus "a" )
				)
				( pin "R7G2.2"
					( objectStatus "b" )
				)
			)
			( gate "C7F18"
				( objectStatus "@baseboard_fab2_lib.baseboard_fab2(sch_1):page215_i309" )
				( pin "C7F18.1"
					( objectStatus "a" )
				)
				( pin "C7F18.2"
					( objectStatus "b" )
				)
			)
			( gate "C7F17"
				( objectStatus "@baseboard_fab2_lib.baseboard_fab2(sch_1):page215_i311" )
				( pin "C7F17.1"
					( objectStatus "a" )
				)
				( pin "C7F17.2"
					( objectStatus "b" )
				)
			)
			( gate "R3T13"
				( objectStatus "@baseboard_fab2_lib.baseboard_fab2(sch_1):page215_i313" )
				( pin "R3T13.1"
					( objectStatus "a" )
				)
				( pin "R3T13.2"
					( objectStatus "b" )
				)
			)
			( gate "R7F20"
				( objectStatus "@baseboard_fab2_lib.baseboard_fab2(sch_1):page215_i315" )
				( pin "R7F20.1"
					( objectStatus "a" )
				)
				( pin "R7F20.2"
					( objectStatus "b" )
				)
			)
			( gate "R7G10"
				( objectStatus "@baseboard_fab2_lib.baseboard_fab2(sch_1):page215_i317" )
				( pin "R7G10.1"
					( objectStatus "a" )
				)
				( pin "R7G10.2"
					( objectStatus "b" )
				)
			)
			( gate "C7G3"
				( objectStatus "@baseboard_fab2_lib.baseboard_fab2(sch_1):page215_i320" )
				( pin "C7G3.1"
					( objectStatus "a" )
				)
				( pin "C7G3.2"
					( objectStatus "b" )
				)
			)
			( gate "R7G8"
				( objectStatus "@baseboard_fab2_lib.baseboard_fab2(sch_1):page215_i321" )
				( pin "R7G8.1"
					( objectStatus "a" )
				)
				( pin "R7G8.2"
					( objectStatus "b" )
				)
			)
			( gate "C7F16"
				( objectStatus "@baseboard_fab2_lib.baseboard_fab2(sch_1):page215_i325" )
				( pin "C7F16.1"
					( objectStatus "a" )
				)
				( pin "C7F16.2"
					( objectStatus "b" )
				)
			)
			( gate "C7F15"
				( objectStatus "@baseboard_fab2_lib.baseboard_fab2(sch_1):page215_i327" )
				( pin "C7F15.1"
					( objectStatus "a" )
				)
				( pin "C7F15.2"
					( objectStatus "b" )
				)
			)
			( gate "R3T11"
				( objectStatus "@baseboard_fab2_lib.baseboard_fab2(sch_1):page215_i330" )
				( pin "R3T11.1"
					( objectStatus "a" )
				)
				( pin "R3T11.2"
					( objectStatus "b" )
				)
			)
			( gate "R7F31"
				( objectStatus "@baseboard_fab2_lib.baseboard_fab2(sch_1):page215_i331" )
				( pin "R7F31.1"
					( objectStatus "a" )
				)
				( pin "R7F31.2"
					( objectStatus "b" )
				)
			)
			( gate "R3U3"
				( objectStatus "@baseboard_fab2_lib.baseboard_fab2(sch_1):page215_i332" )
				( pin "R3U3.1"
					( objectStatus "a" )
				)
				( pin "R3U3.2"
					( objectStatus "b" )
				)
			)
			( gate "R7F34"
				( objectStatus "@baseboard_fab2_lib.baseboard_fab2(sch_1):page215_i336" )
				( pin "R7F34.1"
					( objectStatus "a" )
				)
				( pin "R7F34.2"
					( objectStatus "b" )
				)
			)
			( gate "R7G3"
				( objectStatus "@baseboard_fab2_lib.baseboard_fab2(sch_1):page215_i337" )
				( pin "R7G3.1"
					( objectStatus "a" )
				)
				( pin "R7G3.2"
					( objectStatus "b" )
				)
			)
			( gate "C7G1"
				( objectStatus "@baseboard_fab2_lib.baseboard_fab2(sch_1):page215_i339" )
				( pin "C7G1.1"
					( objectStatus "a" )
				)
				( pin "C7G1.2"
					( objectStatus "b" )
				)
			)
			( gate "R3T7"
				( objectStatus "@baseboard_fab2_lib.baseboard_fab2(sch_1):page215_i341" )
				( pin "R3T7.1"
					( objectStatus "a" )
				)
				( pin "R3T7.2"
					( objectStatus "b" )
				)
			)
			( gate "C7G4"
				( objectStatus "@baseboard_fab2_lib.baseboard_fab2(sch_1):page215_i342" )
				( pin "C7G4.1"
					( objectStatus "a" )
				)
				( pin "C7G4.2"
					( objectStatus "b" )
				)
			)
			( gate "R7F21"
				( objectStatus "@baseboard_fab2_lib.baseboard_fab2(sch_1):page215_i343" )
				( pin "R7F21.1"
					( objectStatus "a" )
				)
				( pin "R7F21.2"
					( objectStatus "b" )
				)
			)
			( gate "R7G9"
				( objectStatus "@baseboard_fab2_lib.baseboard_fab2(sch_1):page215_i344" )
				( pin "R7G9.1"
					( objectStatus "a" )
				)
				( pin "R7G9.2"
					( objectStatus "b" )
				)
			)
			( gate "EU7G1"
				( objectStatus "@baseboard_fab2_lib.baseboard_fab2(sch_1):page215_i358" )
				( pin "EU7G1.21"
					( objectStatus "airef1" )
				)
				( pin "EU7G1.23"
					( objectStatus "airef2" )
				)
				( pin "EU7G1.25"
					( objectStatus "airef3" )
				)
				( pin "EU7G1.22"
					( objectStatus "aisen1" )
				)
				( pin "EU7G1.24"
					( objectStatus "aisen2" )
				)
				( pin "EU7G1.26"
					( objectStatus "aisen3" )
				)
				( pin "EU7G1.5"
					( objectStatus "apwm1" )
				)
				( pin "EU7G1.4"
					( objectStatus "apwm2" )
				)
				( pin "EU7G1.3"
					( objectStatus "apwm3" )
				)
				( pin "EU7G1.35"
					( objectStatus "atsen" )
				)
				( pin "EU7G1.20"
					( objectStatus "avref" )
				)
				( pin "EU7G1.10"
					( objectStatus "avren" )
				)
				( pin "EU7G1.9"
					( objectStatus "avrrdy" )
				)
				( pin "EU7G1.19"
					( objectStatus "avsen" )
				)
				( pin "EU7G1.31"
					( objectStatus "biref1" )
				)
				( pin "EU7G1.32"
					( objectStatus "bisen1" )
				)
				( pin "EU7G1.1"
					( objectStatus "bpwm1" )
				)
				( pin "EU7G1.34"
					( objectStatus "btsen" )
				)
				( pin "EU7G1.30"
					( objectStatus "bvref" )
				)
				( pin "EU7G1.29"
					( objectStatus "bvsen" )
				)
				( pin "EU7G1.2"
					( objectStatus "dnc(0)" )
				)
				( pin "EU7G1.28"
					( objectStatus "dnc(1)" )
				)
				( pin "EU7G1.27"
					( objectStatus "gnd" )
				)
				( pin "EU7G1.38"
					( objectStatus "iinsen" )
				)
				( pin "EU7G1.13"
					( objectStatus "mp0" )
				)
				( pin "EU7G1.14"
					( objectStatus "mp1" )
				)
				( pin "EU7G1.18"
					( objectStatus "mp2" )
				)
				( pin "EU7G1.12"
					( objectStatus "pinalrt_n" )
				)
				( pin "EU7G1.8"
					( objectStatus "reset_n" )
				)
				( pin "EU7G1.7"
					( objectStatus "scl" )
				)
				( pin "EU7G1.6"
					( objectStatus "sda" )
				)
				( pin "EU7G1.41"
					( objectStatus "thpad" )
				)
				( pin "EU7G1.17"
					( objectStatus "valrt_n" )
				)
				( pin "EU7G1.15"
					( objectStatus "vclk" )
				)
				( pin "EU7G1.40"
					( objectStatus "vd12" )
				)
				( pin "EU7G1.39"
					( objectStatus "vdd" )
				)
				( pin "EU7G1.16"
					( objectStatus "vdio" )
				)
				( pin "EU7G1.37"
					( objectStatus "vinsen" )
				)
				( pin "EU7G1.11"
					( objectStatus "vrhot_n" )
				)
				( pin "EU7G1.36"
					( objectStatus "xaddr1" )
				)
				( pin "EU7G1.33"
					( objectStatus "xaddr2" )
				)
			)
			( gate "C4F8"
				( objectStatus "@baseboard_fab2_lib.baseboard_fab2(sch_1):page215_i360" )
				( pin "C4F8.1"
					( objectStatus "a" )
				)
				( pin "C4F8.2"
					( objectStatus "b" )
				)
			)
			( gate "C6G3"
				( objectStatus "@baseboard_fab2_lib.baseboard_fab2(sch_1):page216_i6" )
				( pin "C6G3.1"
					( objectStatus "a" )
				)
				( pin "C6G3.2"
					( objectStatus "b" )
				)
			)
			( gate "C7G31"
				( objectStatus "@baseboard_fab2_lib.baseboard_fab2(sch_1):page216_i44" )
				( pin "C7G31.1"
					( objectStatus "a" )
				)
				( pin "C7G31.2"
					( objectStatus "b" )
				)
			)
			( gate "C3U2"
				( objectStatus "@baseboard_fab2_lib.baseboard_fab2(sch_1):page216_i45" )
				( pin "C3U2.1"
					( objectStatus "a" )
				)
				( pin "C3U2.2"
					( objectStatus "b" )
				)
			)
			( gate "C3U3"
				( objectStatus "@baseboard_fab2_lib.baseboard_fab2(sch_1):page216_i46" )
				( pin "C3U3.1"
					( objectStatus "a" )
				)
				( pin "C3U3.2"
					( objectStatus "b" )
				)
			)
			( gate "C3U4"
				( objectStatus "@baseboard_fab2_lib.baseboard_fab2(sch_1):page216_i47" )
				( pin "C3U4.1"
					( objectStatus "a" )
				)
				( pin "C3U4.2"
					( objectStatus "b" )
				)
			)
			( gate "C7G37"
				( objectStatus "@baseboard_fab2_lib.baseboard_fab2(sch_1):page216_i48" )
				( pin "C7G37.1"
					( objectStatus "a" )
				)
				( pin "C7G37.2"
					( objectStatus "b" )
				)
			)
			( gate "C7G33"
				( objectStatus "@baseboard_fab2_lib.baseboard_fab2(sch_1):page216_i50" )
				( pin "C7G33.1"
					( objectStatus "a" )
				)
				( pin "C7G33.2"
					( objectStatus "b" )
				)
			)
			( gate "C7G29"
				( objectStatus "@baseboard_fab2_lib.baseboard_fab2(sch_1):page216_i51" )
				( pin "C7G29.1"
					( objectStatus "a" )
				)
				( pin "C7G29.2"
					( objectStatus "b" )
				)
			)
			( gate "R3U6"
				( objectStatus "@baseboard_fab2_lib.baseboard_fab2(sch_1):page216_i52" )
				( pin "R3U6.1"
					( objectStatus "a" )
				)
				( pin "R3U6.2"
					( objectStatus "b" )
				)
			)
			( gate "C7G35"
				( objectStatus "@baseboard_fab2_lib.baseboard_fab2(sch_1):page216_i53" )
				( pin "C7G35.1"
					( objectStatus "a" )
				)
				( pin "C7G35.2"
					( objectStatus "b" )
				)
			)
			( gate "C7G34"
				( objectStatus "@baseboard_fab2_lib.baseboard_fab2(sch_1):page216_i54" )
				( pin "C7G34.1"
					( objectStatus "a" )
				)
				( pin "C7G34.2"
					( objectStatus "b" )
				)
			)
			( gate "L7G1"
				( objectStatus "@baseboard_fab2_lib.baseboard_fab2(sch_1):page216_i55" )
				( pin "L7G1.1"
					( objectStatus "ina" )
				)
				( pin "L7G1.2"
					( objectStatus "inb" )
				)
			)
			( gate "L7G2"
				( objectStatus "@baseboard_fab2_lib.baseboard_fab2(sch_1):page216_i65" )
				( pin "L7G2.1"
					( objectStatus "ina" )
				)
				( pin "L7G2.2"
					( objectStatus "inb" )
				)
			)
			( gate "C7G27"
				( objectStatus "@baseboard_fab2_lib.baseboard_fab2(sch_1):page216_i68" )
				( pin "C7G27.1"
					( objectStatus "a" )
				)
				( pin "C7G27.2"
					( objectStatus "b" )
				)
			)
			( gate "C7G41"
				( objectStatus "@baseboard_fab2_lib.baseboard_fab2(sch_1):page216_i72" )
				( pin "C7G41.1"
					( objectStatus "a" )
				)
				( pin "C7G41.2"
					( objectStatus "b" )
				)
			)
			( gate "C7G42"
				( objectStatus "@baseboard_fab2_lib.baseboard_fab2(sch_1):page216_i73" )
				( pin "C7G42.1"
					( objectStatus "a" )
				)
				( pin "C7G42.2"
					( objectStatus "b" )
				)
			)
			( gate "C7G38"
				( objectStatus "@baseboard_fab2_lib.baseboard_fab2(sch_1):page216_i75" )
				( pin "C7G38.1"
					( objectStatus "a" )
				)
				( pin "C7G38.2"
					( objectStatus "b" )
				)
			)
			( gate "R3U9"
				( objectStatus "@baseboard_fab2_lib.baseboard_fab2(sch_1):page216_i76" )
				( pin "R3U9.1"
					( objectStatus "a" )
				)
				( pin "R3U9.2"
					( objectStatus "b" )
				)
			)
			( gate "C7G40"
				( objectStatus "@baseboard_fab2_lib.baseboard_fab2(sch_1):page216_i77" )
				( pin "C7G40.1"
					( objectStatus "a" )
				)
				( pin "C7G40.2"
					( objectStatus "b" )
				)
			)
			( gate "C7G36"
				( objectStatus "@baseboard_fab2_lib.baseboard_fab2(sch_1):page216_i78" )
				( pin "C7G36.1"
					( objectStatus "a" )
				)
				( pin "C7G36.2"
					( objectStatus "b" )
				)
			)
			( gate "C7G30"
				( objectStatus "@baseboard_fab2_lib.baseboard_fab2(sch_1):page216_i79" )
				( pin "C7G30.1"
					( objectStatus "a" )
				)
				( pin "C7G30.2"
					( objectStatus "b" )
				)
			)
			( gate "C3U9"
				( objectStatus "@baseboard_fab2_lib.baseboard_fab2(sch_1):page216_i80" )
				( pin "C3U9.1"
					( objectStatus "a" )
				)
				( pin "C3U9.2"
					( objectStatus "b" )
				)
			)
			( gate "C3U7"
				( objectStatus "@baseboard_fab2_lib.baseboard_fab2(sch_1):page216_i81" )
				( pin "C3U7.1"
					( objectStatus "a" )
				)
				( pin "C3U7.2"
					( objectStatus "b" )
				)
			)
			( gate "C3U6"
				( objectStatus "@baseboard_fab2_lib.baseboard_fab2(sch_1):page216_i84" )
				( pin "C3U6.1"
					( objectStatus "a" )
				)
				( pin "C3U6.2"
					( objectStatus "b" )
				)
			)
			( gate "EU7G2"
				( objectStatus "@baseboard_fab2_lib.baseboard_fab2(sch_1):page216_i102" )
				( pin "EU7G2.33"
					( objectStatus "boost" )
				)
				( pin "EU7G2.35"
					( objectStatus "en" )
				)
				( pin "EU7G2.6"
					( objectStatus "gl(0)" )
				)
				( pin "EU7G2.41"
					( objectStatus "gl(1)" )
				)
				( pin "EU7G2.38"
					( objectStatus "iout" )
				)
				( pin "EU7G2.2"
					( objectStatus "lgnd" )
				)
				( pin "EU7G2.31"
					( objectStatus "nc" )
				)
				( pin "EU7G2.37"
					( objectStatus "ocset" )
				)
				( pin "EU7G2.5"
					( objectStatus "pgnd(0)" )
				)
				( pin "EU7G2.7"
					( objectStatus "pgnd(1)" )
				)
				( pin "EU7G2.40"
					( objectStatus "pgnd(2)" )
				)
				( pin "EU7G2.32"
					( objectStatus "phase" )
				)
				( pin "EU7G2.34"
					( objectStatus "pwm" )
				)
				( pin "EU7G2.39"
					( objectStatus "refin" )
				)
				( pin "EU7G2.10"
					( objectStatus "sw" )
				)
				( pin "EU7G2.36"
					( objectStatus "tout_flt" )
				)
				( pin "EU7G2.3"
					( objectStatus "vcc" )
				)
				( pin "EU7G2.4"
					( objectStatus "vdrv" )
				)
				( pin "EU7G2.25"
					( objectStatus "vin(0)" )
				)
				( pin "EU7G2.30"
					( objectStatus "vin(1)" )
				)
				( pin "EU7G2.1"
					( objectStatus "vos" )
				)
			)
			( gate "EU7G3"
				( objectStatus "@baseboard_fab2_lib.baseboard_fab2(sch_1):page216_i103" )
				( pin "EU7G3.33"
					( objectStatus "boost" )
				)
				( pin "EU7G3.35"
					( objectStatus "en" )
				)
				( pin "EU7G3.6"
					( objectStatus "gl(0)" )
				)
				( pin "EU7G3.41"
					( objectStatus "gl(1)" )
				)
				( pin "EU7G3.38"
					( objectStatus "iout" )
				)
				( pin "EU7G3.2"
					( objectStatus "lgnd" )
				)
				( pin "EU7G3.31"
					( objectStatus "nc" )
				)
				( pin "EU7G3.37"
					( objectStatus "ocset" )
				)
				( pin "EU7G3.5"
					( objectStatus "pgnd(0)" )
				)
				( pin "EU7G3.7"
					( objectStatus "pgnd(1)" )
				)
				( pin "EU7G3.40"
					( objectStatus "pgnd(2)" )
				)
				( pin "EU7G3.32"
					( objectStatus "phase" )
				)
				( pin "EU7G3.34"
					( objectStatus "pwm" )
				)
				( pin "EU7G3.39"
					( objectStatus "refin" )
				)
				( pin "EU7G3.10"
					( objectStatus "sw" )
				)
				( pin "EU7G3.36"
					( objectStatus "tout_flt" )
				)
				( pin "EU7G3.3"
					( objectStatus "vcc" )
				)
				( pin "EU7G3.4"
					( objectStatus "vdrv" )
				)
				( pin "EU7G3.25"
					( objectStatus "vin(0)" )
				)
				( pin "EU7G3.30"
					( objectStatus "vin(1)" )
				)
				( pin "EU7G3.1"
					( objectStatus "vos" )
				)
			)
			( gate "R37"
				( objectStatus "@baseboard_fab2_lib.baseboard_fab2(sch_1):page216_i104" )
				( pin "R37.1"
					( objectStatus "a" )
				)
				( pin "R37.2"
					( objectStatus "b" )
				)
			)
			( gate "R38"
				( objectStatus "@baseboard_fab2_lib.baseboard_fab2(sch_1):page216_i106" )
				( pin "R38.1"
					( objectStatus "a" )
				)
				( pin "R38.2"
					( objectStatus "b" )
				)
			)
			( gate "R3U4"
				( objectStatus "@baseboard_fab2_lib.baseboard_fab2(sch_1):page217_i58" )
				( pin "R3U4.1"
					( objectStatus "a" )
				)
				( pin "R3U4.2"
					( objectStatus "b" )
				)
			)
			( gate "R4U5"
				( objectStatus "@baseboard_fab2_lib.baseboard_fab2(sch_1):page217_i67" )
				( pin "R4U5.1"
					( objectStatus "a" )
				)
				( pin "R4U5.2"
					( objectStatus "b" )
				)
			)
			( gate "R4U7"
				( objectStatus "@baseboard_fab2_lib.baseboard_fab2(sch_1):page217_i71" )
				( pin "R4U7.1"
					( objectStatus "a" )
				)
				( pin "R4U7.2"
					( objectStatus "b" )
				)
			)
			( gate "R4U6"
				( objectStatus "@baseboard_fab2_lib.baseboard_fab2(sch_1):page217_i74" )
				( pin "R4U6.1"
					( objectStatus "a" )
				)
				( pin "R4U6.2"
					( objectStatus "b" )
				)
			)
			( gate "C7G28"
				( objectStatus "@baseboard_fab2_lib.baseboard_fab2(sch_1):page217_i75" )
				( pin "C7G28.1"
					( objectStatus "a" )
				)
				( pin "C7G28.2"
					( objectStatus "b" )
				)
			)
			( gate "C3U1"
				( objectStatus "@baseboard_fab2_lib.baseboard_fab2(sch_1):page217_i76" )
				( pin "C3U1.1"
					( objectStatus "a" )
				)
				( pin "C3U1.2"
					( objectStatus "b" )
				)
			)
			( gate "C3U5"
				( objectStatus "@baseboard_fab2_lib.baseboard_fab2(sch_1):page217_i77" )
				( pin "C3U5.1"
					( objectStatus "a" )
				)
				( pin "C3U5.2"
					( objectStatus "b" )
				)
			)
			( gate "C3U8"
				( objectStatus "@baseboard_fab2_lib.baseboard_fab2(sch_1):page217_i78" )
				( pin "C3U8.1"
					( objectStatus "a" )
				)
				( pin "C3U8.2"
					( objectStatus "b" )
				)
			)
			( gate "C5U13"
				( objectStatus "@baseboard_fab2_lib.baseboard_fab2(sch_1):page217_i82" )
				( pin "C5U13.1"
					( objectStatus "a" )
				)
				( pin "C5U13.2"
					( objectStatus "b" )
				)
			)
			( gate "C5U10"
				( objectStatus "@baseboard_fab2_lib.baseboard_fab2(sch_1):page217_i83" )
				( pin "C5U10.1"
					( objectStatus "a" )
				)
				( pin "C5U10.2"
					( objectStatus "b" )
				)
			)
			( gate "C5U1"
				( objectStatus "@baseboard_fab2_lib.baseboard_fab2(sch_1):page217_i88" )
				( pin "C5U1.1"
					( objectStatus "a" )
				)
				( pin "C5U1.2"
					( objectStatus "b" )
				)
			)
			( gate "C5U14"
				( objectStatus "@baseboard_fab2_lib.baseboard_fab2(sch_1):page217_i89" )
				( pin "C5U14.1"
					( objectStatus "a" )
				)
				( pin "C5U14.2"
					( objectStatus "b" )
				)
			)
			( gate "C5U15"
				( objectStatus "@baseboard_fab2_lib.baseboard_fab2(sch_1):page217_i90" )
				( pin "C5U15.1"
					( objectStatus "a" )
				)
				( pin "C5U15.2"
					( objectStatus "b" )
				)
			)
			( gate "C4T4"
				( objectStatus "@baseboard_fab2_lib.baseboard_fab2(sch_1):page217_i91" )
				( pin "C4T4.1"
					( objectStatus "a" )
				)
				( pin "C4T4.2"
					( objectStatus "b" )
				)
			)
			( gate "C5G9"
				( objectStatus "@baseboard_fab2_lib.baseboard_fab2(sch_1):page217_i92" )
				( pin "C5G9.1"
					( objectStatus "a" )
				)
				( pin "C5G9.2"
					( objectStatus "b" )
				)
			)
			( gate "C5G20"
				( objectStatus "@baseboard_fab2_lib.baseboard_fab2(sch_1):page217_i110" )
				( pin "C5G20.1"
					( objectStatus "a" )
				)
				( pin "C5G20.2"
					( objectStatus "b" )
				)
			)
			( gate "L7F2"
				( objectStatus "@baseboard_fab2_lib.baseboard_fab2(sch_1):page217_i124" )
				( pin "L7F2.1"
					( objectStatus "ina" )
				)
				( pin "L7F2.2"
					( objectStatus "inb" )
				)
			)
			( gate "C7G2"
				( objectStatus "@baseboard_fab2_lib.baseboard_fab2(sch_1):page217_i175" )
				( pin "C7G2.1"
					( objectStatus "a" )
				)
				( pin "C7G2.2"
					( objectStatus "b" )
				)
			)
			( gate "C5P39"
				( objectStatus "@baseboard_fab2_lib.baseboard_fab2(sch_1):page217_i184" )
				( pin "C5P39.1"
					( objectStatus "a" )
				)
				( pin "C5P39.2"
					( objectStatus "b" )
				)
			)
			( gate "C5D57"
				( objectStatus "@baseboard_fab2_lib.baseboard_fab2(sch_1):page217_i186" )
				( pin "C5D57.1"
					( objectStatus "a" )
				)
				( pin "C5D57.2"
					( objectStatus "b" )
				)
			)
			( gate "C5D56"
				( objectStatus "@baseboard_fab2_lib.baseboard_fab2(sch_1):page217_i188" )
				( pin "C5D56.1"
					( objectStatus "a" )
				)
				( pin "C5D56.2"
					( objectStatus "b" )
				)
			)
			( gate "C5D55"
				( objectStatus "@baseboard_fab2_lib.baseboard_fab2(sch_1):page217_i189" )
				( pin "C5D55.1"
					( objectStatus "a" )
				)
				( pin "C5D55.2"
					( objectStatus "b" )
				)
			)
			( gate "C5D54"
				( objectStatus "@baseboard_fab2_lib.baseboard_fab2(sch_1):page217_i190" )
				( pin "C5D54.1"
					( objectStatus "a" )
				)
				( pin "C5D54.2"
					( objectStatus "b" )
				)
			)
			( gate "C5P38"
				( objectStatus "@baseboard_fab2_lib.baseboard_fab2(sch_1):page217_i193" )
				( pin "C5P38.1"
					( objectStatus "a" )
				)
				( pin "C5P38.2"
					( objectStatus "b" )
				)
			)
			( gate "C5F2"
				( objectStatus "@baseboard_fab2_lib.baseboard_fab2(sch_1):page217_i205" )
				( pin "C5F2.1"
					( objectStatus "a" )
				)
				( pin "C5F2.2"
					( objectStatus "b" )
				)
			)
			( gate "C5F1"
				( objectStatus "@baseboard_fab2_lib.baseboard_fab2(sch_1):page217_i206" )
				( pin "C5F1.1"
					( objectStatus "a" )
				)
				( pin "C5F1.2"
					( objectStatus "b" )
				)
			)
			( gate "C5G10"
				( objectStatus "@baseboard_fab2_lib.baseboard_fab2(sch_1):page217_i207" )
				( pin "C5G10.1"
					( objectStatus "a" )
				)
				( pin "C5G10.2"
					( objectStatus "b" )
				)
			)
			( gate "C5T2"
				( objectStatus "@baseboard_fab2_lib.baseboard_fab2(sch_1):page217_i208" )
				( pin "C5T2.1"
					( objectStatus "a" )
				)
				( pin "C5T2.2"
					( objectStatus "b" )
				)
			)
			( gate "C5U11"
				( objectStatus "@baseboard_fab2_lib.baseboard_fab2(sch_1):page217_i209" )
				( pin "C5U11.1"
					( objectStatus "a" )
				)
				( pin "C5U11.2"
					( objectStatus "b" )
				)
			)
			( gate "C5T13"
				( objectStatus "@baseboard_fab2_lib.baseboard_fab2(sch_1):page217_i210" )
				( pin "C5T13.1"
					( objectStatus "a" )
				)
				( pin "C5T13.2"
					( objectStatus "b" )
				)
			)
			( gate "C5T4"
				( objectStatus "@baseboard_fab2_lib.baseboard_fab2(sch_1):page217_i211" )
				( pin "C5T4.1"
					( objectStatus "a" )
				)
				( pin "C5T4.2"
					( objectStatus "b" )
				)
			)
			( gate "C5T1"
				( objectStatus "@baseboard_fab2_lib.baseboard_fab2(sch_1):page217_i212" )
				( pin "C5T1.1"
					( objectStatus "a" )
				)
				( pin "C5T1.2"
					( objectStatus "b" )
				)
			)
			( gate "C5G19"
				( objectStatus "@baseboard_fab2_lib.baseboard_fab2(sch_1):page217_i213" )
				( pin "C5G19.1"
					( objectStatus "a" )
				)
				( pin "C5G19.2"
					( objectStatus "b" )
				)
			)
			( gate "C5T5"
				( objectStatus "@baseboard_fab2_lib.baseboard_fab2(sch_1):page217_i216" )
				( pin "C5T5.1"
					( objectStatus "a" )
				)
				( pin "C5T5.2"
					( objectStatus "b" )
				)
			)
			( gate "C5G3"
				( objectStatus "@baseboard_fab2_lib.baseboard_fab2(sch_1):page217_i217" )
				( pin "C5G3.1"
					( objectStatus "a" )
				)
				( pin "C5G3.2"
					( objectStatus "b" )
				)
			)
			( gate "C5T6"
				( objectStatus "@baseboard_fab2_lib.baseboard_fab2(sch_1):page217_i218" )
				( pin "C5T6.1"
					( objectStatus "a" )
				)
				( pin "C5T6.2"
					( objectStatus "b" )
				)
			)
			( gate "C5T7"
				( objectStatus "@baseboard_fab2_lib.baseboard_fab2(sch_1):page217_i219" )
				( pin "C5T7.1"
					( objectStatus "a" )
				)
				( pin "C5T7.2"
					( objectStatus "b" )
				)
			)
			( gate "C5G15"
				( objectStatus "@baseboard_fab2_lib.baseboard_fab2(sch_1):page217_i220" )
				( pin "C5G15.1"
					( objectStatus "a" )
				)
				( pin "C5G15.2"
					( objectStatus "b" )
				)
			)
			( gate "C5G16"
				( objectStatus "@baseboard_fab2_lib.baseboard_fab2(sch_1):page217_i221" )
				( pin "C5G16.1"
					( objectStatus "a" )
				)
				( pin "C5G16.2"
					( objectStatus "b" )
				)
			)
			( gate "C5T8"
				( objectStatus "@baseboard_fab2_lib.baseboard_fab2(sch_1):page217_i222" )
				( pin "C5T8.1"
					( objectStatus "a" )
				)
				( pin "C5T8.2"
					( objectStatus "b" )
				)
			)
			( gate "C5G14"
				( objectStatus "@baseboard_fab2_lib.baseboard_fab2(sch_1):page217_i223" )
				( pin "C5G14.1"
					( objectStatus "a" )
				)
				( pin "C5G14.2"
					( objectStatus "b" )
				)
			)
			( gate "C5T9"
				( objectStatus "@baseboard_fab2_lib.baseboard_fab2(sch_1):page217_i224" )
				( pin "C5T9.1"
					( objectStatus "a" )
				)
				( pin "C5T9.2"
					( objectStatus "b" )
				)
			)
			( gate "C5T10"
				( objectStatus "@baseboard_fab2_lib.baseboard_fab2(sch_1):page217_i225" )
				( pin "C5T10.1"
					( objectStatus "a" )
				)
				( pin "C5T10.2"
					( objectStatus "b" )
				)
			)
			( gate "C5G17"
				( objectStatus "@baseboard_fab2_lib.baseboard_fab2(sch_1):page217_i226" )
				( pin "C5G17.1"
					( objectStatus "a" )
				)
				( pin "C5G17.2"
					( objectStatus "b" )
				)
			)
			( gate "C5G18"
				( objectStatus "@baseboard_fab2_lib.baseboard_fab2(sch_1):page217_i227" )
				( pin "C5G18.1"
					( objectStatus "a" )
				)
				( pin "C5G18.2"
					( objectStatus "b" )
				)
			)
			( gate "C5T11"
				( objectStatus "@baseboard_fab2_lib.baseboard_fab2(sch_1):page217_i228" )
				( pin "C5T11.1"
					( objectStatus "a" )
				)
				( pin "C5T11.2"
					( objectStatus "b" )
				)
			)
			( gate "C5T12"
				( objectStatus "@baseboard_fab2_lib.baseboard_fab2(sch_1):page217_i229" )
				( pin "C5T12.1"
					( objectStatus "a" )
				)
				( pin "C5T12.2"
					( objectStatus "b" )
				)
			)
			( gate "C5G8"
				( objectStatus "@baseboard_fab2_lib.baseboard_fab2(sch_1):page217_i230" )
				( pin "C5G8.1"
					( objectStatus "a" )
				)
				( pin "C5G8.2"
					( objectStatus "b" )
				)
			)
			( gate "C5G1"
				( objectStatus "@baseboard_fab2_lib.baseboard_fab2(sch_1):page217_i231" )
				( pin "C5G1.1"
					( objectStatus "a" )
				)
				( pin "C5G1.2"
					( objectStatus "b" )
				)
			)
			( gate "C5U9"
				( objectStatus "@baseboard_fab2_lib.baseboard_fab2(sch_1):page217_i232" )
				( pin "C5U9.1"
					( objectStatus "a" )
				)
				( pin "C5U9.2"
					( objectStatus "b" )
				)
			)
			( gate "C5U8"
				( objectStatus "@baseboard_fab2_lib.baseboard_fab2(sch_1):page217_i233" )
				( pin "C5U8.1"
					( objectStatus "a" )
				)
				( pin "C5U8.2"
					( objectStatus "b" )
				)
			)
			( gate "C5G7"
				( objectStatus "@baseboard_fab2_lib.baseboard_fab2(sch_1):page217_i234" )
				( pin "C5G7.1"
					( objectStatus "a" )
				)
				( pin "C5G7.2"
					( objectStatus "b" )
				)
			)
			( gate "C5G5"
				( objectStatus "@baseboard_fab2_lib.baseboard_fab2(sch_1):page217_i235" )
				( pin "C5G5.1"
					( objectStatus "a" )
				)
				( pin "C5G5.2"
					( objectStatus "b" )
				)
			)
			( gate "C5U7"
				( objectStatus "@baseboard_fab2_lib.baseboard_fab2(sch_1):page217_i236" )
				( pin "C5U7.1"
					( objectStatus "a" )
				)
				( pin "C5U7.2"
					( objectStatus "b" )
				)
			)
			( gate "C5G6"
				( objectStatus "@baseboard_fab2_lib.baseboard_fab2(sch_1):page217_i237" )
				( pin "C5G6.1"
					( objectStatus "a" )
				)
				( pin "C5G6.2"
					( objectStatus "b" )
				)
			)
			( gate "C5U6"
				( objectStatus "@baseboard_fab2_lib.baseboard_fab2(sch_1):page217_i238" )
				( pin "C5U6.1"
					( objectStatus "a" )
				)
				( pin "C5U6.2"
					( objectStatus "b" )
				)
			)
			( gate "C5U5"
				( objectStatus "@baseboard_fab2_lib.baseboard_fab2(sch_1):page217_i239" )
				( pin "C5U5.1"
					( objectStatus "a" )
				)
				( pin "C5U5.2"
					( objectStatus "b" )
				)
			)
			( gate "C5G13"
				( objectStatus "@baseboard_fab2_lib.baseboard_fab2(sch_1):page217_i240" )
				( pin "C5G13.1"
					( objectStatus "a" )
				)
				( pin "C5G13.2"
					( objectStatus "b" )
				)
			)
			( gate "C5G4"
				( objectStatus "@baseboard_fab2_lib.baseboard_fab2(sch_1):page217_i241" )
				( pin "C5G4.1"
					( objectStatus "a" )
				)
				( pin "C5G4.2"
					( objectStatus "b" )
				)
			)
			( gate "C5U4"
				( objectStatus "@baseboard_fab2_lib.baseboard_fab2(sch_1):page217_i243" )
				( pin "C5U4.1"
					( objectStatus "a" )
				)
				( pin "C5U4.2"
					( objectStatus "b" )
				)
			)
			( gate "C5U3"
				( objectStatus "@baseboard_fab2_lib.baseboard_fab2(sch_1):page217_i244" )
				( pin "C5U3.1"
					( objectStatus "a" )
				)
				( pin "C5U3.2"
					( objectStatus "b" )
				)
			)
			( gate "C5G2"
				( objectStatus "@baseboard_fab2_lib.baseboard_fab2(sch_1):page217_i245" )
				( pin "C5G2.1"
					( objectStatus "a" )
				)
				( pin "C5G2.2"
					( objectStatus "b" )
				)
			)
			( gate "C5G12"
				( objectStatus "@baseboard_fab2_lib.baseboard_fab2(sch_1):page217_i246" )
				( pin "C5G12.1"
					( objectStatus "a" )
				)
				( pin "C5G12.2"
					( objectStatus "b" )
				)
			)
			( gate "C5U2"
				( objectStatus "@baseboard_fab2_lib.baseboard_fab2(sch_1):page217_i247" )
				( pin "C5U2.1"
					( objectStatus "a" )
				)
				( pin "C5U2.2"
					( objectStatus "b" )
				)
			)
			( gate "C5G11"
				( objectStatus "@baseboard_fab2_lib.baseboard_fab2(sch_1):page217_i250" )
				( pin "C5G11.1"
					( objectStatus "a" )
				)
				( pin "C5G11.2"
					( objectStatus "b" )
				)
			)
			( gate "R3L11"
				( objectStatus "@baseboard_fab2_lib.baseboard_fab2(sch_1):page218_i7" )
				( pin "R3L11.1"
					( objectStatus "a" )
				)
				( pin "R3L11.2"
					( objectStatus "b" )
				)
			)
			( gate "R3M3"
				( objectStatus "@baseboard_fab2_lib.baseboard_fab2(sch_1):page218_i11" )
				( pin "R3M3.1"
					( objectStatus "a" )
				)
				( pin "R3M3.2"
					( objectStatus "b" )
				)
			)
			( gate "R7B1"
				( objectStatus "@baseboard_fab2_lib.baseboard_fab2(sch_1):page218_i12" )
				( pin "R7B1.1"
					( objectStatus "a" )
				)
				( pin "R7B1.2"
					( objectStatus "b" )
				)
			)
			( gate "R7A9"
				( objectStatus "@baseboard_fab2_lib.baseboard_fab2(sch_1):page218_i14" )
				( pin "R7A9.1"
					( objectStatus "a" )
				)
				( pin "R7A9.2"
					( objectStatus "b" )
				)
			)
			( gate "R7A11"
				( objectStatus "@baseboard_fab2_lib.baseboard_fab2(sch_1):page218_i15" )
				( pin "R7A11.1"
					( objectStatus "a" )
				)
				( pin "R7A11.2"
					( objectStatus "b" )
				)
			)
			( gate "R7B5"
				( objectStatus "@baseboard_fab2_lib.baseboard_fab2(sch_1):page218_i16" )
				( pin "R7B5.1"
					( objectStatus "a" )
				)
				( pin "R7B5.2"
					( objectStatus "b" )
				)
			)
			( gate "R7B4"
				( objectStatus "@baseboard_fab2_lib.baseboard_fab2(sch_1):page218_i17" )
				( pin "R7B4.1"
					( objectStatus "a" )
				)
				( pin "R7B4.2"
					( objectStatus "b" )
				)
			)
			( gate "R7B3"
				( objectStatus "@baseboard_fab2_lib.baseboard_fab2(sch_1):page218_i21" )
				( pin "R7B3.1"
					( objectStatus "a" )
				)
				( pin "R7B3.2"
					( objectStatus "b" )
				)
			)
			( gate "C7B1"
				( objectStatus "@baseboard_fab2_lib.baseboard_fab2(sch_1):page218_i22" )
				( pin "C7B1.1"
					( objectStatus "a" )
				)
				( pin "C7B1.2"
					( objectStatus "b" )
				)
			)
			( gate "C7B2"
				( objectStatus "@baseboard_fab2_lib.baseboard_fab2(sch_1):page218_i23" )
				( pin "C7B2.1"
					( objectStatus "a" )
				)
				( pin "C7B2.2"
					( objectStatus "b" )
				)
			)
			( gate "R7B2"
				( objectStatus "@baseboard_fab2_lib.baseboard_fab2(sch_1):page218_i24" )
				( pin "R7B2.1"
					( objectStatus "a" )
				)
				( pin "R7B2.2"
					( objectStatus "b" )
				)
			)
			( gate "R7A12"
				( objectStatus "@baseboard_fab2_lib.baseboard_fab2(sch_1):page218_i25" )
				( pin "R7A12.1"
					( objectStatus "a" )
				)
				( pin "R7A12.2"
					( objectStatus "b" )
				)
			)
			( gate "C7B3"
				( objectStatus "@baseboard_fab2_lib.baseboard_fab2(sch_1):page218_i26" )
				( pin "C7B3.1"
					( objectStatus "a" )
				)
				( pin "C7B3.2"
					( objectStatus "b" )
				)
			)
			( gate "C7A37"
				( objectStatus "@baseboard_fab2_lib.baseboard_fab2(sch_1):page218_i29" )
				( pin "C7A37.1"
					( objectStatus "a" )
				)
				( pin "C7A37.2"
					( objectStatus "b" )
				)
			)
			( gate "C7A38"
				( objectStatus "@baseboard_fab2_lib.baseboard_fab2(sch_1):page218_i31" )
				( pin "C7A38.1"
					( objectStatus "a" )
				)
				( pin "C7A38.2"
					( objectStatus "b" )
				)
			)
			( gate "R3M1"
				( objectStatus "@baseboard_fab2_lib.baseboard_fab2(sch_1):page218_i34" )
				( pin "R3M1.1"
					( objectStatus "a" )
				)
				( pin "R3M1.2"
					( objectStatus "b" )
				)
			)
			( gate "R3M5"
				( objectStatus "@baseboard_fab2_lib.baseboard_fab2(sch_1):page218_i35" )
				( pin "R3M5.1"
					( objectStatus "a" )
				)
				( pin "R3M5.2"
					( objectStatus "b" )
				)
			)
			( gate "R7A8"
				( objectStatus "@baseboard_fab2_lib.baseboard_fab2(sch_1):page218_i37" )
				( pin "R7A8.1"
					( objectStatus "a" )
				)
				( pin "R7A8.2"
					( objectStatus "b" )
				)
			)
			( gate "C7A29"
				( objectStatus "@baseboard_fab2_lib.baseboard_fab2(sch_1):page218_i39" )
				( pin "C7A29.1"
					( objectStatus "a" )
				)
				( pin "C7A29.2"
					( objectStatus "b" )
				)
			)
			( gate "R7A10"
				( objectStatus "@baseboard_fab2_lib.baseboard_fab2(sch_1):page218_i40" )
				( pin "R7A10.1"
					( objectStatus "a" )
				)
				( pin "R7A10.2"
					( objectStatus "b" )
				)
			)
			( gate "R3L13"
				( objectStatus "@baseboard_fab2_lib.baseboard_fab2(sch_1):page218_i47" )
				( pin "R3L13.1"
					( objectStatus "a" )
				)
				( pin "R3L13.2"
					( objectStatus "b" )
				)
			)
			( gate "R7A17"
				( objectStatus "@baseboard_fab2_lib.baseboard_fab2(sch_1):page218_i48" )
				( pin "R7A17.1"
					( objectStatus "a" )
				)
				( pin "R7A17.2"
					( objectStatus "b" )
				)
			)
			( gate "R3L10"
				( objectStatus "@baseboard_fab2_lib.baseboard_fab2(sch_1):page218_i50" )
				( pin "R3L10.1"
					( objectStatus "a" )
				)
				( pin "R3L10.2"
					( objectStatus "b" )
				)
			)
			( gate "R3L12"
				( objectStatus "@baseboard_fab2_lib.baseboard_fab2(sch_1):page218_i53" )
				( pin "R3L12.1"
					( objectStatus "a" )
				)
				( pin "R3L12.2"
					( objectStatus "b" )
				)
			)
			( gate "R7A16"
				( objectStatus "@baseboard_fab2_lib.baseboard_fab2(sch_1):page218_i54" )
				( pin "R7A16.1"
					( objectStatus "a" )
				)
				( pin "R7A16.2"
					( objectStatus "b" )
				)
			)
			( gate "C7A35"
				( objectStatus "@baseboard_fab2_lib.baseboard_fab2(sch_1):page218_i55" )
				( pin "C7A35.1"
					( objectStatus "a" )
				)
				( pin "C7A35.2"
					( objectStatus "b" )
				)
			)
			( gate "R3L9"
				( objectStatus "@baseboard_fab2_lib.baseboard_fab2(sch_1):page218_i57" )
				( pin "R3L9.1"
					( objectStatus "a" )
				)
				( pin "R3L9.2"
					( objectStatus "b" )
				)
			)
			( gate "R3M6"
				( objectStatus "@baseboard_fab2_lib.baseboard_fab2(sch_1):page218_i59" )
				( pin "R3M6.1"
					( objectStatus "a" )
				)
				( pin "R3M6.2"
					( objectStatus "b" )
				)
			)
			( gate "R7A7"
				( objectStatus "@baseboard_fab2_lib.baseboard_fab2(sch_1):page218_i60" )
				( pin "R7A7.1"
					( objectStatus "a" )
				)
				( pin "R7A7.2"
					( objectStatus "b" )
				)
			)
			( gate "C7A28"
				( objectStatus "@baseboard_fab2_lib.baseboard_fab2(sch_1):page218_i61" )
				( pin "C7A28.1"
					( objectStatus "a" )
				)
				( pin "C7A28.2"
					( objectStatus "b" )
				)
			)
			( gate "EU7A5"
				( objectStatus "@baseboard_fab2_lib.baseboard_fab2(sch_1):page218_i75" )
				( pin "EU7A5.21"
					( objectStatus "airef1" )
				)
				( pin "EU7A5.23"
					( objectStatus "airef2" )
				)
				( pin "EU7A5.25"
					( objectStatus "airef3" )
				)
				( pin "EU7A5.22"
					( objectStatus "aisen1" )
				)
				( pin "EU7A5.24"
					( objectStatus "aisen2" )
				)
				( pin "EU7A5.26"
					( objectStatus "aisen3" )
				)
				( pin "EU7A5.5"
					( objectStatus "apwm1" )
				)
				( pin "EU7A5.4"
					( objectStatus "apwm2" )
				)
				( pin "EU7A5.3"
					( objectStatus "apwm3" )
				)
				( pin "EU7A5.35"
					( objectStatus "atsen" )
				)
				( pin "EU7A5.20"
					( objectStatus "avref" )
				)
				( pin "EU7A5.10"
					( objectStatus "avren" )
				)
				( pin "EU7A5.9"
					( objectStatus "avrrdy" )
				)
				( pin "EU7A5.19"
					( objectStatus "avsen" )
				)
				( pin "EU7A5.31"
					( objectStatus "biref1" )
				)
				( pin "EU7A5.32"
					( objectStatus "bisen1" )
				)
				( pin "EU7A5.1"
					( objectStatus "bpwm1" )
				)
				( pin "EU7A5.34"
					( objectStatus "btsen" )
				)
				( pin "EU7A5.30"
					( objectStatus "bvref" )
				)
				( pin "EU7A5.29"
					( objectStatus "bvsen" )
				)
				( pin "EU7A5.2"
					( objectStatus "dnc(0)" )
				)
				( pin "EU7A5.28"
					( objectStatus "dnc(1)" )
				)
				( pin "EU7A5.27"
					( objectStatus "gnd" )
				)
				( pin "EU7A5.38"
					( objectStatus "iinsen" )
				)
				( pin "EU7A5.13"
					( objectStatus "mp0" )
				)
				( pin "EU7A5.14"
					( objectStatus "mp1" )
				)
				( pin "EU7A5.18"
					( objectStatus "mp2" )
				)
				( pin "EU7A5.12"
					( objectStatus "pinalrt_n" )
				)
				( pin "EU7A5.8"
					( objectStatus "reset_n" )
				)
				( pin "EU7A5.7"
					( objectStatus "scl" )
				)
				( pin "EU7A5.6"
					( objectStatus "sda" )
				)
				( pin "EU7A5.41"
					( objectStatus "thpad" )
				)
				( pin "EU7A5.17"
					( objectStatus "valrt_n" )
				)
				( pin "EU7A5.15"
					( objectStatus "vclk" )
				)
				( pin "EU7A5.40"
					( objectStatus "vd12" )
				)
				( pin "EU7A5.39"
					( objectStatus "vdd" )
				)
				( pin "EU7A5.16"
					( objectStatus "vdio" )
				)
				( pin "EU7A5.37"
					( objectStatus "vinsen" )
				)
				( pin "EU7A5.11"
					( objectStatus "vrhot_n" )
				)
				( pin "EU7A5.36"
					( objectStatus "xaddr1" )
				)
				( pin "EU7A5.33"
					( objectStatus "xaddr2" )
				)
			)
			( gate "C4B10"
				( objectStatus "@baseboard_fab2_lib.baseboard_fab2(sch_1):page218_i77" )
				( pin "C4B10.1"
					( objectStatus "a" )
				)
				( pin "C4B10.2"
					( objectStatus "b" )
				)
			)
			( gate "C7A12"
				( objectStatus "@baseboard_fab2_lib.baseboard_fab2(sch_1):page219_i44" )
				( pin "C7A12.1"
					( objectStatus "a" )
				)
				( pin "C7A12.2"
					( objectStatus "b" )
				)
			)
			( gate "C3L2"
				( objectStatus "@baseboard_fab2_lib.baseboard_fab2(sch_1):page219_i45" )
				( pin "C3L2.1"
					( objectStatus "a" )
				)
				( pin "C3L2.2"
					( objectStatus "b" )
				)
			)
			( gate "C3L4"
				( objectStatus "@baseboard_fab2_lib.baseboard_fab2(sch_1):page219_i46" )
				( pin "C3L4.1"
					( objectStatus "a" )
				)
				( pin "C3L4.2"
					( objectStatus "b" )
				)
			)
			( gate "C3L13"
				( objectStatus "@baseboard_fab2_lib.baseboard_fab2(sch_1):page219_i47" )
				( pin "C3L13.1"
					( objectStatus "a" )
				)
				( pin "C3L13.2"
					( objectStatus "b" )
				)
			)
			( gate "C7A11"
				( objectStatus "@baseboard_fab2_lib.baseboard_fab2(sch_1):page219_i48" )
				( pin "C7A11.1"
					( objectStatus "a" )
				)
				( pin "C7A11.2"
					( objectStatus "b" )
				)
			)
			( gate "C7A16"
				( objectStatus "@baseboard_fab2_lib.baseboard_fab2(sch_1):page219_i50" )
				( pin "C7A16.1"
					( objectStatus "a" )
				)
				( pin "C7A16.2"
					( objectStatus "b" )
				)
			)
			( gate "C7A5"
				( objectStatus "@baseboard_fab2_lib.baseboard_fab2(sch_1):page219_i51" )
				( pin "C7A5.1"
					( objectStatus "a" )
				)
				( pin "C7A5.2"
					( objectStatus "b" )
				)
			)
			( gate "R3L6"
				( objectStatus "@baseboard_fab2_lib.baseboard_fab2(sch_1):page219_i52" )
				( pin "R3L6.1"
					( objectStatus "a" )
				)
				( pin "R3L6.2"
					( objectStatus "b" )
				)
			)
			( gate "C7A18"
				( objectStatus "@baseboard_fab2_lib.baseboard_fab2(sch_1):page219_i53" )
				( pin "C7A18.1"
					( objectStatus "a" )
				)
				( pin "C7A18.2"
					( objectStatus "b" )
				)
			)
			( gate "C7A17"
				( objectStatus "@baseboard_fab2_lib.baseboard_fab2(sch_1):page219_i54" )
				( pin "C7A17.1"
					( objectStatus "a" )
				)
				( pin "C7A17.2"
					( objectStatus "b" )
				)
			)
			( gate "L7A1"
				( objectStatus "@baseboard_fab2_lib.baseboard_fab2(sch_1):page219_i55" )
				( pin "L7A1.1"
					( objectStatus "ina" )
				)
				( pin "L7A1.2"
					( objectStatus "inb" )
				)
			)
			( gate "L7A3"
				( objectStatus "@baseboard_fab2_lib.baseboard_fab2(sch_1):page219_i65" )
				( pin "L7A3.1"
					( objectStatus "ina" )
				)
				( pin "L7A3.2"
					( objectStatus "inb" )
				)
			)
			( gate "C6A4"
				( objectStatus "@baseboard_fab2_lib.baseboard_fab2(sch_1):page219_i68" )
				( pin "C6A4.1"
					( objectStatus "a" )
				)
				( pin "C6A4.2"
					( objectStatus "b" )
				)
			)
			( gate "C7A25"
				( objectStatus "@baseboard_fab2_lib.baseboard_fab2(sch_1):page219_i72" )
				( pin "C7A25.1"
					( objectStatus "a" )
				)
				( pin "C7A25.2"
					( objectStatus "b" )
				)
			)
			( gate "C7A26"
				( objectStatus "@baseboard_fab2_lib.baseboard_fab2(sch_1):page219_i73" )
				( pin "C7A26.1"
					( objectStatus "a" )
				)
				( pin "C7A26.2"
					( objectStatus "b" )
				)
			)
			( gate "C7A22"
				( objectStatus "@baseboard_fab2_lib.baseboard_fab2(sch_1):page219_i75" )
				( pin "C7A22.1"
					( objectStatus "a" )
				)
				( pin "C7A22.2"
					( objectStatus "b" )
				)
			)
			( gate "R3L8"
				( objectStatus "@baseboard_fab2_lib.baseboard_fab2(sch_1):page219_i76" )
				( pin "R3L8.1"
					( objectStatus "a" )
				)
				( pin "R3L8.2"
					( objectStatus "b" )
				)
			)
			( gate "C7A24"
				( objectStatus "@baseboard_fab2_lib.baseboard_fab2(sch_1):page219_i77" )
				( pin "C7A24.1"
					( objectStatus "a" )
				)
				( pin "C7A24.2"
					( objectStatus "b" )
				)
			)
			( gate "C7A20"
				( objectStatus "@baseboard_fab2_lib.baseboard_fab2(sch_1):page219_i78" )
				( pin "C7A20.1"
					( objectStatus "a" )
				)
				( pin "C7A20.2"
					( objectStatus "b" )
				)
			)
			( gate "C7A21"
				( objectStatus "@baseboard_fab2_lib.baseboard_fab2(sch_1):page219_i79" )
				( pin "C7A21.1"
					( objectStatus "a" )
				)
				( pin "C7A21.2"
					( objectStatus "b" )
				)
			)
			( gate "C3L17"
				( objectStatus "@baseboard_fab2_lib.baseboard_fab2(sch_1):page219_i80" )
				( pin "C3L17.1"
					( objectStatus "a" )
				)
				( pin "C3L17.2"
					( objectStatus "b" )
				)
			)
			( gate "C3L16"
				( objectStatus "@baseboard_fab2_lib.baseboard_fab2(sch_1):page219_i81" )
				( pin "C3L16.1"
					( objectStatus "a" )
				)
				( pin "C3L16.2"
					( objectStatus "b" )
				)
			)
			( gate "C3L15"
				( objectStatus "@baseboard_fab2_lib.baseboard_fab2(sch_1):page219_i84" )
				( pin "C3L15.1"
					( objectStatus "a" )
				)
				( pin "C3L15.2"
					( objectStatus "b" )
				)
			)
			( gate "C6A1"
				( objectStatus "@baseboard_fab2_lib.baseboard_fab2(sch_1):page219_i87" )
				( pin "C6A1.1"
					( objectStatus "a" )
				)
				( pin "C6A1.2"
					( objectStatus "b" )
				)
			)
			( gate "EU7A1"
				( objectStatus "@baseboard_fab2_lib.baseboard_fab2(sch_1):page219_i106" )
				( pin "EU7A1.33"
					( objectStatus "boost" )
				)
				( pin "EU7A1.35"
					( objectStatus "en" )
				)
				( pin "EU7A1.6"
					( objectStatus "gl(0)" )
				)
				( pin "EU7A1.41"
					( objectStatus "gl(1)" )
				)
				( pin "EU7A1.38"
					( objectStatus "iout" )
				)
				( pin "EU7A1.2"
					( objectStatus "lgnd" )
				)
				( pin "EU7A1.31"
					( objectStatus "nc" )
				)
				( pin "EU7A1.37"
					( objectStatus "ocset" )
				)
				( pin "EU7A1.5"
					( objectStatus "pgnd(0)" )
				)
				( pin "EU7A1.7"
					( objectStatus "pgnd(1)" )
				)
				( pin "EU7A1.40"
					( objectStatus "pgnd(2)" )
				)
				( pin "EU7A1.32"
					( objectStatus "phase" )
				)
				( pin "EU7A1.34"
					( objectStatus "pwm" )
				)
				( pin "EU7A1.39"
					( objectStatus "refin" )
				)
				( pin "EU7A1.10"
					( objectStatus "sw" )
				)
				( pin "EU7A1.36"
					( objectStatus "tout_flt" )
				)
				( pin "EU7A1.3"
					( objectStatus "vcc" )
				)
				( pin "EU7A1.4"
					( objectStatus "vdrv" )
				)
				( pin "EU7A1.25"
					( objectStatus "vin(0)" )
				)
				( pin "EU7A1.30"
					( objectStatus "vin(1)" )
				)
				( pin "EU7A1.1"
					( objectStatus "vos" )
				)
			)
			( gate "EU7A4"
				( objectStatus "@baseboard_fab2_lib.baseboard_fab2(sch_1):page219_i107" )
				( pin "EU7A4.33"
					( objectStatus "boost" )
				)
				( pin "EU7A4.35"
					( objectStatus "en" )
				)
				( pin "EU7A4.6"
					( objectStatus "gl(0)" )
				)
				( pin "EU7A4.41"
					( objectStatus "gl(1)" )
				)
				( pin "EU7A4.38"
					( objectStatus "iout" )
				)
				( pin "EU7A4.2"
					( objectStatus "lgnd" )
				)
				( pin "EU7A4.31"
					( objectStatus "nc" )
				)
				( pin "EU7A4.37"
					( objectStatus "ocset" )
				)
				( pin "EU7A4.5"
					( objectStatus "pgnd(0)" )
				)
				( pin "EU7A4.7"
					( objectStatus "pgnd(1)" )
				)
				( pin "EU7A4.40"
					( objectStatus "pgnd(2)" )
				)
				( pin "EU7A4.32"
					( objectStatus "phase" )
				)
				( pin "EU7A4.34"
					( objectStatus "pwm" )
				)
				( pin "EU7A4.39"
					( objectStatus "refin" )
				)
				( pin "EU7A4.10"
					( objectStatus "sw" )
				)
				( pin "EU7A4.36"
					( objectStatus "tout_flt" )
				)
				( pin "EU7A4.3"
					( objectStatus "vcc" )
				)
				( pin "EU7A4.4"
					( objectStatus "vdrv" )
				)
				( pin "EU7A4.25"
					( objectStatus "vin(0)" )
				)
				( pin "EU7A4.30"
					( objectStatus "vin(1)" )
				)
				( pin "EU7A4.1"
					( objectStatus "vos" )
				)
			)
			( gate "R39"
				( objectStatus "@baseboard_fab2_lib.baseboard_fab2(sch_1):page219_i108" )
				( pin "R39.1"
					( objectStatus "a" )
				)
				( pin "R39.2"
					( objectStatus "b" )
				)
			)
			( gate "R40"
				( objectStatus "@baseboard_fab2_lib.baseboard_fab2(sch_1):page219_i110" )
				( pin "R40.1"
					( objectStatus "a" )
				)
				( pin "R40.2"
					( objectStatus "b" )
				)
			)
			( gate "R4L4"
				( objectStatus "@baseboard_fab2_lib.baseboard_fab2(sch_1):page220_i58" )
				( pin "R4L4.1"
					( objectStatus "a" )
				)
				( pin "R4L4.2"
					( objectStatus "b" )
				)
			)
			( gate "R4L1"
				( objectStatus "@baseboard_fab2_lib.baseboard_fab2(sch_1):page220_i67" )
				( pin "R4L1.1"
					( objectStatus "a" )
				)
				( pin "R4L1.2"
					( objectStatus "b" )
				)
			)
			( gate "R4L3"
				( objectStatus "@baseboard_fab2_lib.baseboard_fab2(sch_1):page220_i71" )
				( pin "R4L3.1"
					( objectStatus "a" )
				)
				( pin "R4L3.2"
					( objectStatus "b" )
				)
			)
			( gate "R4L2"
				( objectStatus "@baseboard_fab2_lib.baseboard_fab2(sch_1):page220_i74" )
				( pin "R4L2.1"
					( objectStatus "a" )
				)
				( pin "R4L2.2"
					( objectStatus "b" )
				)
			)
			( gate "C3L6"
				( objectStatus "@baseboard_fab2_lib.baseboard_fab2(sch_1):page220_i75" )
				( pin "C3L6.1"
					( objectStatus "a" )
				)
				( pin "C3L6.2"
					( objectStatus "b" )
				)
			)
			( gate "C3L14"
				( objectStatus "@baseboard_fab2_lib.baseboard_fab2(sch_1):page220_i76" )
				( pin "C3L14.1"
					( objectStatus "a" )
				)
				( pin "C3L14.2"
					( objectStatus "b" )
				)
			)
			( gate "C6A5"
				( objectStatus "@baseboard_fab2_lib.baseboard_fab2(sch_1):page220_i77" )
				( pin "C6A5.1"
					( objectStatus "a" )
				)
				( pin "C6A5.2"
					( objectStatus "b" )
				)
			)
			( gate "C4L5"
				( objectStatus "@baseboard_fab2_lib.baseboard_fab2(sch_1):page220_i78" )
				( pin "C4L5.1"
					( objectStatus "a" )
				)
				( pin "C4L5.2"
					( objectStatus "b" )
				)
			)
			( gate "C5M8"
				( objectStatus "@baseboard_fab2_lib.baseboard_fab2(sch_1):page220_i82" )
				( pin "C5M8.1"
					( objectStatus "a" )
				)
				( pin "C5M8.2"
					( objectStatus "b" )
				)
			)
			( gate "C5L14"
				( objectStatus "@baseboard_fab2_lib.baseboard_fab2(sch_1):page220_i83" )
				( pin "C5L14.1"
					( objectStatus "a" )
				)
				( pin "C5L14.2"
					( objectStatus "b" )
				)
			)
			( gate "C5M12"
				( objectStatus "@baseboard_fab2_lib.baseboard_fab2(sch_1):page220_i88" )
				( pin "C5M12.1"
					( objectStatus "a" )
				)
				( pin "C5M12.2"
					( objectStatus "b" )
				)
			)
			( gate "C5L3"
				( objectStatus "@baseboard_fab2_lib.baseboard_fab2(sch_1):page220_i89" )
				( pin "C5L3.1"
					( objectStatus "a" )
				)
				( pin "C5L3.2"
					( objectStatus "b" )
				)
			)
			( gate "C5L2"
				( objectStatus "@baseboard_fab2_lib.baseboard_fab2(sch_1):page220_i90" )
				( pin "C5L2.1"
					( objectStatus "a" )
				)
				( pin "C5L2.2"
					( objectStatus "b" )
				)
			)
			( gate "C5L1"
				( objectStatus "@baseboard_fab2_lib.baseboard_fab2(sch_1):page220_i91" )
				( pin "C5L1.1"
					( objectStatus "a" )
				)
				( pin "C5L1.2"
					( objectStatus "b" )
				)
			)
			( gate "C5A20"
				( objectStatus "@baseboard_fab2_lib.baseboard_fab2(sch_1):page220_i92" )
				( pin "C5A20.1"
					( objectStatus "a" )
				)
				( pin "C5A20.2"
					( objectStatus "b" )
				)
			)
			( gate "C5A10"
				( objectStatus "@baseboard_fab2_lib.baseboard_fab2(sch_1):page220_i110" )
				( pin "C5A10.1"
					( objectStatus "a" )
				)
				( pin "C5A10.2"
					( objectStatus "b" )
				)
			)
			( gate "L7A5"
				( objectStatus "@baseboard_fab2_lib.baseboard_fab2(sch_1):page220_i124" )
				( pin "L7A5.1"
					( objectStatus "ina" )
				)
				( pin "L7A5.2"
					( objectStatus "inb" )
				)
			)
			( gate "C7A19"
				( objectStatus "@baseboard_fab2_lib.baseboard_fab2(sch_1):page220_i175" )
				( pin "C7A19.1"
					( objectStatus "a" )
				)
				( pin "C7A19.2"
					( objectStatus "b" )
				)
			)
			( gate "C5P2"
				( objectStatus "@baseboard_fab2_lib.baseboard_fab2(sch_1):page220_i177" )
				( pin "C5P2.1"
					( objectStatus "a" )
				)
				( pin "C5P2.2"
					( objectStatus "b" )
				)
			)
			( gate "C5P1"
				( objectStatus "@baseboard_fab2_lib.baseboard_fab2(sch_1):page220_i179" )
				( pin "C5P1.1"
					( objectStatus "a" )
				)
				( pin "C5P1.2"
					( objectStatus "b" )
				)
			)
			( gate "C5D9"
				( objectStatus "@baseboard_fab2_lib.baseboard_fab2(sch_1):page220_i180" )
				( pin "C5D9.1"
					( objectStatus "a" )
				)
				( pin "C5D9.2"
					( objectStatus "b" )
				)
			)
			( gate "C5D6"
				( objectStatus "@baseboard_fab2_lib.baseboard_fab2(sch_1):page220_i182" )
				( pin "C5D6.1"
					( objectStatus "a" )
				)
				( pin "C5D6.2"
					( objectStatus "b" )
				)
			)
			( gate "C5D7"
				( objectStatus "@baseboard_fab2_lib.baseboard_fab2(sch_1):page220_i183" )
				( pin "C5D7.1"
					( objectStatus "a" )
				)
				( pin "C5D7.2"
					( objectStatus "b" )
				)
			)
			( gate "C5D8"
				( objectStatus "@baseboard_fab2_lib.baseboard_fab2(sch_1):page220_i184" )
				( pin "C5D8.1"
					( objectStatus "a" )
				)
				( pin "C5D8.2"
					( objectStatus "b" )
				)
			)
			( gate "C5L15"
				( objectStatus "@baseboard_fab2_lib.baseboard_fab2(sch_1):page220_i192" )
				( pin "C5L15.1"
					( objectStatus "a" )
				)
				( pin "C5L15.2"
					( objectStatus "b" )
				)
			)
			( gate "C5A5"
				( objectStatus "@baseboard_fab2_lib.baseboard_fab2(sch_1):page220_i193" )
				( pin "C5A5.1"
					( objectStatus "a" )
				)
				( pin "C5A5.2"
					( objectStatus "b" )
				)
			)
			( gate "C5B1"
				( objectStatus "@baseboard_fab2_lib.baseboard_fab2(sch_1):page220_i194" )
				( pin "C5B1.1"
					( objectStatus "a" )
				)
				( pin "C5B1.2"
					( objectStatus "b" )
				)
			)
			( gate "C5M9"
				( objectStatus "@baseboard_fab2_lib.baseboard_fab2(sch_1):page220_i195" )
				( pin "C5M9.1"
					( objectStatus "a" )
				)
				( pin "C5M9.2"
					( objectStatus "b" )
				)
			)
			( gate "C4M5"
				( objectStatus "@baseboard_fab2_lib.baseboard_fab2(sch_1):page220_i196" )
				( pin "C4M5.1"
					( objectStatus "a" )
				)
				( pin "C4M5.2"
					( objectStatus "b" )
				)
			)
			( gate "C5B2"
				( objectStatus "@baseboard_fab2_lib.baseboard_fab2(sch_1):page220_i197" )
				( pin "C5B2.1"
					( objectStatus "a" )
				)
				( pin "C5B2.2"
					( objectStatus "b" )
				)
			)
			( gate "C5M10"
				( objectStatus "@baseboard_fab2_lib.baseboard_fab2(sch_1):page220_i198" )
				( pin "C5M10.1"
					( objectStatus "a" )
				)
				( pin "C5M10.2"
					( objectStatus "b" )
				)
			)
			( gate "C5M3"
				( objectStatus "@baseboard_fab2_lib.baseboard_fab2(sch_1):page220_i199" )
				( pin "C5M3.1"
					( objectStatus "a" )
				)
				( pin "C5M3.2"
					( objectStatus "b" )
				)
			)
			( gate "C5M11"
				( objectStatus "@baseboard_fab2_lib.baseboard_fab2(sch_1):page220_i200" )
				( pin "C5M11.1"
					( objectStatus "a" )
				)
				( pin "C5M11.2"
					( objectStatus "b" )
				)
			)
			( gate "C5A19"
				( objectStatus "@baseboard_fab2_lib.baseboard_fab2(sch_1):page220_i203" )
				( pin "C5A19.1"
					( objectStatus "a" )
				)
				( pin "C5A19.2"
					( objectStatus "b" )
				)
			)
			( gate "C5A18"
				( objectStatus "@baseboard_fab2_lib.baseboard_fab2(sch_1):page220_i204" )
				( pin "C5A18.1"
					( objectStatus "a" )
				)
				( pin "C5A18.2"
					( objectStatus "b" )
				)
			)
			( gate "C5A17"
				( objectStatus "@baseboard_fab2_lib.baseboard_fab2(sch_1):page220_i205" )
				( pin "C5A17.1"
					( objectStatus "a" )
				)
				( pin "C5A17.2"
					( objectStatus "b" )
				)
			)
			( gate "C5A4"
				( objectStatus "@baseboard_fab2_lib.baseboard_fab2(sch_1):page220_i206" )
				( pin "C5A4.1"
					( objectStatus "a" )
				)
				( pin "C5A4.2"
					( objectStatus "b" )
				)
			)
			( gate "C5A16"
				( objectStatus "@baseboard_fab2_lib.baseboard_fab2(sch_1):page220_i207" )
				( pin "C5A16.1"
					( objectStatus "a" )
				)
				( pin "C5A16.2"
					( objectStatus "b" )
				)
			)
			( gate "C5A9"
				( objectStatus "@baseboard_fab2_lib.baseboard_fab2(sch_1):page220_i208" )
				( pin "C5A9.1"
					( objectStatus "a" )
				)
				( pin "C5A9.2"
					( objectStatus "b" )
				)
			)
			( gate "C5A8"
				( objectStatus "@baseboard_fab2_lib.baseboard_fab2(sch_1):page220_i209" )
				( pin "C5A8.1"
					( objectStatus "a" )
				)
				( pin "C5A8.2"
					( objectStatus "b" )
				)
			)
			( gate "C5A3"
				( objectStatus "@baseboard_fab2_lib.baseboard_fab2(sch_1):page220_i210" )
				( pin "C5A3.1"
					( objectStatus "a" )
				)
				( pin "C5A3.2"
					( objectStatus "b" )
				)
			)
			( gate "C5A7"
				( objectStatus "@baseboard_fab2_lib.baseboard_fab2(sch_1):page220_i211" )
				( pin "C5A7.1"
					( objectStatus "a" )
				)
				( pin "C5A7.2"
					( objectStatus "b" )
				)
			)
			( gate "C5A6"
				( objectStatus "@baseboard_fab2_lib.baseboard_fab2(sch_1):page220_i212" )
				( pin "C5A6.1"
					( objectStatus "a" )
				)
				( pin "C5A6.2"
					( objectStatus "b" )
				)
			)
			( gate "C5A14"
				( objectStatus "@baseboard_fab2_lib.baseboard_fab2(sch_1):page220_i213" )
				( pin "C5A14.1"
					( objectStatus "a" )
				)
				( pin "C5A14.2"
					( objectStatus "b" )
				)
			)
			( gate "C5A2"
				( objectStatus "@baseboard_fab2_lib.baseboard_fab2(sch_1):page220_i214" )
				( pin "C5A2.1"
					( objectStatus "a" )
				)
				( pin "C5A2.2"
					( objectStatus "b" )
				)
			)
			( gate "C5A13"
				( objectStatus "@baseboard_fab2_lib.baseboard_fab2(sch_1):page220_i215" )
				( pin "C5A13.1"
					( objectStatus "a" )
				)
				( pin "C5A13.2"
					( objectStatus "b" )
				)
			)
			( gate "C5A12"
				( objectStatus "@baseboard_fab2_lib.baseboard_fab2(sch_1):page220_i216" )
				( pin "C5A12.1"
					( objectStatus "a" )
				)
				( pin "C5A12.2"
					( objectStatus "b" )
				)
			)
			( gate "C5A15"
				( objectStatus "@baseboard_fab2_lib.baseboard_fab2(sch_1):page220_i217" )
				( pin "C5A15.1"
					( objectStatus "a" )
				)
				( pin "C5A15.2"
					( objectStatus "b" )
				)
			)
			( gate "C5A1"
				( objectStatus "@baseboard_fab2_lib.baseboard_fab2(sch_1):page220_i219" )
				( pin "C5A1.1"
					( objectStatus "a" )
				)
				( pin "C5A1.2"
					( objectStatus "b" )
				)
			)
			( gate "C5A11"
				( objectStatus "@baseboard_fab2_lib.baseboard_fab2(sch_1):page220_i221" )
				( pin "C5A11.1"
					( objectStatus "a" )
				)
				( pin "C5A11.2"
					( objectStatus "b" )
				)
			)
			( gate "C4M2"
				( objectStatus "@baseboard_fab2_lib.baseboard_fab2(sch_1):page220_i222" )
				( pin "C4M2.1"
					( objectStatus "a" )
				)
				( pin "C4M2.2"
					( objectStatus "b" )
				)
			)
			( gate "C5M1"
				( objectStatus "@baseboard_fab2_lib.baseboard_fab2(sch_1):page220_i223" )
				( pin "C5M1.1"
					( objectStatus "a" )
				)
				( pin "C5M1.2"
					( objectStatus "b" )
				)
			)
			( gate "C5M2"
				( objectStatus "@baseboard_fab2_lib.baseboard_fab2(sch_1):page220_i224" )
				( pin "C5M2.1"
					( objectStatus "a" )
				)
				( pin "C5M2.2"
					( objectStatus "b" )
				)
			)
			( gate "C5M4"
				( objectStatus "@baseboard_fab2_lib.baseboard_fab2(sch_1):page220_i225" )
				( pin "C5M4.1"
					( objectStatus "a" )
				)
				( pin "C5M4.2"
					( objectStatus "b" )
				)
			)
			( gate "C5M5"
				( objectStatus "@baseboard_fab2_lib.baseboard_fab2(sch_1):page220_i226" )
				( pin "C5M5.1"
					( objectStatus "a" )
				)
				( pin "C5M5.2"
					( objectStatus "b" )
				)
			)
			( gate "C5M6"
				( objectStatus "@baseboard_fab2_lib.baseboard_fab2(sch_1):page220_i227" )
				( pin "C5M6.1"
					( objectStatus "a" )
				)
				( pin "C5M6.2"
					( objectStatus "b" )
				)
			)
			( gate "C5M7"
				( objectStatus "@baseboard_fab2_lib.baseboard_fab2(sch_1):page220_i228" )
				( pin "C5M7.1"
					( objectStatus "a" )
				)
				( pin "C5M7.2"
					( objectStatus "b" )
				)
			)
			( gate "C5L13"
				( objectStatus "@baseboard_fab2_lib.baseboard_fab2(sch_1):page220_i229" )
				( pin "C5L13.1"
					( objectStatus "a" )
				)
				( pin "C5L13.2"
					( objectStatus "b" )
				)
			)
			( gate "C5L12"
				( objectStatus "@baseboard_fab2_lib.baseboard_fab2(sch_1):page220_i230" )
				( pin "C5L12.1"
					( objectStatus "a" )
				)
				( pin "C5L12.2"
					( objectStatus "b" )
				)
			)
			( gate "C5L11"
				( objectStatus "@baseboard_fab2_lib.baseboard_fab2(sch_1):page220_i231" )
				( pin "C5L11.1"
					( objectStatus "a" )
				)
				( pin "C5L11.2"
					( objectStatus "b" )
				)
			)
			( gate "C5L10"
				( objectStatus "@baseboard_fab2_lib.baseboard_fab2(sch_1):page220_i232" )
				( pin "C5L10.1"
					( objectStatus "a" )
				)
				( pin "C5L10.2"
					( objectStatus "b" )
				)
			)
			( gate "C5L9"
				( objectStatus "@baseboard_fab2_lib.baseboard_fab2(sch_1):page220_i233" )
				( pin "C5L9.1"
					( objectStatus "a" )
				)
				( pin "C5L9.2"
					( objectStatus "b" )
				)
			)
			( gate "C5L8"
				( objectStatus "@baseboard_fab2_lib.baseboard_fab2(sch_1):page220_i234" )
				( pin "C5L8.1"
					( objectStatus "a" )
				)
				( pin "C5L8.2"
					( objectStatus "b" )
				)
			)
			( gate "C5L7"
				( objectStatus "@baseboard_fab2_lib.baseboard_fab2(sch_1):page220_i236" )
				( pin "C5L7.1"
					( objectStatus "a" )
				)
				( pin "C5L7.2"
					( objectStatus "b" )
				)
			)
			( gate "C5L6"
				( objectStatus "@baseboard_fab2_lib.baseboard_fab2(sch_1):page220_i237" )
				( pin "C5L6.1"
					( objectStatus "a" )
				)
				( pin "C5L6.2"
					( objectStatus "b" )
				)
			)
			( gate "EU4G3"
				( objectStatus "@baseboard_fab2_lib.baseboard_fab2(sch_1):page221_i1" )
				( pin "EU4G3.3"
					( objectStatus "agnd" )
				)
				( pin "EU4G3.2"
					( objectStatus "bias" )
				)
				( pin "EU4G3.7"
					( objectStatus "en" )
				)
				( pin "EU4G3.5"
					( objectStatus "pg" )
				)
				( pin "EU4G3.8"
					( objectStatus "pgnd" )
				)
				( pin "EU4G3.6"
					( objectStatus "sns" )
				)
				( pin "EU4G3.11"
					( objectStatus "thpad" )
				)
				( pin "EU4G3.4"
					( objectStatus "vddq" )
				)
				( pin "EU4G3.10"
					( objectStatus "vin" )
				)
				( pin "EU4G3.1"
					( objectStatus "vref" )
				)
				( pin "EU4G3.9"
					( objectStatus "vtt" )
				)
			)
			( gate "C4G14"
				( objectStatus "@baseboard_fab2_lib.baseboard_fab2(sch_1):page221_i15" )
				( pin "C4G14.1"
					( objectStatus "a" )
				)
				( pin "C4G14.2"
					( objectStatus "b" )
				)
			)
			( gate "R5U1"
				( objectStatus "@baseboard_fab2_lib.baseboard_fab2(sch_1):page221_i18" )
				( pin "R5U1.1"
					( objectStatus "a" )
				)
				( pin "R5U1.2"
					( objectStatus "b" )
				)
			)
			( gate "C4G24"
				( objectStatus "@baseboard_fab2_lib.baseboard_fab2(sch_1):page221_i20" )
				( pin "C4G24.1"
					( objectStatus "a" )
				)
				( pin "C4G24.2"
					( objectStatus "b" )
				)
			)
			( gate "C6U16"
				( objectStatus "@baseboard_fab2_lib.baseboard_fab2(sch_1):page221_i22" )
				( pin "C6U16.1"
					( objectStatus "a" )
				)
				( pin "C6U16.2"
					( objectStatus "b" )
				)
			)
			( gate "C4G15"
				( objectStatus "@baseboard_fab2_lib.baseboard_fab2(sch_1):page221_i24" )
				( pin "C4G15.1"
					( objectStatus "a" )
				)
				( pin "C4G15.2"
					( objectStatus "b" )
				)
			)
			( gate "C6U15"
				( objectStatus "@baseboard_fab2_lib.baseboard_fab2(sch_1):page221_i26" )
				( pin "C6U15.1"
					( objectStatus "a" )
				)
				( pin "C6U15.2"
					( objectStatus "b" )
				)
			)
			( gate "R6U4"
				( objectStatus "@baseboard_fab2_lib.baseboard_fab2(sch_1):page221_i28" )
				( pin "R6U4.1"
					( objectStatus "a" )
				)
				( pin "R6U4.2"
					( objectStatus "b" )
				)
			)
			( gate "R6U5"
				( objectStatus "@baseboard_fab2_lib.baseboard_fab2(sch_1):page221_i32" )
				( pin "R6U5.1"
					( objectStatus "a" )
				)
				( pin "R6U5.2"
					( objectStatus "b" )
				)
			)
			( gate "C4G16"
				( objectStatus "@baseboard_fab2_lib.baseboard_fab2(sch_1):page221_i34" )
				( pin "C4G16.1"
					( objectStatus "a" )
				)
				( pin "C4G16.2"
					( objectStatus "b" )
				)
			)
			( gate "R6U15"
				( objectStatus "@baseboard_fab2_lib.baseboard_fab2(sch_1):page221_i37" )
				( pin "R6U15.1"
					( objectStatus "a" )
				)
				( pin "R6U15.2"
					( objectStatus "b" )
				)
			)
			( gate "R4G23"
				( objectStatus "@baseboard_fab2_lib.baseboard_fab2(sch_1):page221_i38" )
				( pin "R4G23.1"
					( objectStatus "a" )
				)
				( pin "R4G23.2"
					( objectStatus "b" )
				)
			)
			( gate "C4G23"
				( objectStatus "@baseboard_fab2_lib.baseboard_fab2(sch_1):page221_i39" )
				( pin "C4G23.1"
					( objectStatus "a" )
				)
				( pin "C4G23.2"
					( objectStatus "b" )
				)
			)
			( gate "R4G18"
				( objectStatus "@baseboard_fab2_lib.baseboard_fab2(sch_1):page221_i45" )
				( pin "R4G18.1"
					( objectStatus "a" )
				)
				( pin "R4G18.2"
					( objectStatus "b" )
				)
			)
			( gate "C6U12"
				( objectStatus "@baseboard_fab2_lib.baseboard_fab2(sch_1):page221_i49" )
				( pin "C6U12.1"
					( objectStatus "a" )
				)
				( pin "C6U12.2"
					( objectStatus "b" )
				)
			)
			( gate "C5U12"
				( objectStatus "@baseboard_fab2_lib.baseboard_fab2(sch_1):page221_i50" )
				( pin "C5U12.1"
					( objectStatus "a" )
				)
				( pin "C5U12.2"
					( objectStatus "b" )
				)
			)
			( gate "C5T3"
				( objectStatus "@baseboard_fab2_lib.baseboard_fab2(sch_1):page221_i51" )
				( pin "C5T3.1"
					( objectStatus "a" )
				)
				( pin "C5T3.2"
					( objectStatus "b" )
				)
			)
			( gate "C5U16"
				( objectStatus "@baseboard_fab2_lib.baseboard_fab2(sch_1):page221_i52" )
				( pin "C5U16.1"
					( objectStatus "a" )
				)
				( pin "C5U16.2"
					( objectStatus "b" )
				)
			)
			( gate "R4G19"
				( objectStatus "@baseboard_fab2_lib.baseboard_fab2(sch_1):page221_i54" )
				( pin "R4G19.1"
					( objectStatus "a" )
				)
				( pin "R4G19.2"
					( objectStatus "b" )
				)
			)
			( gate "R6U16"
				( objectStatus "@baseboard_fab2_lib.baseboard_fab2(sch_1):page221_i55" )
				( pin "R6U16.1"
					( objectStatus "a" )
				)
				( pin "R6U16.2"
					( objectStatus "b" )
				)
			)
			( gate "C4A12"
				( objectStatus "@baseboard_fab2_lib.baseboard_fab2(sch_1):page222_i12" )
				( pin "C4A12.1"
					( objectStatus "a" )
				)
				( pin "C4A12.2"
					( objectStatus "b" )
				)
			)
			( gate "R5L1"
				( objectStatus "@baseboard_fab2_lib.baseboard_fab2(sch_1):page222_i15" )
				( pin "R5L1.1"
					( objectStatus "a" )
				)
				( pin "R5L1.2"
					( objectStatus "b" )
				)
			)
			( gate "C4A1"
				( objectStatus "@baseboard_fab2_lib.baseboard_fab2(sch_1):page222_i16" )
				( pin "C4A1.1"
					( objectStatus "a" )
				)
				( pin "C4A1.2"
					( objectStatus "b" )
				)
			)
			( gate "R6L9"
				( objectStatus "@baseboard_fab2_lib.baseboard_fab2(sch_1):page222_i19" )
				( pin "R6L9.1"
					( objectStatus "a" )
				)
				( pin "R6L9.2"
					( objectStatus "b" )
				)
			)
			( gate "C4A9"
				( objectStatus "@baseboard_fab2_lib.baseboard_fab2(sch_1):page222_i21" )
				( pin "C4A9.1"
					( objectStatus "a" )
				)
				( pin "C4A9.2"
					( objectStatus "b" )
				)
			)
			( gate "C6L3"
				( objectStatus "@baseboard_fab2_lib.baseboard_fab2(sch_1):page222_i24" )
				( pin "C6L3.1"
					( objectStatus "a" )
				)
				( pin "C6L3.2"
					( objectStatus "b" )
				)
			)
			( gate "C6L4"
				( objectStatus "@baseboard_fab2_lib.baseboard_fab2(sch_1):page222_i26" )
				( pin "C6L4.1"
					( objectStatus "a" )
				)
				( pin "C6L4.2"
					( objectStatus "b" )
				)
			)
			( gate "C4A10"
				( objectStatus "@baseboard_fab2_lib.baseboard_fab2(sch_1):page222_i28" )
				( pin "C4A10.1"
					( objectStatus "a" )
				)
				( pin "C4A10.2"
					( objectStatus "b" )
				)
			)
			( gate "R6L11"
				( objectStatus "@baseboard_fab2_lib.baseboard_fab2(sch_1):page222_i30" )
				( pin "R6L11.1"
					( objectStatus "a" )
				)
				( pin "R6L11.2"
					( objectStatus "b" )
				)
			)
			( gate "EU4A1"
				( objectStatus "@baseboard_fab2_lib.baseboard_fab2(sch_1):page222_i31" )
				( pin "EU4A1.3"
					( objectStatus "agnd" )
				)
				( pin "EU4A1.2"
					( objectStatus "bias" )
				)
				( pin "EU4A1.7"
					( objectStatus "en" )
				)
				( pin "EU4A1.5"
					( objectStatus "pg" )
				)
				( pin "EU4A1.8"
					( objectStatus "pgnd" )
				)
				( pin "EU4A1.6"
					( objectStatus "sns" )
				)
				( pin "EU4A1.11"
					( objectStatus "thpad" )
				)
				( pin "EU4A1.4"
					( objectStatus "vddq" )
				)
				( pin "EU4A1.10"
					( objectStatus "vin" )
				)
				( pin "EU4A1.1"
					( objectStatus "vref" )
				)
				( pin "EU4A1.9"
					( objectStatus "vtt" )
				)
			)
			( gate "R6L10"
				( objectStatus "@baseboard_fab2_lib.baseboard_fab2(sch_1):page222_i34" )
				( pin "R6L10.1"
					( objectStatus "a" )
				)
				( pin "R6L10.2"
					( objectStatus "b" )
				)
			)
			( gate "R6L4"
				( objectStatus "@baseboard_fab2_lib.baseboard_fab2(sch_1):page222_i37" )
				( pin "R6L4.1"
					( objectStatus "a" )
				)
				( pin "R6L4.2"
					( objectStatus "b" )
				)
			)
			( gate "R4A2"
				( objectStatus "@baseboard_fab2_lib.baseboard_fab2(sch_1):page222_i38" )
				( pin "R4A2.1"
					( objectStatus "a" )
				)
				( pin "R4A2.2"
					( objectStatus "b" )
				)
			)
			( gate "C4A2"
				( objectStatus "@baseboard_fab2_lib.baseboard_fab2(sch_1):page222_i40" )
				( pin "C4A2.1"
					( objectStatus "a" )
				)
				( pin "C4A2.2"
					( objectStatus "b" )
				)
			)
			( gate "C4A11"
				( objectStatus "@baseboard_fab2_lib.baseboard_fab2(sch_1):page222_i46" )
				( pin "C4A11.1"
					( objectStatus "a" )
				)
				( pin "C4A11.2"
					( objectStatus "b" )
				)
			)
			( gate "C5L4"
				( objectStatus "@baseboard_fab2_lib.baseboard_fab2(sch_1):page222_i47" )
				( pin "C5L4.1"
					( objectStatus "a" )
				)
				( pin "C5L4.2"
					( objectStatus "b" )
				)
			)
			( gate "C5M13"
				( objectStatus "@baseboard_fab2_lib.baseboard_fab2(sch_1):page222_i48" )
				( pin "C5M13.1"
					( objectStatus "a" )
				)
				( pin "C5M13.2"
					( objectStatus "b" )
				)
			)
			( gate "C5L5"
				( objectStatus "@baseboard_fab2_lib.baseboard_fab2(sch_1):page222_i49" )
				( pin "C5L5.1"
					( objectStatus "a" )
				)
				( pin "C5L5.2"
					( objectStatus "b" )
				)
			)
			( gate "R4A6"
				( objectStatus "@baseboard_fab2_lib.baseboard_fab2(sch_1):page222_i51" )
				( pin "R4A6.1"
					( objectStatus "a" )
				)
				( pin "R4A6.2"
					( objectStatus "b" )
				)
			)
			( gate "R4A1"
				( objectStatus "@baseboard_fab2_lib.baseboard_fab2(sch_1):page222_i52" )
				( pin "R4A1.1"
					( objectStatus "a" )
				)
				( pin "R4A1.2"
					( objectStatus "b" )
				)
			)
			( gate "R9U3"
				( objectStatus "@baseboard_fab2_lib.baseboard_fab2(sch_1):page223_i8" )
				( pin "R9U3.1"
					( objectStatus "a" )
				)
				( pin "R9U3.2"
					( objectStatus "b" )
				)
			)
			( gate "R1G6"
				( objectStatus "@baseboard_fab2_lib.baseboard_fab2(sch_1):page223_i13" )
				( pin "R1G6.1"
					( objectStatus "a" )
				)
				( pin "R1G6.2"
					( objectStatus "b" )
				)
			)
			( gate "R1G12"
				( objectStatus "@baseboard_fab2_lib.baseboard_fab2(sch_1):page223_i14" )
				( pin "R1G12.1"
					( objectStatus "a" )
				)
				( pin "R1G12.2"
					( objectStatus "b" )
				)
			)
			( gate "R1G9"
				( objectStatus "@baseboard_fab2_lib.baseboard_fab2(sch_1):page223_i16" )
				( pin "R1G9.1"
					( objectStatus "a" )
				)
				( pin "R1G9.2"
					( objectStatus "b" )
				)
			)
			( gate "R1G16"
				( objectStatus "@baseboard_fab2_lib.baseboard_fab2(sch_1):page223_i17" )
				( pin "R1G16.1"
					( objectStatus "a" )
				)
				( pin "R1G16.2"
					( objectStatus "b" )
				)
			)
			( gate "R1G19"
				( objectStatus "@baseboard_fab2_lib.baseboard_fab2(sch_1):page223_i21" )
				( pin "R1G19.1"
					( objectStatus "a" )
				)
				( pin "R1G19.2"
					( objectStatus "b" )
				)
			)
			( gate "R1G21"
				( objectStatus "@baseboard_fab2_lib.baseboard_fab2(sch_1):page223_i22" )
				( pin "R1G21.1"
					( objectStatus "a" )
				)
				( pin "R1G21.2"
					( objectStatus "b" )
				)
			)
			( gate "R1G10"
				( objectStatus "@baseboard_fab2_lib.baseboard_fab2(sch_1):page223_i23" )
				( pin "R1G10.1"
					( objectStatus "a" )
				)
				( pin "R1G10.2"
					( objectStatus "b" )
				)
			)
			( gate "C1G27"
				( objectStatus "@baseboard_fab2_lib.baseboard_fab2(sch_1):page223_i25" )
				( pin "C1G27.1"
					( objectStatus "a" )
				)
				( pin "C1G27.2"
					( objectStatus "b" )
				)
			)
			( gate "C1G25"
				( objectStatus "@baseboard_fab2_lib.baseboard_fab2(sch_1):page223_i27" )
				( pin "C1G25.1"
					( objectStatus "a" )
				)
				( pin "C1G25.2"
					( objectStatus "b" )
				)
			)
			( gate "R9U10"
				( objectStatus "@baseboard_fab2_lib.baseboard_fab2(sch_1):page223_i30" )
				( pin "R9U10.1"
					( objectStatus "a" )
				)
				( pin "R9U10.2"
					( objectStatus "b" )
				)
			)
			( gate "R1G5"
				( objectStatus "@baseboard_fab2_lib.baseboard_fab2(sch_1):page223_i32" )
				( pin "R1G5.1"
					( objectStatus "a" )
				)
				( pin "R1G5.2"
					( objectStatus "b" )
				)
			)
			( gate "C1G24"
				( objectStatus "@baseboard_fab2_lib.baseboard_fab2(sch_1):page223_i36" )
				( pin "C1G24.1"
					( objectStatus "a" )
				)
				( pin "C1G24.2"
					( objectStatus "b" )
				)
			)
			( gate "C1G16"
				( objectStatus "@baseboard_fab2_lib.baseboard_fab2(sch_1):page223_i39" )
				( pin "C1G16.1"
					( objectStatus "a" )
				)
				( pin "C1G16.2"
					( objectStatus "b" )
				)
			)
			( gate "C1G23"
				( objectStatus "@baseboard_fab2_lib.baseboard_fab2(sch_1):page223_i41" )
				( pin "C1G23.1"
					( objectStatus "a" )
				)
				( pin "C1G23.2"
					( objectStatus "b" )
				)
			)
			( gate "C1G22"
				( objectStatus "@baseboard_fab2_lib.baseboard_fab2(sch_1):page223_i44" )
				( pin "C1G22.1"
					( objectStatus "a" )
				)
				( pin "C1G22.2"
					( objectStatus "b" )
				)
			)
			( gate "R9U4"
				( objectStatus "@baseboard_fab2_lib.baseboard_fab2(sch_1):page223_i50" )
				( pin "R9U4.1"
					( objectStatus "a" )
				)
				( pin "R9U4.2"
					( objectStatus "b" )
				)
			)
			( gate "R1G7"
				( objectStatus "@baseboard_fab2_lib.baseboard_fab2(sch_1):page223_i53" )
				( pin "R1G7.1"
					( objectStatus "a" )
				)
				( pin "R1G7.2"
					( objectStatus "b" )
				)
			)
			( gate "R9U11"
				( objectStatus "@baseboard_fab2_lib.baseboard_fab2(sch_1):page223_i57" )
				( pin "R9U11.1"
					( objectStatus "a" )
				)
				( pin "R9U11.2"
					( objectStatus "b" )
				)
			)
			( gate "R1G24"
				( objectStatus "@baseboard_fab2_lib.baseboard_fab2(sch_1):page223_i58" )
				( pin "R1G24.1"
					( objectStatus "a" )
				)
				( pin "R1G24.2"
					( objectStatus "b" )
				)
			)
			( gate "C1G26"
				( objectStatus "@baseboard_fab2_lib.baseboard_fab2(sch_1):page223_i59" )
				( pin "C1G26.1"
					( objectStatus "a" )
				)
				( pin "C1G26.2"
					( objectStatus "b" )
				)
			)
			( gate "R1G23"
				( objectStatus "@baseboard_fab2_lib.baseboard_fab2(sch_1):page223_i77" )
				( pin "R1G23.1"
					( objectStatus "a" )
				)
				( pin "R1G23.2"
					( objectStatus "b" )
				)
			)
			( gate "R1G22"
				( objectStatus "@baseboard_fab2_lib.baseboard_fab2(sch_1):page223_i78" )
				( pin "R1G22.1"
					( objectStatus "a" )
				)
				( pin "R1G22.2"
					( objectStatus "b" )
				)
			)
			( gate "R1G11"
				( objectStatus "@baseboard_fab2_lib.baseboard_fab2(sch_1):page223_i79" )
				( pin "R1G11.1"
					( objectStatus "a" )
				)
				( pin "R1G11.2"
					( objectStatus "b" )
				)
			)
			( gate "C1G21"
				( objectStatus "@baseboard_fab2_lib.baseboard_fab2(sch_1):page223_i80" )
				( pin "C1G21.1"
					( objectStatus "a" )
				)
				( pin "C1G21.2"
					( objectStatus "b" )
				)
			)
			( gate "R1G8"
				( objectStatus "@baseboard_fab2_lib.baseboard_fab2(sch_1):page223_i82" )
				( pin "R1G8.1"
					( objectStatus "a" )
				)
				( pin "R1G8.2"
					( objectStatus "b" )
				)
			)
			( gate "R9U7"
				( objectStatus "@baseboard_fab2_lib.baseboard_fab2(sch_1):page223_i84" )
				( pin "R9U7.1"
					( objectStatus "a" )
				)
				( pin "R9U7.2"
					( objectStatus "b" )
				)
			)
			( gate "R9U8"
				( objectStatus "@baseboard_fab2_lib.baseboard_fab2(sch_1):page223_i85" )
				( pin "R9U8.1"
					( objectStatus "a" )
				)
				( pin "R9U8.2"
					( objectStatus "b" )
				)
			)
			( gate "R9U5"
				( objectStatus "@baseboard_fab2_lib.baseboard_fab2(sch_1):page223_i87" )
				( pin "R9U5.1"
					( objectStatus "a" )
				)
				( pin "R9U5.2"
					( objectStatus "b" )
				)
			)
			( gate "R9U6"
				( objectStatus "@baseboard_fab2_lib.baseboard_fab2(sch_1):page223_i88" )
				( pin "R9U6.1"
					( objectStatus "a" )
				)
				( pin "R9U6.2"
					( objectStatus "b" )
				)
			)
			( gate "EU1G2"
				( objectStatus "@baseboard_fab2_lib.baseboard_fab2(sch_1):page223_i90" )
				( pin "EU1G2.21"
					( objectStatus "airef1" )
				)
				( pin "EU1G2.23"
					( objectStatus "airef2" )
				)
				( pin "EU1G2.25"
					( objectStatus "airef3" )
				)
				( pin "EU1G2.22"
					( objectStatus "aisen1" )
				)
				( pin "EU1G2.24"
					( objectStatus "aisen2" )
				)
				( pin "EU1G2.26"
					( objectStatus "aisen3" )
				)
				( pin "EU1G2.5"
					( objectStatus "apwm1" )
				)
				( pin "EU1G2.4"
					( objectStatus "apwm2" )
				)
				( pin "EU1G2.3"
					( objectStatus "apwm3" )
				)
				( pin "EU1G2.35"
					( objectStatus "atsen" )
				)
				( pin "EU1G2.20"
					( objectStatus "avref" )
				)
				( pin "EU1G2.10"
					( objectStatus "avren" )
				)
				( pin "EU1G2.9"
					( objectStatus "avrrdy" )
				)
				( pin "EU1G2.19"
					( objectStatus "avsen" )
				)
				( pin "EU1G2.31"
					( objectStatus "biref1" )
				)
				( pin "EU1G2.32"
					( objectStatus "bisen1" )
				)
				( pin "EU1G2.1"
					( objectStatus "bpwm1" )
				)
				( pin "EU1G2.34"
					( objectStatus "btsen" )
				)
				( pin "EU1G2.30"
					( objectStatus "bvref" )
				)
				( pin "EU1G2.29"
					( objectStatus "bvsen" )
				)
				( pin "EU1G2.2"
					( objectStatus "dnc(0)" )
				)
				( pin "EU1G2.28"
					( objectStatus "dnc(1)" )
				)
				( pin "EU1G2.27"
					( objectStatus "gnd" )
				)
				( pin "EU1G2.38"
					( objectStatus "iinsen" )
				)
				( pin "EU1G2.13"
					( objectStatus "mp0" )
				)
				( pin "EU1G2.14"
					( objectStatus "mp1" )
				)
				( pin "EU1G2.18"
					( objectStatus "mp2" )
				)
				( pin "EU1G2.12"
					( objectStatus "pinalrt_n" )
				)
				( pin "EU1G2.8"
					( objectStatus "reset_n" )
				)
				( pin "EU1G2.7"
					( objectStatus "scl" )
				)
				( pin "EU1G2.6"
					( objectStatus "sda" )
				)
				( pin "EU1G2.41"
					( objectStatus "thpad" )
				)
				( pin "EU1G2.17"
					( objectStatus "valrt_n" )
				)
				( pin "EU1G2.15"
					( objectStatus "vclk" )
				)
				( pin "EU1G2.40"
					( objectStatus "vd12" )
				)
				( pin "EU1G2.39"
					( objectStatus "vdd" )
				)
				( pin "EU1G2.16"
					( objectStatus "vdio" )
				)
				( pin "EU1G2.37"
					( objectStatus "vinsen" )
				)
				( pin "EU1G2.11"
					( objectStatus "vrhot_n" )
				)
				( pin "EU1G2.36"
					( objectStatus "xaddr1" )
				)
				( pin "EU1G2.33"
					( objectStatus "xaddr2" )
				)
			)
			( gate "C9T2"
				( objectStatus "@baseboard_fab2_lib.baseboard_fab2(sch_1):page223_i92" )
				( pin "C9T2.1"
					( objectStatus "a" )
				)
				( pin "C9T2.2"
					( objectStatus "b" )
				)
			)
			( gate "C1G17"
				( objectStatus "@baseboard_fab2_lib.baseboard_fab2(sch_1):page224_i6" )
				( pin "C1G17.1"
					( objectStatus "a" )
				)
				( pin "C1G17.2"
					( objectStatus "b" )
				)
			)
			( gate "C1G11"
				( objectStatus "@baseboard_fab2_lib.baseboard_fab2(sch_1):page224_i44" )
				( pin "C1G11.1"
					( objectStatus "a" )
				)
				( pin "C1G11.2"
					( objectStatus "b" )
				)
			)
			( gate "C9U6"
				( objectStatus "@baseboard_fab2_lib.baseboard_fab2(sch_1):page224_i45" )
				( pin "C9U6.1"
					( objectStatus "a" )
				)
				( pin "C9U6.2"
					( objectStatus "b" )
				)
			)
			( gate "C9U4"
				( objectStatus "@baseboard_fab2_lib.baseboard_fab2(sch_1):page224_i46" )
				( pin "C9U4.1"
					( objectStatus "a" )
				)
				( pin "C9U4.2"
					( objectStatus "b" )
				)
			)
			( gate "C9T4"
				( objectStatus "@baseboard_fab2_lib.baseboard_fab2(sch_1):page224_i47" )
				( pin "C9T4.1"
					( objectStatus "a" )
				)
				( pin "C9T4.2"
					( objectStatus "b" )
				)
			)
			( gate "C1G1"
				( objectStatus "@baseboard_fab2_lib.baseboard_fab2(sch_1):page224_i48" )
				( pin "C1G1.1"
					( objectStatus "a" )
				)
				( pin "C1G1.2"
					( objectStatus "b" )
				)
			)
			( gate "C1G6"
				( objectStatus "@baseboard_fab2_lib.baseboard_fab2(sch_1):page224_i50" )
				( pin "C1G6.1"
					( objectStatus "a" )
				)
				( pin "C1G6.2"
					( objectStatus "b" )
				)
			)
			( gate "C1G14"
				( objectStatus "@baseboard_fab2_lib.baseboard_fab2(sch_1):page224_i51" )
				( pin "C1G14.1"
					( objectStatus "a" )
				)
				( pin "C1G14.2"
					( objectStatus "b" )
				)
			)
			( gate "R9U1"
				( objectStatus "@baseboard_fab2_lib.baseboard_fab2(sch_1):page224_i52" )
				( pin "R9U1.1"
					( objectStatus "a" )
				)
				( pin "R9U1.2"
					( objectStatus "b" )
				)
			)
			( gate "C1G4"
				( objectStatus "@baseboard_fab2_lib.baseboard_fab2(sch_1):page224_i53" )
				( pin "C1G4.1"
					( objectStatus "a" )
				)
				( pin "C1G4.2"
					( objectStatus "b" )
				)
			)
			( gate "C1G5"
				( objectStatus "@baseboard_fab2_lib.baseboard_fab2(sch_1):page224_i54" )
				( pin "C1G5.1"
					( objectStatus "a" )
				)
				( pin "C1G5.2"
					( objectStatus "b" )
				)
			)
			( gate "L1G1"
				( objectStatus "@baseboard_fab2_lib.baseboard_fab2(sch_1):page224_i55" )
				( pin "L1G1.1"
					( objectStatus "ina" )
				)
				( pin "L1G1.2"
					( objectStatus "inb" )
				)
			)
			( gate "L1F2"
				( objectStatus "@baseboard_fab2_lib.baseboard_fab2(sch_1):page224_i65" )
				( pin "L1F2.1"
					( objectStatus "ina" )
				)
				( pin "L1F2.2"
					( objectStatus "inb" )
				)
			)
			( gate "C1G20"
				( objectStatus "@baseboard_fab2_lib.baseboard_fab2(sch_1):page224_i68" )
				( pin "C1G20.1"
					( objectStatus "a" )
				)
				( pin "C1G20.2"
					( objectStatus "b" )
				)
			)
			( gate "C1F23"
				( objectStatus "@baseboard_fab2_lib.baseboard_fab2(sch_1):page224_i72" )
				( pin "C1F23.1"
					( objectStatus "a" )
				)
				( pin "C1F23.2"
					( objectStatus "b" )
				)
			)
			( gate "C1F21"
				( objectStatus "@baseboard_fab2_lib.baseboard_fab2(sch_1):page224_i73" )
				( pin "C1F21.1"
					( objectStatus "a" )
				)
				( pin "C1F21.2"
					( objectStatus "b" )
				)
			)
			( gate "C1F26"
				( objectStatus "@baseboard_fab2_lib.baseboard_fab2(sch_1):page224_i75" )
				( pin "C1F26.1"
					( objectStatus "a" )
				)
				( pin "C1F26.2"
					( objectStatus "b" )
				)
			)
			( gate "R9T10"
				( objectStatus "@baseboard_fab2_lib.baseboard_fab2(sch_1):page224_i76" )
				( pin "R9T10.1"
					( objectStatus "a" )
				)
				( pin "R9T10.2"
					( objectStatus "b" )
				)
			)
			( gate "C1F24"
				( objectStatus "@baseboard_fab2_lib.baseboard_fab2(sch_1):page224_i77" )
				( pin "C1F24.1"
					( objectStatus "a" )
				)
				( pin "C1F24.2"
					( objectStatus "b" )
				)
			)
			( gate "C1G3"
				( objectStatus "@baseboard_fab2_lib.baseboard_fab2(sch_1):page224_i78" )
				( pin "C1G3.1"
					( objectStatus "a" )
				)
				( pin "C1G3.2"
					( objectStatus "b" )
				)
			)
			( gate "C1G13"
				( objectStatus "@baseboard_fab2_lib.baseboard_fab2(sch_1):page224_i79" )
				( pin "C1G13.1"
					( objectStatus "a" )
				)
				( pin "C1G13.2"
					( objectStatus "b" )
				)
			)
			( gate "C9U3"
				( objectStatus "@baseboard_fab2_lib.baseboard_fab2(sch_1):page224_i80" )
				( pin "C9U3.1"
					( objectStatus "a" )
				)
				( pin "C9U3.2"
					( objectStatus "b" )
				)
			)
			( gate "C9T6"
				( objectStatus "@baseboard_fab2_lib.baseboard_fab2(sch_1):page224_i81" )
				( pin "C9T6.1"
					( objectStatus "a" )
				)
				( pin "C9T6.2"
					( objectStatus "b" )
				)
			)
			( gate "C9U1"
				( objectStatus "@baseboard_fab2_lib.baseboard_fab2(sch_1):page224_i84" )
				( pin "C9U1.1"
					( objectStatus "a" )
				)
				( pin "C9U1.2"
					( objectStatus "b" )
				)
			)
			( gate "EU1G1"
				( objectStatus "@baseboard_fab2_lib.baseboard_fab2(sch_1):page224_i110" )
				( pin "EU1G1.33"
					( objectStatus "boost" )
				)
				( pin "EU1G1.35"
					( objectStatus "en" )
				)
				( pin "EU1G1.6"
					( objectStatus "gl(0)" )
				)
				( pin "EU1G1.41"
					( objectStatus "gl(1)" )
				)
				( pin "EU1G1.38"
					( objectStatus "iout" )
				)
				( pin "EU1G1.2"
					( objectStatus "lgnd" )
				)
				( pin "EU1G1.31"
					( objectStatus "nc" )
				)
				( pin "EU1G1.37"
					( objectStatus "ocset" )
				)
				( pin "EU1G1.5"
					( objectStatus "pgnd(0)" )
				)
				( pin "EU1G1.7"
					( objectStatus "pgnd(1)" )
				)
				( pin "EU1G1.40"
					( objectStatus "pgnd(2)" )
				)
				( pin "EU1G1.32"
					( objectStatus "phase" )
				)
				( pin "EU1G1.34"
					( objectStatus "pwm" )
				)
				( pin "EU1G1.39"
					( objectStatus "refin" )
				)
				( pin "EU1G1.10"
					( objectStatus "sw" )
				)
				( pin "EU1G1.36"
					( objectStatus "tout_flt" )
				)
				( pin "EU1G1.3"
					( objectStatus "vcc" )
				)
				( pin "EU1G1.4"
					( objectStatus "vdrv" )
				)
				( pin "EU1G1.25"
					( objectStatus "vin(0)" )
				)
				( pin "EU1G1.30"
					( objectStatus "vin(1)" )
				)
				( pin "EU1G1.1"
					( objectStatus "vos" )
				)
			)
			( gate "EU1F1"
				( objectStatus "@baseboard_fab2_lib.baseboard_fab2(sch_1):page224_i111" )
				( pin "EU1F1.33"
					( objectStatus "boost" )
				)
				( pin "EU1F1.35"
					( objectStatus "en" )
				)
				( pin "EU1F1.6"
					( objectStatus "gl(0)" )
				)
				( pin "EU1F1.41"
					( objectStatus "gl(1)" )
				)
				( pin "EU1F1.38"
					( objectStatus "iout" )
				)
				( pin "EU1F1.2"
					( objectStatus "lgnd" )
				)
				( pin "EU1F1.31"
					( objectStatus "nc" )
				)
				( pin "EU1F1.37"
					( objectStatus "ocset" )
				)
				( pin "EU1F1.5"
					( objectStatus "pgnd(0)" )
				)
				( pin "EU1F1.7"
					( objectStatus "pgnd(1)" )
				)
				( pin "EU1F1.40"
					( objectStatus "pgnd(2)" )
				)
				( pin "EU1F1.32"
					( objectStatus "phase" )
				)
				( pin "EU1F1.34"
					( objectStatus "pwm" )
				)
				( pin "EU1F1.39"
					( objectStatus "refin" )
				)
				( pin "EU1F1.10"
					( objectStatus "sw" )
				)
				( pin "EU1F1.36"
					( objectStatus "tout_flt" )
				)
				( pin "EU1F1.3"
					( objectStatus "vcc" )
				)
				( pin "EU1F1.4"
					( objectStatus "vdrv" )
				)
				( pin "EU1F1.25"
					( objectStatus "vin(0)" )
				)
				( pin "EU1F1.30"
					( objectStatus "vin(1)" )
				)
				( pin "EU1F1.1"
					( objectStatus "vos" )
				)
			)
			( gate "R41"
				( objectStatus "@baseboard_fab2_lib.baseboard_fab2(sch_1):page224_i112" )
				( pin "R41.1"
					( objectStatus "a" )
				)
				( pin "R41.2"
					( objectStatus "b" )
				)
			)
			( gate "R42"
				( objectStatus "@baseboard_fab2_lib.baseboard_fab2(sch_1):page224_i114" )
				( pin "R42.1"
					( objectStatus "a" )
				)
				( pin "R42.2"
					( objectStatus "b" )
				)
			)
			( gate "R1G20"
				( objectStatus "@baseboard_fab2_lib.baseboard_fab2(sch_1):page225_i58" )
				( pin "R1G20.1"
					( objectStatus "a" )
				)
				( pin "R1G20.2"
					( objectStatus "b" )
				)
			)
			( gate "R7U3"
				( objectStatus "@baseboard_fab2_lib.baseboard_fab2(sch_1):page225_i67" )
				( pin "R7U3.1"
					( objectStatus "a" )
				)
				( pin "R7U3.2"
					( objectStatus "b" )
				)
			)
			( gate "R7U1"
				( objectStatus "@baseboard_fab2_lib.baseboard_fab2(sch_1):page225_i71" )
				( pin "R7U1.1"
					( objectStatus "a" )
				)
				( pin "R7U1.2"
					( objectStatus "b" )
				)
			)
			( gate "R7U2"
				( objectStatus "@baseboard_fab2_lib.baseboard_fab2(sch_1):page225_i74" )
				( pin "R7U2.1"
					( objectStatus "a" )
				)
				( pin "R7U2.2"
					( objectStatus "b" )
				)
			)
			( gate "C9T5"
				( objectStatus "@baseboard_fab2_lib.baseboard_fab2(sch_1):page225_i75" )
				( pin "C9T5.1"
					( objectStatus "a" )
				)
				( pin "C9T5.2"
					( objectStatus "b" )
				)
			)
			( gate "C9U2"
				( objectStatus "@baseboard_fab2_lib.baseboard_fab2(sch_1):page225_i76" )
				( pin "C9U2.1"
					( objectStatus "a" )
				)
				( pin "C9U2.2"
					( objectStatus "b" )
				)
			)
			( gate "C9U9"
				( objectStatus "@baseboard_fab2_lib.baseboard_fab2(sch_1):page225_i77" )
				( pin "C9U9.1"
					( objectStatus "a" )
				)
				( pin "C9U9.2"
					( objectStatus "b" )
				)
			)
			( gate "C9U5"
				( objectStatus "@baseboard_fab2_lib.baseboard_fab2(sch_1):page225_i78" )
				( pin "C9U5.1"
					( objectStatus "a" )
				)
				( pin "C9U5.2"
					( objectStatus "b" )
				)
			)
			( gate "C8U1"
				( objectStatus "@baseboard_fab2_lib.baseboard_fab2(sch_1):page225_i82" )
				( pin "C8U1.1"
					( objectStatus "a" )
				)
				( pin "C8U1.2"
					( objectStatus "b" )
				)
			)
			( gate "C8U8"
				( objectStatus "@baseboard_fab2_lib.baseboard_fab2(sch_1):page225_i83" )
				( pin "C8U8.1"
					( objectStatus "a" )
				)
				( pin "C8U8.2"
					( objectStatus "b" )
				)
			)
			( gate "C8U12"
				( objectStatus "@baseboard_fab2_lib.baseboard_fab2(sch_1):page225_i88" )
				( pin "C8U12.1"
					( objectStatus "a" )
				)
				( pin "C8U12.2"
					( objectStatus "b" )
				)
			)
			( gate "C8U11"
				( objectStatus "@baseboard_fab2_lib.baseboard_fab2(sch_1):page225_i89" )
				( pin "C8U11.1"
					( objectStatus "a" )
				)
				( pin "C8U11.2"
					( objectStatus "b" )
				)
			)
			( gate "C7T1"
				( objectStatus "@baseboard_fab2_lib.baseboard_fab2(sch_1):page225_i90" )
				( pin "C7T1.1"
					( objectStatus "a" )
				)
				( pin "C7T1.2"
					( objectStatus "b" )
				)
			)
			( gate "C7U7"
				( objectStatus "@baseboard_fab2_lib.baseboard_fab2(sch_1):page225_i91" )
				( pin "C7U7.1"
					( objectStatus "a" )
				)
				( pin "C7U7.2"
					( objectStatus "b" )
				)
			)
			( gate "C2G7"
				( objectStatus "@baseboard_fab2_lib.baseboard_fab2(sch_1):page225_i92" )
				( pin "C2G7.1"
					( objectStatus "a" )
				)
				( pin "C2G7.2"
					( objectStatus "b" )
				)
			)
			( gate "C2G16"
				( objectStatus "@baseboard_fab2_lib.baseboard_fab2(sch_1):page225_i110" )
				( pin "C2G16.1"
					( objectStatus "a" )
				)
				( pin "C2G16.2"
					( objectStatus "b" )
				)
			)
			( gate "L1F1"
				( objectStatus "@baseboard_fab2_lib.baseboard_fab2(sch_1):page225_i124" )
				( pin "L1F1.1"
					( objectStatus "ina" )
				)
				( pin "L1F1.2"
					( objectStatus "inb" )
				)
			)
			( gate "C8P31"
				( objectStatus "@baseboard_fab2_lib.baseboard_fab2(sch_1):page225_i178" )
				( pin "C8P31.1"
					( objectStatus "a" )
				)
				( pin "C8P31.2"
					( objectStatus "b" )
				)
			)
			( gate "C2D43"
				( objectStatus "@baseboard_fab2_lib.baseboard_fab2(sch_1):page225_i179" )
				( pin "C2D43.1"
					( objectStatus "a" )
				)
				( pin "C2D43.2"
					( objectStatus "b" )
				)
			)
			( gate "C2D41"
				( objectStatus "@baseboard_fab2_lib.baseboard_fab2(sch_1):page225_i180" )
				( pin "C2D41.1"
					( objectStatus "a" )
				)
				( pin "C2D41.2"
					( objectStatus "b" )
				)
			)
			( gate "C2D44"
				( objectStatus "@baseboard_fab2_lib.baseboard_fab2(sch_1):page225_i181" )
				( pin "C2D44.1"
					( objectStatus "a" )
				)
				( pin "C2D44.2"
					( objectStatus "b" )
				)
			)
			( gate "C2D42"
				( objectStatus "@baseboard_fab2_lib.baseboard_fab2(sch_1):page225_i183" )
				( pin "C2D42.1"
					( objectStatus "a" )
				)
				( pin "C2D42.2"
					( objectStatus "b" )
				)
			)
			( gate "C8P30"
				( objectStatus "@baseboard_fab2_lib.baseboard_fab2(sch_1):page225_i184" )
				( pin "C8P30.1"
					( objectStatus "a" )
				)
				( pin "C8P30.2"
					( objectStatus "b" )
				)
			)
			( gate "C1G15"
				( objectStatus "@baseboard_fab2_lib.baseboard_fab2(sch_1):page225_i192" )
				( pin "C1G15.1"
					( objectStatus "a" )
				)
				( pin "C1G15.2"
					( objectStatus "b" )
				)
			)
			( gate "C1G12"
				( objectStatus "@baseboard_fab2_lib.baseboard_fab2(sch_1):page225_i193" )
				( pin "C1G12.1"
					( objectStatus "a" )
				)
				( pin "C1G12.2"
					( objectStatus "b" )
				)
			)
			( gate "C1G2"
				( objectStatus "@baseboard_fab2_lib.baseboard_fab2(sch_1):page225_i194" )
				( pin "C1G2.1"
					( objectStatus "a" )
				)
				( pin "C1G2.2"
					( objectStatus "b" )
				)
			)
			( gate "C1G7"
				( objectStatus "@baseboard_fab2_lib.baseboard_fab2(sch_1):page225_i195" )
				( pin "C1G7.1"
					( objectStatus "a" )
				)
				( pin "C1G7.2"
					( objectStatus "b" )
				)
			)
			( gate "C8T4"
				( objectStatus "@baseboard_fab2_lib.baseboard_fab2(sch_1):page225_i196" )
				( pin "C8T4.1"
					( objectStatus "a" )
				)
				( pin "C8T4.2"
					( objectStatus "b" )
				)
			)
			( gate "C2G8"
				( objectStatus "@baseboard_fab2_lib.baseboard_fab2(sch_1):page225_i197" )
				( pin "C2G8.1"
					( objectStatus "a" )
				)
				( pin "C2G8.2"
					( objectStatus "b" )
				)
			)
			( gate "C8T2"
				( objectStatus "@baseboard_fab2_lib.baseboard_fab2(sch_1):page225_i198" )
				( pin "C8T2.1"
					( objectStatus "a" )
				)
				( pin "C8T2.2"
					( objectStatus "b" )
				)
			)
			( gate "C8U13"
				( objectStatus "@baseboard_fab2_lib.baseboard_fab2(sch_1):page225_i199" )
				( pin "C8U13.1"
					( objectStatus "a" )
				)
				( pin "C8U13.2"
					( objectStatus "b" )
				)
			)
			( gate "C2G15"
				( objectStatus "@baseboard_fab2_lib.baseboard_fab2(sch_1):page225_i200" )
				( pin "C2G15.1"
					( objectStatus "a" )
				)
				( pin "C2G15.2"
					( objectStatus "b" )
				)
			)
			( gate "C2F1"
				( objectStatus "@baseboard_fab2_lib.baseboard_fab2(sch_1):page225_i201" )
				( pin "C2F1.1"
					( objectStatus "a" )
				)
				( pin "C2F1.2"
					( objectStatus "b" )
				)
			)
			( gate "C8T1"
				( objectStatus "@baseboard_fab2_lib.baseboard_fab2(sch_1):page225_i202" )
				( pin "C8T1.1"
					( objectStatus "a" )
				)
				( pin "C8T1.2"
					( objectStatus "b" )
				)
			)
			( gate "C8U9"
				( objectStatus "@baseboard_fab2_lib.baseboard_fab2(sch_1):page225_i203" )
				( pin "C8U9.1"
					( objectStatus "a" )
				)
				( pin "C8U9.2"
					( objectStatus "b" )
				)
			)
			( gate "C8T11"
				( objectStatus "@baseboard_fab2_lib.baseboard_fab2(sch_1):page225_i204" )
				( pin "C8T11.1"
					( objectStatus "a" )
				)
				( pin "C8T11.2"
					( objectStatus "b" )
				)
			)
			( gate "C3G6"
				( objectStatus "@baseboard_fab2_lib.baseboard_fab2(sch_1):page225_i207" )
				( pin "C3G6.1"
					( objectStatus "a" )
				)
				( pin "C3G6.2"
					( objectStatus "b" )
				)
			)
			( gate "C3G5"
				( objectStatus "@baseboard_fab2_lib.baseboard_fab2(sch_1):page225_i208" )
				( pin "C3G5.1"
					( objectStatus "a" )
				)
				( pin "C3G5.2"
					( objectStatus "b" )
				)
			)
			( gate "C2G14"
				( objectStatus "@baseboard_fab2_lib.baseboard_fab2(sch_1):page225_i209" )
				( pin "C2G14.1"
					( objectStatus "a" )
				)
				( pin "C2G14.2"
					( objectStatus "b" )
				)
			)
			( gate "C2G13"
				( objectStatus "@baseboard_fab2_lib.baseboard_fab2(sch_1):page225_i210" )
				( pin "C2G13.1"
					( objectStatus "a" )
				)
				( pin "C2G13.2"
					( objectStatus "b" )
				)
			)
			( gate "C3G2"
				( objectStatus "@baseboard_fab2_lib.baseboard_fab2(sch_1):page225_i211" )
				( pin "C3G2.1"
					( objectStatus "a" )
				)
				( pin "C3G2.2"
					( objectStatus "b" )
				)
			)
			( gate "C3G1"
				( objectStatus "@baseboard_fab2_lib.baseboard_fab2(sch_1):page225_i212" )
				( pin "C3G1.1"
					( objectStatus "a" )
				)
				( pin "C3G1.2"
					( objectStatus "b" )
				)
			)
			( gate "C2G6"
				( objectStatus "@baseboard_fab2_lib.baseboard_fab2(sch_1):page225_i213" )
				( pin "C2G6.1"
					( objectStatus "a" )
				)
				( pin "C2G6.2"
					( objectStatus "b" )
				)
			)
			( gate "C2G5"
				( objectStatus "@baseboard_fab2_lib.baseboard_fab2(sch_1):page225_i214" )
				( pin "C2G5.1"
					( objectStatus "a" )
				)
				( pin "C2G5.2"
					( objectStatus "b" )
				)
			)
			( gate "C2G4"
				( objectStatus "@baseboard_fab2_lib.baseboard_fab2(sch_1):page225_i215" )
				( pin "C2G4.1"
					( objectStatus "a" )
				)
				( pin "C2G4.2"
					( objectStatus "b" )
				)
			)
			( gate "C2G3"
				( objectStatus "@baseboard_fab2_lib.baseboard_fab2(sch_1):page225_i216" )
				( pin "C2G3.1"
					( objectStatus "a" )
				)
				( pin "C2G3.2"
					( objectStatus "b" )
				)
			)
			( gate "C2G2"
				( objectStatus "@baseboard_fab2_lib.baseboard_fab2(sch_1):page225_i217" )
				( pin "C2G2.1"
					( objectStatus "a" )
				)
				( pin "C2G2.2"
					( objectStatus "b" )
				)
			)
			( gate "C2G9"
				( objectStatus "@baseboard_fab2_lib.baseboard_fab2(sch_1):page225_i218" )
				( pin "C2G9.1"
					( objectStatus "a" )
				)
				( pin "C2G9.2"
					( objectStatus "b" )
				)
			)
			( gate "C2G1"
				( objectStatus "@baseboard_fab2_lib.baseboard_fab2(sch_1):page225_i219" )
				( pin "C2G1.1"
					( objectStatus "a" )
				)
				( pin "C2G1.2"
					( objectStatus "b" )
				)
			)
			( gate "C2G12"
				( objectStatus "@baseboard_fab2_lib.baseboard_fab2(sch_1):page225_i220" )
				( pin "C2G12.1"
					( objectStatus "a" )
				)
				( pin "C2G12.2"
					( objectStatus "b" )
				)
			)
			( gate "C2G11"
				( objectStatus "@baseboard_fab2_lib.baseboard_fab2(sch_1):page225_i221" )
				( pin "C2G11.1"
					( objectStatus "a" )
				)
				( pin "C2G11.2"
					( objectStatus "b" )
				)
			)
			( gate "C2G10"
				( objectStatus "@baseboard_fab2_lib.baseboard_fab2(sch_1):page225_i223" )
				( pin "C2G10.1"
					( objectStatus "a" )
				)
				( pin "C2G10.2"
					( objectStatus "b" )
				)
			)
			( gate "C8U4"
				( objectStatus "@baseboard_fab2_lib.baseboard_fab2(sch_1):page225_i225" )
				( pin "C8U4.1"
					( objectStatus "a" )
				)
				( pin "C8U4.2"
					( objectStatus "b" )
				)
			)
			( gate "C8T10"
				( objectStatus "@baseboard_fab2_lib.baseboard_fab2(sch_1):page225_i226" )
				( pin "C8T10.1"
					( objectStatus "a" )
				)
				( pin "C8T10.2"
					( objectStatus "b" )
				)
			)
			( gate "C8T9"
				( objectStatus "@baseboard_fab2_lib.baseboard_fab2(sch_1):page225_i227" )
				( pin "C8T9.1"
					( objectStatus "a" )
				)
				( pin "C8T9.2"
					( objectStatus "b" )
				)
			)
			( gate "C8U5"
				( objectStatus "@baseboard_fab2_lib.baseboard_fab2(sch_1):page225_i228" )
				( pin "C8U5.1"
					( objectStatus "a" )
				)
				( pin "C8U5.2"
					( objectStatus "b" )
				)
			)
			( gate "C8T8"
				( objectStatus "@baseboard_fab2_lib.baseboard_fab2(sch_1):page225_i229" )
				( pin "C8T8.1"
					( objectStatus "a" )
				)
				( pin "C8T8.2"
					( objectStatus "b" )
				)
			)
			( gate "C8T7"
				( objectStatus "@baseboard_fab2_lib.baseboard_fab2(sch_1):page225_i230" )
				( pin "C8T7.1"
					( objectStatus "a" )
				)
				( pin "C8T7.2"
					( objectStatus "b" )
				)
			)
			( gate "C8T6"
				( objectStatus "@baseboard_fab2_lib.baseboard_fab2(sch_1):page225_i231" )
				( pin "C8T6.1"
					( objectStatus "a" )
				)
				( pin "C8T6.2"
					( objectStatus "b" )
				)
			)
			( gate "C8U6"
				( objectStatus "@baseboard_fab2_lib.baseboard_fab2(sch_1):page225_i232" )
				( pin "C8U6.1"
					( objectStatus "a" )
				)
				( pin "C8U6.2"
					( objectStatus "b" )
				)
			)
			( gate "C8T5"
				( objectStatus "@baseboard_fab2_lib.baseboard_fab2(sch_1):page225_i233" )
				( pin "C8T5.1"
					( objectStatus "a" )
				)
				( pin "C8T5.2"
					( objectStatus "b" )
				)
			)
			( gate "C7T5"
				( objectStatus "@baseboard_fab2_lib.baseboard_fab2(sch_1):page225_i234" )
				( pin "C7T5.1"
					( objectStatus "a" )
				)
				( pin "C7T5.2"
					( objectStatus "b" )
				)
			)
			( gate "C7T4"
				( objectStatus "@baseboard_fab2_lib.baseboard_fab2(sch_1):page225_i235" )
				( pin "C7T4.1"
					( objectStatus "a" )
				)
				( pin "C7T4.2"
					( objectStatus "b" )
				)
			)
			( gate "C8U3"
				( objectStatus "@baseboard_fab2_lib.baseboard_fab2(sch_1):page225_i236" )
				( pin "C8U3.1"
					( objectStatus "a" )
				)
				( pin "C8U3.2"
					( objectStatus "b" )
				)
			)
			( gate "C7U1"
				( objectStatus "@baseboard_fab2_lib.baseboard_fab2(sch_1):page225_i237" )
				( pin "C7U1.1"
					( objectStatus "a" )
				)
				( pin "C7U1.2"
					( objectStatus "b" )
				)
			)
			( gate "C7U2"
				( objectStatus "@baseboard_fab2_lib.baseboard_fab2(sch_1):page225_i238" )
				( pin "C7U2.1"
					( objectStatus "a" )
				)
				( pin "C7U2.2"
					( objectStatus "b" )
				)
			)
			( gate "C8U2"
				( objectStatus "@baseboard_fab2_lib.baseboard_fab2(sch_1):page225_i239" )
				( pin "C8U2.1"
					( objectStatus "a" )
				)
				( pin "C8U2.2"
					( objectStatus "b" )
				)
			)
			( gate "C8U7"
				( objectStatus "@baseboard_fab2_lib.baseboard_fab2(sch_1):page225_i241" )
				( pin "C8U7.1"
					( objectStatus "a" )
				)
				( pin "C8U7.2"
					( objectStatus "b" )
				)
			)
			( gate "R9M7"
				( objectStatus "@baseboard_fab2_lib.baseboard_fab2(sch_1):page226_i8" )
				( pin "R9M7.1"
					( objectStatus "a" )
				)
				( pin "R9M7.2"
					( objectStatus "b" )
				)
			)
			( gate "R1B13"
				( objectStatus "@baseboard_fab2_lib.baseboard_fab2(sch_1):page226_i13" )
				( pin "R1B13.1"
					( objectStatus "a" )
				)
				( pin "R1B13.2"
					( objectStatus "b" )
				)
			)
			( gate "R1B5"
				( objectStatus "@baseboard_fab2_lib.baseboard_fab2(sch_1):page226_i14" )
				( pin "R1B5.1"
					( objectStatus "a" )
				)
				( pin "R1B5.2"
					( objectStatus "b" )
				)
			)
			( gate "R1B11"
				( objectStatus "@baseboard_fab2_lib.baseboard_fab2(sch_1):page226_i16" )
				( pin "R1B11.1"
					( objectStatus "a" )
				)
				( pin "R1B11.2"
					( objectStatus "b" )
				)
			)
			( gate "R1B2"
				( objectStatus "@baseboard_fab2_lib.baseboard_fab2(sch_1):page226_i17" )
				( pin "R1B2.1"
					( objectStatus "a" )
				)
				( pin "R1B2.2"
					( objectStatus "b" )
				)
			)
			( gate "R1B6"
				( objectStatus "@baseboard_fab2_lib.baseboard_fab2(sch_1):page226_i21" )
				( pin "R1B6.1"
					( objectStatus "a" )
				)
				( pin "R1B6.2"
					( objectStatus "b" )
				)
			)
			( gate "R1B7"
				( objectStatus "@baseboard_fab2_lib.baseboard_fab2(sch_1):page226_i22" )
				( pin "R1B7.1"
					( objectStatus "a" )
				)
				( pin "R1B7.2"
					( objectStatus "b" )
				)
			)
			( gate "R1B10"
				( objectStatus "@baseboard_fab2_lib.baseboard_fab2(sch_1):page226_i23" )
				( pin "R1B10.1"
					( objectStatus "a" )
				)
				( pin "R1B10.2"
					( objectStatus "b" )
				)
			)
			( gate "C1B6"
				( objectStatus "@baseboard_fab2_lib.baseboard_fab2(sch_1):page226_i25" )
				( pin "C1B6.1"
					( objectStatus "a" )
				)
				( pin "C1B6.2"
					( objectStatus "b" )
				)
			)
			( gate "C1B5"
				( objectStatus "@baseboard_fab2_lib.baseboard_fab2(sch_1):page226_i27" )
				( pin "C1B5.1"
					( objectStatus "a" )
				)
				( pin "C1B5.2"
					( objectStatus "b" )
				)
			)
			( gate "R9M3"
				( objectStatus "@baseboard_fab2_lib.baseboard_fab2(sch_1):page226_i30" )
				( pin "R9M3.1"
					( objectStatus "a" )
				)
				( pin "R9M3.2"
					( objectStatus "b" )
				)
			)
			( gate "R1B16"
				( objectStatus "@baseboard_fab2_lib.baseboard_fab2(sch_1):page226_i32" )
				( pin "R1B16.1"
					( objectStatus "a" )
				)
				( pin "R1B16.2"
					( objectStatus "b" )
				)
			)
			( gate "C1B11"
				( objectStatus "@baseboard_fab2_lib.baseboard_fab2(sch_1):page226_i36" )
				( pin "C1B11.1"
					( objectStatus "a" )
				)
				( pin "C1B11.2"
					( objectStatus "b" )
				)
			)
			( gate "C1B12"
				( objectStatus "@baseboard_fab2_lib.baseboard_fab2(sch_1):page226_i39" )
				( pin "C1B12.1"
					( objectStatus "a" )
				)
				( pin "C1B12.2"
					( objectStatus "b" )
				)
			)
			( gate "C1B3"
				( objectStatus "@baseboard_fab2_lib.baseboard_fab2(sch_1):page226_i41" )
				( pin "C1B3.1"
					( objectStatus "a" )
				)
				( pin "C1B3.2"
					( objectStatus "b" )
				)
			)
			( gate "C1B2"
				( objectStatus "@baseboard_fab2_lib.baseboard_fab2(sch_1):page226_i44" )
				( pin "C1B2.1"
					( objectStatus "a" )
				)
				( pin "C1B2.2"
					( objectStatus "b" )
				)
			)
			( gate "R9M6"
				( objectStatus "@baseboard_fab2_lib.baseboard_fab2(sch_1):page226_i50" )
				( pin "R9M6.1"
					( objectStatus "a" )
				)
				( pin "R9M6.2"
					( objectStatus "b" )
				)
			)
			( gate "R1B8"
				( objectStatus "@baseboard_fab2_lib.baseboard_fab2(sch_1):page226_i53" )
				( pin "R1B8.1"
					( objectStatus "a" )
				)
				( pin "R1B8.2"
					( objectStatus "b" )
				)
			)
			( gate "R9M8"
				( objectStatus "@baseboard_fab2_lib.baseboard_fab2(sch_1):page226_i57" )
				( pin "R9M8.1"
					( objectStatus "a" )
				)
				( pin "R9M8.2"
					( objectStatus "b" )
				)
			)
			( gate "R1B9"
				( objectStatus "@baseboard_fab2_lib.baseboard_fab2(sch_1):page226_i58" )
				( pin "R1B9.1"
					( objectStatus "a" )
				)
				( pin "R1B9.2"
					( objectStatus "b" )
				)
			)
			( gate "C1B8"
				( objectStatus "@baseboard_fab2_lib.baseboard_fab2(sch_1):page226_i59" )
				( pin "C1B8.1"
					( objectStatus "a" )
				)
				( pin "C1B8.2"
					( objectStatus "b" )
				)
			)
			( gate "R1B15"
				( objectStatus "@baseboard_fab2_lib.baseboard_fab2(sch_1):page226_i77" )
				( pin "R1B15.1"
					( objectStatus "a" )
				)
				( pin "R1B15.2"
					( objectStatus "b" )
				)
			)
			( gate "R1B12"
				( objectStatus "@baseboard_fab2_lib.baseboard_fab2(sch_1):page226_i78" )
				( pin "R1B12.1"
					( objectStatus "a" )
				)
				( pin "R1B12.2"
					( objectStatus "b" )
				)
			)
			( gate "R1B1"
				( objectStatus "@baseboard_fab2_lib.baseboard_fab2(sch_1):page226_i79" )
				( pin "R1B1.1"
					( objectStatus "a" )
				)
				( pin "R1B1.2"
					( objectStatus "b" )
				)
			)
			( gate "C1B4"
				( objectStatus "@baseboard_fab2_lib.baseboard_fab2(sch_1):page226_i80" )
				( pin "C1B4.1"
					( objectStatus "a" )
				)
				( pin "C1B4.2"
					( objectStatus "b" )
				)
			)
			( gate "R1B4"
				( objectStatus "@baseboard_fab2_lib.baseboard_fab2(sch_1):page226_i82" )
				( pin "R1B4.1"
					( objectStatus "a" )
				)
				( pin "R1B4.2"
					( objectStatus "b" )
				)
			)
			( gate "R9M9"
				( objectStatus "@baseboard_fab2_lib.baseboard_fab2(sch_1):page226_i84" )
				( pin "R9M9.1"
					( objectStatus "a" )
				)
				( pin "R9M9.2"
					( objectStatus "b" )
				)
			)
			( gate "R9M5"
				( objectStatus "@baseboard_fab2_lib.baseboard_fab2(sch_1):page226_i85" )
				( pin "R9M5.1"
					( objectStatus "a" )
				)
				( pin "R9M5.2"
					( objectStatus "b" )
				)
			)
			( gate "R9M11"
				( objectStatus "@baseboard_fab2_lib.baseboard_fab2(sch_1):page226_i87" )
				( pin "R9M11.1"
					( objectStatus "a" )
				)
				( pin "R9M11.2"
					( objectStatus "b" )
				)
			)
			( gate "R9M10"
				( objectStatus "@baseboard_fab2_lib.baseboard_fab2(sch_1):page226_i88" )
				( pin "R9M10.1"
					( objectStatus "a" )
				)
				( pin "R9M10.2"
					( objectStatus "b" )
				)
			)
			( gate "EU1B1"
				( objectStatus "@baseboard_fab2_lib.baseboard_fab2(sch_1):page226_i90" )
				( pin "EU1B1.21"
					( objectStatus "airef1" )
				)
				( pin "EU1B1.23"
					( objectStatus "airef2" )
				)
				( pin "EU1B1.25"
					( objectStatus "airef3" )
				)
				( pin "EU1B1.22"
					( objectStatus "aisen1" )
				)
				( pin "EU1B1.24"
					( objectStatus "aisen2" )
				)
				( pin "EU1B1.26"
					( objectStatus "aisen3" )
				)
				( pin "EU1B1.5"
					( objectStatus "apwm1" )
				)
				( pin "EU1B1.4"
					( objectStatus "apwm2" )
				)
				( pin "EU1B1.3"
					( objectStatus "apwm3" )
				)
				( pin "EU1B1.35"
					( objectStatus "atsen" )
				)
				( pin "EU1B1.20"
					( objectStatus "avref" )
				)
				( pin "EU1B1.10"
					( objectStatus "avren" )
				)
				( pin "EU1B1.9"
					( objectStatus "avrrdy" )
				)
				( pin "EU1B1.19"
					( objectStatus "avsen" )
				)
				( pin "EU1B1.31"
					( objectStatus "biref1" )
				)
				( pin "EU1B1.32"
					( objectStatus "bisen1" )
				)
				( pin "EU1B1.1"
					( objectStatus "bpwm1" )
				)
				( pin "EU1B1.34"
					( objectStatus "btsen" )
				)
				( pin "EU1B1.30"
					( objectStatus "bvref" )
				)
				( pin "EU1B1.29"
					( objectStatus "bvsen" )
				)
				( pin "EU1B1.2"
					( objectStatus "dnc(0)" )
				)
				( pin "EU1B1.28"
					( objectStatus "dnc(1)" )
				)
				( pin "EU1B1.27"
					( objectStatus "gnd" )
				)
				( pin "EU1B1.38"
					( objectStatus "iinsen" )
				)
				( pin "EU1B1.13"
					( objectStatus "mp0" )
				)
				( pin "EU1B1.14"
					( objectStatus "mp1" )
				)
				( pin "EU1B1.18"
					( objectStatus "mp2" )
				)
				( pin "EU1B1.12"
					( objectStatus "pinalrt_n" )
				)
				( pin "EU1B1.8"
					( objectStatus "reset_n" )
				)
				( pin "EU1B1.7"
					( objectStatus "scl" )
				)
				( pin "EU1B1.6"
					( objectStatus "sda" )
				)
				( pin "EU1B1.41"
					( objectStatus "thpad" )
				)
				( pin "EU1B1.17"
					( objectStatus "valrt_n" )
				)
				( pin "EU1B1.15"
					( objectStatus "vclk" )
				)
				( pin "EU1B1.40"
					( objectStatus "vd12" )
				)
				( pin "EU1B1.39"
					( objectStatus "vdd" )
				)
				( pin "EU1B1.16"
					( objectStatus "vdio" )
				)
				( pin "EU1B1.37"
					( objectStatus "vinsen" )
				)
				( pin "EU1B1.11"
					( objectStatus "vrhot_n" )
				)
				( pin "EU1B1.36"
					( objectStatus "xaddr1" )
				)
				( pin "EU1B1.33"
					( objectStatus "xaddr2" )
				)
			)
			( gate "C1B13"
				( objectStatus "@baseboard_fab2_lib.baseboard_fab2(sch_1):page226_i92" )
				( pin "C1B13.1"
					( objectStatus "a" )
				)
				( pin "C1B13.2"
					( objectStatus "b" )
				)
			)
			( gate "C1A12"
				( objectStatus "@baseboard_fab2_lib.baseboard_fab2(sch_1):page227_i6" )
				( pin "C1A12.1"
					( objectStatus "a" )
				)
				( pin "C1A12.2"
					( objectStatus "b" )
				)
			)
			( gate "C1A18"
				( objectStatus "@baseboard_fab2_lib.baseboard_fab2(sch_1):page227_i44" )
				( pin "C1A18.1"
					( objectStatus "a" )
				)
				( pin "C1A18.2"
					( objectStatus "b" )
				)
			)
			( gate "C9L11"
				( objectStatus "@baseboard_fab2_lib.baseboard_fab2(sch_1):page227_i45" )
				( pin "C9L11.1"
					( objectStatus "a" )
				)
				( pin "C9L11.2"
					( objectStatus "b" )
				)
			)
			( gate "C9L10"
				( objectStatus "@baseboard_fab2_lib.baseboard_fab2(sch_1):page227_i46" )
				( pin "C9L10.1"
					( objectStatus "a" )
				)
				( pin "C9L10.2"
					( objectStatus "b" )
				)
			)
			( gate "C9L6"
				( objectStatus "@baseboard_fab2_lib.baseboard_fab2(sch_1):page227_i47" )
				( pin "C9L6.1"
					( objectStatus "a" )
				)
				( pin "C9L6.2"
					( objectStatus "b" )
				)
			)
			( gate "C1A19"
				( objectStatus "@baseboard_fab2_lib.baseboard_fab2(sch_1):page227_i48" )
				( pin "C1A19.1"
					( objectStatus "a" )
				)
				( pin "C1A19.2"
					( objectStatus "b" )
				)
			)
			( gate "C1A14"
				( objectStatus "@baseboard_fab2_lib.baseboard_fab2(sch_1):page227_i50" )
				( pin "C1A14.1"
					( objectStatus "a" )
				)
				( pin "C1A14.2"
					( objectStatus "b" )
				)
			)
			( gate "C1A10"
				( objectStatus "@baseboard_fab2_lib.baseboard_fab2(sch_1):page227_i51" )
				( pin "C1A10.1"
					( objectStatus "a" )
				)
				( pin "C1A10.2"
					( objectStatus "b" )
				)
			)
			( gate "R9L9"
				( objectStatus "@baseboard_fab2_lib.baseboard_fab2(sch_1):page227_i52" )
				( pin "R9L9.1"
					( objectStatus "a" )
				)
				( pin "R9L9.2"
					( objectStatus "b" )
				)
			)
			( gate "C1A2"
				( objectStatus "@baseboard_fab2_lib.baseboard_fab2(sch_1):page227_i53" )
				( pin "C1A2.1"
					( objectStatus "a" )
				)
				( pin "C1A2.2"
					( objectStatus "b" )
				)
			)
			( gate "C1A3"
				( objectStatus "@baseboard_fab2_lib.baseboard_fab2(sch_1):page227_i54" )
				( pin "C1A3.1"
					( objectStatus "a" )
				)
				( pin "C1A3.2"
					( objectStatus "b" )
				)
			)
			( gate "L1A2"
				( objectStatus "@baseboard_fab2_lib.baseboard_fab2(sch_1):page227_i55" )
				( pin "L1A2.1"
					( objectStatus "ina" )
				)
				( pin "L1A2.2"
					( objectStatus "inb" )
				)
			)
			( gate "L1A1"
				( objectStatus "@baseboard_fab2_lib.baseboard_fab2(sch_1):page227_i65" )
				( pin "L1A1.1"
					( objectStatus "ina" )
				)
				( pin "L1A1.2"
					( objectStatus "inb" )
				)
			)
			( gate "C1A1"
				( objectStatus "@baseboard_fab2_lib.baseboard_fab2(sch_1):page227_i68" )
				( pin "C1A1.1"
					( objectStatus "a" )
				)
				( pin "C1A1.2"
					( objectStatus "b" )
				)
			)
			( gate "C1A13"
				( objectStatus "@baseboard_fab2_lib.baseboard_fab2(sch_1):page227_i72" )
				( pin "C1A13.1"
					( objectStatus "a" )
				)
				( pin "C1A13.2"
					( objectStatus "b" )
				)
			)
			( gate "C1A11"
				( objectStatus "@baseboard_fab2_lib.baseboard_fab2(sch_1):page227_i73" )
				( pin "C1A11.1"
					( objectStatus "a" )
				)
				( pin "C1A11.2"
					( objectStatus "b" )
				)
			)
			( gate "C1A8"
				( objectStatus "@baseboard_fab2_lib.baseboard_fab2(sch_1):page227_i75" )
				( pin "C1A8.1"
					( objectStatus "a" )
				)
				( pin "C1A8.2"
					( objectStatus "b" )
				)
			)
			( gate "R9L4"
				( objectStatus "@baseboard_fab2_lib.baseboard_fab2(sch_1):page227_i76" )
				( pin "R9L4.1"
					( objectStatus "a" )
				)
				( pin "R9L4.2"
					( objectStatus "b" )
				)
			)
			( gate "C1A6"
				( objectStatus "@baseboard_fab2_lib.baseboard_fab2(sch_1):page227_i77" )
				( pin "C1A6.1"
					( objectStatus "a" )
				)
				( pin "C1A6.2"
					( objectStatus "b" )
				)
			)
			( gate "C1A20"
				( objectStatus "@baseboard_fab2_lib.baseboard_fab2(sch_1):page227_i78" )
				( pin "C1A20.1"
					( objectStatus "a" )
				)
				( pin "C1A20.2"
					( objectStatus "b" )
				)
			)
			( gate "C1A9"
				( objectStatus "@baseboard_fab2_lib.baseboard_fab2(sch_1):page227_i79" )
				( pin "C1A9.1"
					( objectStatus "a" )
				)
				( pin "C1A9.2"
					( objectStatus "b" )
				)
			)
			( gate "C9L5"
				( objectStatus "@baseboard_fab2_lib.baseboard_fab2(sch_1):page227_i80" )
				( pin "C9L5.1"
					( objectStatus "a" )
				)
				( pin "C9L5.2"
					( objectStatus "b" )
				)
			)
			( gate "C9L13"
				( objectStatus "@baseboard_fab2_lib.baseboard_fab2(sch_1):page227_i81" )
				( pin "C9L13.1"
					( objectStatus "a" )
				)
				( pin "C9L13.2"
					( objectStatus "b" )
				)
			)
			( gate "C9L14"
				( objectStatus "@baseboard_fab2_lib.baseboard_fab2(sch_1):page227_i84" )
				( pin "C9L14.1"
					( objectStatus "a" )
				)
				( pin "C9L14.2"
					( objectStatus "b" )
				)
			)
			( gate "EU1A2"
				( objectStatus "@baseboard_fab2_lib.baseboard_fab2(sch_1):page227_i101" )
				( pin "EU1A2.33"
					( objectStatus "boost" )
				)
				( pin "EU1A2.35"
					( objectStatus "en" )
				)
				( pin "EU1A2.6"
					( objectStatus "gl(0)" )
				)
				( pin "EU1A2.41"
					( objectStatus "gl(1)" )
				)
				( pin "EU1A2.38"
					( objectStatus "iout" )
				)
				( pin "EU1A2.2"
					( objectStatus "lgnd" )
				)
				( pin "EU1A2.31"
					( objectStatus "nc" )
				)
				( pin "EU1A2.37"
					( objectStatus "ocset" )
				)
				( pin "EU1A2.5"
					( objectStatus "pgnd(0)" )
				)
				( pin "EU1A2.7"
					( objectStatus "pgnd(1)" )
				)
				( pin "EU1A2.40"
					( objectStatus "pgnd(2)" )
				)
				( pin "EU1A2.32"
					( objectStatus "phase" )
				)
				( pin "EU1A2.34"
					( objectStatus "pwm" )
				)
				( pin "EU1A2.39"
					( objectStatus "refin" )
				)
				( pin "EU1A2.10"
					( objectStatus "sw" )
				)
				( pin "EU1A2.36"
					( objectStatus "tout_flt" )
				)
				( pin "EU1A2.3"
					( objectStatus "vcc" )
				)
				( pin "EU1A2.4"
					( objectStatus "vdrv" )
				)
				( pin "EU1A2.25"
					( objectStatus "vin(0)" )
				)
				( pin "EU1A2.30"
					( objectStatus "vin(1)" )
				)
				( pin "EU1A2.1"
					( objectStatus "vos" )
				)
			)
			( gate "EU1A1"
				( objectStatus "@baseboard_fab2_lib.baseboard_fab2(sch_1):page227_i102" )
				( pin "EU1A1.33"
					( objectStatus "boost" )
				)
				( pin "EU1A1.35"
					( objectStatus "en" )
				)
				( pin "EU1A1.6"
					( objectStatus "gl(0)" )
				)
				( pin "EU1A1.41"
					( objectStatus "gl(1)" )
				)
				( pin "EU1A1.38"
					( objectStatus "iout" )
				)
				( pin "EU1A1.2"
					( objectStatus "lgnd" )
				)
				( pin "EU1A1.31"
					( objectStatus "nc" )
				)
				( pin "EU1A1.37"
					( objectStatus "ocset" )
				)
				( pin "EU1A1.5"
					( objectStatus "pgnd(0)" )
				)
				( pin "EU1A1.7"
					( objectStatus "pgnd(1)" )
				)
				( pin "EU1A1.40"
					( objectStatus "pgnd(2)" )
				)
				( pin "EU1A1.32"
					( objectStatus "phase" )
				)
				( pin "EU1A1.34"
					( objectStatus "pwm" )
				)
				( pin "EU1A1.39"
					( objectStatus "refin" )
				)
				( pin "EU1A1.10"
					( objectStatus "sw" )
				)
				( pin "EU1A1.36"
					( objectStatus "tout_flt" )
				)
				( pin "EU1A1.3"
					( objectStatus "vcc" )
				)
				( pin "EU1A1.4"
					( objectStatus "vdrv" )
				)
				( pin "EU1A1.25"
					( objectStatus "vin(0)" )
				)
				( pin "EU1A1.30"
					( objectStatus "vin(1)" )
				)
				( pin "EU1A1.1"
					( objectStatus "vos" )
				)
			)
			( gate "R44"
				( objectStatus "@baseboard_fab2_lib.baseboard_fab2(sch_1):page227_i103" )
				( pin "R44.1"
					( objectStatus "a" )
				)
				( pin "R44.2"
					( objectStatus "b" )
				)
			)
			( gate "R43"
				( objectStatus "@baseboard_fab2_lib.baseboard_fab2(sch_1):page227_i105" )
				( pin "R43.1"
					( objectStatus "a" )
				)
				( pin "R43.2"
					( objectStatus "b" )
				)
			)
			( gate "R1A1"
				( objectStatus "@baseboard_fab2_lib.baseboard_fab2(sch_1):page228_i58" )
				( pin "R1A1.1"
					( objectStatus "a" )
				)
				( pin "R1A1.2"
					( objectStatus "b" )
				)
			)
			( gate "R7L1"
				( objectStatus "@baseboard_fab2_lib.baseboard_fab2(sch_1):page228_i67" )
				( pin "R7L1.1"
					( objectStatus "a" )
				)
				( pin "R7L1.2"
					( objectStatus "b" )
				)
			)
			( gate "R7L3"
				( objectStatus "@baseboard_fab2_lib.baseboard_fab2(sch_1):page228_i71" )
				( pin "R7L3.1"
					( objectStatus "a" )
				)
				( pin "R7L3.2"
					( objectStatus "b" )
				)
			)
			( gate "R7L2"
				( objectStatus "@baseboard_fab2_lib.baseboard_fab2(sch_1):page228_i74" )
				( pin "R7L2.1"
					( objectStatus "a" )
				)
				( pin "R7L2.2"
					( objectStatus "b" )
				)
			)
			( gate "C9L9"
				( objectStatus "@baseboard_fab2_lib.baseboard_fab2(sch_1):page228_i75" )
				( pin "C9L9.1"
					( objectStatus "a" )
				)
				( pin "C9L9.2"
					( objectStatus "b" )
				)
			)
			( gate "C9L12"
				( objectStatus "@baseboard_fab2_lib.baseboard_fab2(sch_1):page228_i76" )
				( pin "C9L12.1"
					( objectStatus "a" )
				)
				( pin "C9L12.2"
					( objectStatus "b" )
				)
			)
			( gate "C9L4"
				( objectStatus "@baseboard_fab2_lib.baseboard_fab2(sch_1):page228_i77" )
				( pin "C9L4.1"
					( objectStatus "a" )
				)
				( pin "C9L4.2"
					( objectStatus "b" )
				)
			)
			( gate "C9L2"
				( objectStatus "@baseboard_fab2_lib.baseboard_fab2(sch_1):page228_i78" )
				( pin "C9L2.1"
					( objectStatus "a" )
				)
				( pin "C9L2.2"
					( objectStatus "b" )
				)
			)
			( gate "C2A8"
				( objectStatus "@baseboard_fab2_lib.baseboard_fab2(sch_1):page228_i82" )
				( pin "C2A8.1"
					( objectStatus "a" )
				)
				( pin "C2A8.2"
					( objectStatus "b" )
				)
			)
			( gate "C8L2"
				( objectStatus "@baseboard_fab2_lib.baseboard_fab2(sch_1):page228_i83" )
				( pin "C8L2.1"
					( objectStatus "a" )
				)
				( pin "C8L2.2"
					( objectStatus "b" )
				)
			)
			( gate "C8L11"
				( objectStatus "@baseboard_fab2_lib.baseboard_fab2(sch_1):page228_i88" )
				( pin "C8L11.1"
					( objectStatus "a" )
				)
				( pin "C8L11.2"
					( objectStatus "b" )
				)
			)
			( gate "C2A16"
				( objectStatus "@baseboard_fab2_lib.baseboard_fab2(sch_1):page228_i89" )
				( pin "C2A16.1"
					( objectStatus "a" )
				)
				( pin "C2A16.2"
					( objectStatus "b" )
				)
			)
			( gate "C8M7"
				( objectStatus "@baseboard_fab2_lib.baseboard_fab2(sch_1):page228_i90" )
				( pin "C8M7.1"
					( objectStatus "a" )
				)
				( pin "C8M7.2"
					( objectStatus "b" )
				)
			)
			( gate "C8M11"
				( objectStatus "@baseboard_fab2_lib.baseboard_fab2(sch_1):page228_i91" )
				( pin "C8M11.1"
					( objectStatus "a" )
				)
				( pin "C8M11.2"
					( objectStatus "b" )
				)
			)
			( gate "C7L1"
				( objectStatus "@baseboard_fab2_lib.baseboard_fab2(sch_1):page228_i92" )
				( pin "C7L1.1"
					( objectStatus "a" )
				)
				( pin "C7L1.2"
					( objectStatus "b" )
				)
			)
			( gate "C8L1"
				( objectStatus "@baseboard_fab2_lib.baseboard_fab2(sch_1):page228_i110" )
				( pin "C8L1.1"
					( objectStatus "a" )
				)
				( pin "C8L1.2"
					( objectStatus "b" )
				)
			)
			( gate "L1B1"
				( objectStatus "@baseboard_fab2_lib.baseboard_fab2(sch_1):page228_i124" )
				( pin "L1B1.1"
					( objectStatus "ina" )
				)
				( pin "L1B1.2"
					( objectStatus "inb" )
				)
			)
			( gate "C1B10"
				( objectStatus "@baseboard_fab2_lib.baseboard_fab2(sch_1):page228_i175" )
				( pin "C1B10.1"
					( objectStatus "a" )
				)
				( pin "C1B10.2"
					( objectStatus "b" )
				)
			)
			( gate "C8P2"
				( objectStatus "@baseboard_fab2_lib.baseboard_fab2(sch_1):page228_i183" )
				( pin "C8P2.1"
					( objectStatus "a" )
				)
				( pin "C8P2.2"
					( objectStatus "b" )
				)
			)
			( gate "C8P1"
				( objectStatus "@baseboard_fab2_lib.baseboard_fab2(sch_1):page228_i185" )
				( pin "C8P1.1"
					( objectStatus "a" )
				)
				( pin "C8P1.2"
					( objectStatus "b" )
				)
			)
			( gate "C2D7"
				( objectStatus "@baseboard_fab2_lib.baseboard_fab2(sch_1):page228_i186" )
				( pin "C2D7.1"
					( objectStatus "a" )
				)
				( pin "C2D7.2"
					( objectStatus "b" )
				)
			)
			( gate "C2D4"
				( objectStatus "@baseboard_fab2_lib.baseboard_fab2(sch_1):page228_i187" )
				( pin "C2D4.1"
					( objectStatus "a" )
				)
				( pin "C2D4.2"
					( objectStatus "b" )
				)
			)
			( gate "C2D5"
				( objectStatus "@baseboard_fab2_lib.baseboard_fab2(sch_1):page228_i188" )
				( pin "C2D5.1"
					( objectStatus "a" )
				)
				( pin "C2D5.2"
					( objectStatus "b" )
				)
			)
			( gate "C2D6"
				( objectStatus "@baseboard_fab2_lib.baseboard_fab2(sch_1):page228_i190" )
				( pin "C2D6.1"
					( objectStatus "a" )
				)
				( pin "C2D6.2"
					( objectStatus "b" )
				)
			)
			( gate "C8M8"
				( objectStatus "@baseboard_fab2_lib.baseboard_fab2(sch_1):page228_i198" )
				( pin "C8M8.1"
					( objectStatus "a" )
				)
				( pin "C8M8.2"
					( objectStatus "b" )
				)
			)
			( gate "C2A5"
				( objectStatus "@baseboard_fab2_lib.baseboard_fab2(sch_1):page228_i199" )
				( pin "C2A5.1"
					( objectStatus "a" )
				)
				( pin "C2A5.2"
					( objectStatus "b" )
				)
			)
			( gate "C2B1"
				( objectStatus "@baseboard_fab2_lib.baseboard_fab2(sch_1):page228_i200" )
				( pin "C2B1.1"
					( objectStatus "a" )
				)
				( pin "C2B1.2"
					( objectStatus "b" )
				)
			)
			( gate "C8L12"
				( objectStatus "@baseboard_fab2_lib.baseboard_fab2(sch_1):page228_i201" )
				( pin "C8L12.1"
					( objectStatus "a" )
				)
				( pin "C8L12.2"
					( objectStatus "b" )
				)
			)
			( gate "C7M5"
				( objectStatus "@baseboard_fab2_lib.baseboard_fab2(sch_1):page228_i202" )
				( pin "C7M5.1"
					( objectStatus "a" )
				)
				( pin "C7M5.2"
					( objectStatus "b" )
				)
			)
			( gate "C8M10"
				( objectStatus "@baseboard_fab2_lib.baseboard_fab2(sch_1):page228_i203" )
				( pin "C8M10.1"
					( objectStatus "a" )
				)
				( pin "C8M10.2"
					( objectStatus "b" )
				)
			)
			( gate "C2B2"
				( objectStatus "@baseboard_fab2_lib.baseboard_fab2(sch_1):page228_i204" )
				( pin "C2B2.1"
					( objectStatus "a" )
				)
				( pin "C2B2.2"
					( objectStatus "b" )
				)
			)
			( gate "C8M9"
				( objectStatus "@baseboard_fab2_lib.baseboard_fab2(sch_1):page228_i205" )
				( pin "C8M9.1"
					( objectStatus "a" )
				)
				( pin "C8M9.2"
					( objectStatus "b" )
				)
			)
			( gate "C8M2"
				( objectStatus "@baseboard_fab2_lib.baseboard_fab2(sch_1):page228_i206" )
				( pin "C8M2.1"
					( objectStatus "a" )
				)
				( pin "C8M2.2"
					( objectStatus "b" )
				)
			)
			( gate "C2A2"
				( objectStatus "@baseboard_fab2_lib.baseboard_fab2(sch_1):page228_i209" )
				( pin "C2A2.1"
					( objectStatus "a" )
				)
				( pin "C2A2.2"
					( objectStatus "b" )
				)
			)
			( gate "C2A1"
				( objectStatus "@baseboard_fab2_lib.baseboard_fab2(sch_1):page228_i210" )
				( pin "C2A1.1"
					( objectStatus "a" )
				)
				( pin "C2A1.2"
					( objectStatus "b" )
				)
			)
			( gate "C2A12"
				( objectStatus "@baseboard_fab2_lib.baseboard_fab2(sch_1):page228_i211" )
				( pin "C2A12.1"
					( objectStatus "a" )
				)
				( pin "C2A12.2"
					( objectStatus "b" )
				)
			)
			( gate "C2A13"
				( objectStatus "@baseboard_fab2_lib.baseboard_fab2(sch_1):page228_i212" )
				( pin "C2A13.1"
					( objectStatus "a" )
				)
				( pin "C2A13.2"
					( objectStatus "b" )
				)
			)
			( gate "C2A11"
				( objectStatus "@baseboard_fab2_lib.baseboard_fab2(sch_1):page228_i213" )
				( pin "C2A11.1"
					( objectStatus "a" )
				)
				( pin "C2A11.2"
					( objectStatus "b" )
				)
			)
			( gate "C2A10"
				( objectStatus "@baseboard_fab2_lib.baseboard_fab2(sch_1):page228_i214" )
				( pin "C2A10.1"
					( objectStatus "a" )
				)
				( pin "C2A10.2"
					( objectStatus "b" )
				)
			)
			( gate "C2A9"
				( objectStatus "@baseboard_fab2_lib.baseboard_fab2(sch_1):page228_i215" )
				( pin "C2A9.1"
					( objectStatus "a" )
				)
				( pin "C2A9.2"
					( objectStatus "b" )
				)
			)
			( gate "C3A2"
				( objectStatus "@baseboard_fab2_lib.baseboard_fab2(sch_1):page228_i216" )
				( pin "C3A2.1"
					( objectStatus "a" )
				)
				( pin "C3A2.2"
					( objectStatus "b" )
				)
			)
			( gate "C3A1"
				( objectStatus "@baseboard_fab2_lib.baseboard_fab2(sch_1):page228_i217" )
				( pin "C3A1.1"
					( objectStatus "a" )
				)
				( pin "C3A1.2"
					( objectStatus "b" )
				)
			)
			( gate "C2A7"
				( objectStatus "@baseboard_fab2_lib.baseboard_fab2(sch_1):page228_i218" )
				( pin "C2A7.1"
					( objectStatus "a" )
				)
				( pin "C2A7.2"
					( objectStatus "b" )
				)
			)
			( gate "C2A6"
				( objectStatus "@baseboard_fab2_lib.baseboard_fab2(sch_1):page228_i219" )
				( pin "C2A6.1"
					( objectStatus "a" )
				)
				( pin "C2A6.2"
					( objectStatus "b" )
				)
			)
			( gate "C2A14"
				( objectStatus "@baseboard_fab2_lib.baseboard_fab2(sch_1):page228_i220" )
				( pin "C2A14.1"
					( objectStatus "a" )
				)
				( pin "C2A14.2"
					( objectStatus "b" )
				)
			)
			( gate "C2A15"
				( objectStatus "@baseboard_fab2_lib.baseboard_fab2(sch_1):page228_i221" )
				( pin "C2A15.1"
					( objectStatus "a" )
				)
				( pin "C2A15.2"
					( objectStatus "b" )
				)
			)
			( gate "C3A5"
				( objectStatus "@baseboard_fab2_lib.baseboard_fab2(sch_1):page228_i222" )
				( pin "C3A5.1"
					( objectStatus "a" )
				)
				( pin "C3A5.2"
					( objectStatus "b" )
				)
			)
			( gate "C3A6"
				( objectStatus "@baseboard_fab2_lib.baseboard_fab2(sch_1):page228_i223" )
				( pin "C3A6.1"
					( objectStatus "a" )
				)
				( pin "C3A6.2"
					( objectStatus "b" )
				)
			)
			( gate "C7L5"
				( objectStatus "@baseboard_fab2_lib.baseboard_fab2(sch_1):page228_i225" )
				( pin "C7L5.1"
					( objectStatus "a" )
				)
				( pin "C7L5.2"
					( objectStatus "b" )
				)
			)
			( gate "C8M3"
				( objectStatus "@baseboard_fab2_lib.baseboard_fab2(sch_1):page228_i227" )
				( pin "C8M3.1"
					( objectStatus "a" )
				)
				( pin "C8M3.2"
					( objectStatus "b" )
				)
			)
			( gate "C8M5"
				( objectStatus "@baseboard_fab2_lib.baseboard_fab2(sch_1):page228_i228" )
				( pin "C8M5.1"
					( objectStatus "a" )
				)
				( pin "C8M5.2"
					( objectStatus "b" )
				)
			)
			( gate "C8L10"
				( objectStatus "@baseboard_fab2_lib.baseboard_fab2(sch_1):page228_i229" )
				( pin "C8L10.1"
					( objectStatus "a" )
				)
				( pin "C8L10.2"
					( objectStatus "b" )
				)
			)
			( gate "C2A3"
				( objectStatus "@baseboard_fab2_lib.baseboard_fab2(sch_1):page228_i230" )
				( pin "C2A3.1"
					( objectStatus "a" )
				)
				( pin "C2A3.2"
					( objectStatus "b" )
				)
			)
			( gate "C7M1"
				( objectStatus "@baseboard_fab2_lib.baseboard_fab2(sch_1):page228_i231" )
				( pin "C7M1.1"
					( objectStatus "a" )
				)
				( pin "C7M1.2"
					( objectStatus "b" )
				)
			)
			( gate "C7M2"
				( objectStatus "@baseboard_fab2_lib.baseboard_fab2(sch_1):page228_i232" )
				( pin "C7M2.1"
					( objectStatus "a" )
				)
				( pin "C7M2.2"
					( objectStatus "b" )
				)
			)
			( gate "C8M4"
				( objectStatus "@baseboard_fab2_lib.baseboard_fab2(sch_1):page228_i233" )
				( pin "C8M4.1"
					( objectStatus "a" )
				)
				( pin "C8M4.2"
					( objectStatus "b" )
				)
			)
			( gate "C2A4"
				( objectStatus "@baseboard_fab2_lib.baseboard_fab2(sch_1):page228_i234" )
				( pin "C2A4.1"
					( objectStatus "a" )
				)
				( pin "C2A4.2"
					( objectStatus "b" )
				)
			)
			( gate "C8M6"
				( objectStatus "@baseboard_fab2_lib.baseboard_fab2(sch_1):page228_i235" )
				( pin "C8M6.1"
					( objectStatus "a" )
				)
				( pin "C8M6.2"
					( objectStatus "b" )
				)
			)
			( gate "C8L9"
				( objectStatus "@baseboard_fab2_lib.baseboard_fab2(sch_1):page228_i236" )
				( pin "C8L9.1"
					( objectStatus "a" )
				)
				( pin "C8L9.2"
					( objectStatus "b" )
				)
			)
			( gate "C8L8"
				( objectStatus "@baseboard_fab2_lib.baseboard_fab2(sch_1):page228_i237" )
				( pin "C8L8.1"
					( objectStatus "a" )
				)
				( pin "C8L8.2"
					( objectStatus "b" )
				)
			)
			( gate "C7L4"
				( objectStatus "@baseboard_fab2_lib.baseboard_fab2(sch_1):page228_i238" )
				( pin "C7L4.1"
					( objectStatus "a" )
				)
				( pin "C7L4.2"
					( objectStatus "b" )
				)
			)
			( gate "C8L7"
				( objectStatus "@baseboard_fab2_lib.baseboard_fab2(sch_1):page228_i239" )
				( pin "C8L7.1"
					( objectStatus "a" )
				)
				( pin "C8L7.2"
					( objectStatus "b" )
				)
			)
			( gate "C8L6"
				( objectStatus "@baseboard_fab2_lib.baseboard_fab2(sch_1):page228_i240" )
				( pin "C8L6.1"
					( objectStatus "a" )
				)
				( pin "C8L6.2"
					( objectStatus "b" )
				)
			)
			( gate "C8L5"
				( objectStatus "@baseboard_fab2_lib.baseboard_fab2(sch_1):page228_i241" )
				( pin "C8L5.1"
					( objectStatus "a" )
				)
				( pin "C8L5.2"
					( objectStatus "b" )
				)
			)
			( gate "C8M1"
				( objectStatus "@baseboard_fab2_lib.baseboard_fab2(sch_1):page228_i243" )
				( pin "C8M1.1"
					( objectStatus "a" )
				)
				( pin "C8M1.2"
					( objectStatus "b" )
				)
			)
			( gate "R4G17"
				( objectStatus "@baseboard_fab2_lib.baseboard_fab2(sch_1):page229_i14" )
				( pin "R4G17.1"
					( objectStatus "a" )
				)
				( pin "R4G17.2"
					( objectStatus "b" )
				)
			)
			( gate "C4G13"
				( objectStatus "@baseboard_fab2_lib.baseboard_fab2(sch_1):page229_i15" )
				( pin "C4G13.1"
					( objectStatus "a" )
				)
				( pin "C4G13.2"
					( objectStatus "b" )
				)
			)
			( gate "C4G20"
				( objectStatus "@baseboard_fab2_lib.baseboard_fab2(sch_1):page229_i17" )
				( pin "C4G20.1"
					( objectStatus "a" )
				)
				( pin "C4G20.2"
					( objectStatus "b" )
				)
			)
			( gate "R8U1"
				( objectStatus "@baseboard_fab2_lib.baseboard_fab2(sch_1):page229_i18" )
				( pin "R8U1.1"
					( objectStatus "a" )
				)
				( pin "R8U1.2"
					( objectStatus "b" )
				)
			)
			( gate "C4G21"
				( objectStatus "@baseboard_fab2_lib.baseboard_fab2(sch_1):page229_i21" )
				( pin "C4G21.1"
					( objectStatus "a" )
				)
				( pin "C4G21.2"
					( objectStatus "b" )
				)
			)
			( gate "EU4G2"
				( objectStatus "@baseboard_fab2_lib.baseboard_fab2(sch_1):page229_i24" )
				( pin "EU4G2.3"
					( objectStatus "agnd" )
				)
				( pin "EU4G2.2"
					( objectStatus "bias" )
				)
				( pin "EU4G2.7"
					( objectStatus "en" )
				)
				( pin "EU4G2.5"
					( objectStatus "pg" )
				)
				( pin "EU4G2.8"
					( objectStatus "pgnd" )
				)
				( pin "EU4G2.6"
					( objectStatus "sns" )
				)
				( pin "EU4G2.11"
					( objectStatus "thpad" )
				)
				( pin "EU4G2.4"
					( objectStatus "vddq" )
				)
				( pin "EU4G2.10"
					( objectStatus "vin" )
				)
				( pin "EU4G2.1"
					( objectStatus "vref" )
				)
				( pin "EU4G2.9"
					( objectStatus "vtt" )
				)
			)
			( gate "C6U14"
				( objectStatus "@baseboard_fab2_lib.baseboard_fab2(sch_1):page229_i25" )
				( pin "C6U14.1"
					( objectStatus "a" )
				)
				( pin "C6U14.2"
					( objectStatus "b" )
				)
			)
			( gate "C4G18"
				( objectStatus "@baseboard_fab2_lib.baseboard_fab2(sch_1):page229_i27" )
				( pin "C4G18.1"
					( objectStatus "a" )
				)
				( pin "C4G18.2"
					( objectStatus "b" )
				)
			)
			( gate "C6U13"
				( objectStatus "@baseboard_fab2_lib.baseboard_fab2(sch_1):page229_i29" )
				( pin "C6U13.1"
					( objectStatus "a" )
				)
				( pin "C6U13.2"
					( objectStatus "b" )
				)
			)
			( gate "R6U7"
				( objectStatus "@baseboard_fab2_lib.baseboard_fab2(sch_1):page229_i32" )
				( pin "R6U7.1"
					( objectStatus "a" )
				)
				( pin "R6U7.2"
					( objectStatus "b" )
				)
			)
			( gate "R6U3"
				( objectStatus "@baseboard_fab2_lib.baseboard_fab2(sch_1):page229_i34" )
				( pin "R6U3.1"
					( objectStatus "a" )
				)
				( pin "R6U3.2"
					( objectStatus "b" )
				)
			)
			( gate "R4G16"
				( objectStatus "@baseboard_fab2_lib.baseboard_fab2(sch_1):page229_i35" )
				( pin "R4G16.1"
					( objectStatus "a" )
				)
				( pin "R4G16.2"
					( objectStatus "b" )
				)
			)
			( gate "C4G12"
				( objectStatus "@baseboard_fab2_lib.baseboard_fab2(sch_1):page229_i36" )
				( pin "C4G12.1"
					( objectStatus "a" )
				)
				( pin "C4G12.2"
					( objectStatus "b" )
				)
			)
			( gate "R6U6"
				( objectStatus "@baseboard_fab2_lib.baseboard_fab2(sch_1):page229_i39" )
				( pin "R6U6.1"
					( objectStatus "a" )
				)
				( pin "R6U6.2"
					( objectStatus "b" )
				)
			)
			( gate "C6U11"
				( objectStatus "@baseboard_fab2_lib.baseboard_fab2(sch_1):page229_i46" )
				( pin "C6U11.1"
					( objectStatus "a" )
				)
				( pin "C6U11.2"
					( objectStatus "b" )
				)
			)
			( gate "C2F2"
				( objectStatus "@baseboard_fab2_lib.baseboard_fab2(sch_1):page229_i47" )
				( pin "C2F2.1"
					( objectStatus "a" )
				)
				( pin "C2F2.2"
					( objectStatus "b" )
				)
			)
			( gate "C8T3"
				( objectStatus "@baseboard_fab2_lib.baseboard_fab2(sch_1):page229_i48" )
				( pin "C8T3.1"
					( objectStatus "a" )
				)
				( pin "C8T3.2"
					( objectStatus "b" )
				)
			)
			( gate "C8U10"
				( objectStatus "@baseboard_fab2_lib.baseboard_fab2(sch_1):page229_i49" )
				( pin "C8U10.1"
					( objectStatus "a" )
				)
				( pin "C8U10.2"
					( objectStatus "b" )
				)
			)
			( gate "R4G15"
				( objectStatus "@baseboard_fab2_lib.baseboard_fab2(sch_1):page229_i51" )
				( pin "R4G15.1"
					( objectStatus "a" )
				)
				( pin "R4G15.2"
					( objectStatus "b" )
				)
			)
			( gate "R6U8"
				( objectStatus "@baseboard_fab2_lib.baseboard_fab2(sch_1):page229_i52" )
				( pin "R6U8.1"
					( objectStatus "a" )
				)
				( pin "R6U8.2"
					( objectStatus "b" )
				)
			)
			( gate "R8L1"
				( objectStatus "@baseboard_fab2_lib.baseboard_fab2(sch_1):page230_i13" )
				( pin "R8L1.1"
					( objectStatus "a" )
				)
				( pin "R8L1.2"
					( objectStatus "b" )
				)
			)
			( gate "C4A3"
				( objectStatus "@baseboard_fab2_lib.baseboard_fab2(sch_1):page230_i16" )
				( pin "C4A3.1"
					( objectStatus "a" )
				)
				( pin "C4A3.2"
					( objectStatus "b" )
				)
			)
			( gate "R4A5"
				( objectStatus "@baseboard_fab2_lib.baseboard_fab2(sch_1):page230_i17" )
				( pin "R4A5.1"
					( objectStatus "a" )
				)
				( pin "R4A5.2"
					( objectStatus "b" )
				)
			)
			( gate "C4A13"
				( objectStatus "@baseboard_fab2_lib.baseboard_fab2(sch_1):page230_i18" )
				( pin "C4A13.1"
					( objectStatus "a" )
				)
				( pin "C4A13.2"
					( objectStatus "b" )
				)
			)
			( gate "C4A14"
				( objectStatus "@baseboard_fab2_lib.baseboard_fab2(sch_1):page230_i21" )
				( pin "C4A14.1"
					( objectStatus "a" )
				)
				( pin "C4A14.2"
					( objectStatus "b" )
				)
			)
			( gate "C4A15"
				( objectStatus "@baseboard_fab2_lib.baseboard_fab2(sch_1):page230_i25" )
				( pin "C4A15.1"
					( objectStatus "a" )
				)
				( pin "C4A15.2"
					( objectStatus "b" )
				)
			)
			( gate "C6L5"
				( objectStatus "@baseboard_fab2_lib.baseboard_fab2(sch_1):page230_i26" )
				( pin "C6L5.1"
					( objectStatus "a" )
				)
				( pin "C6L5.2"
					( objectStatus "b" )
				)
			)
			( gate "C4A8"
				( objectStatus "@baseboard_fab2_lib.baseboard_fab2(sch_1):page230_i28" )
				( pin "C4A8.1"
					( objectStatus "a" )
				)
				( pin "C4A8.2"
					( objectStatus "b" )
				)
			)
			( gate "R6L8"
				( objectStatus "@baseboard_fab2_lib.baseboard_fab2(sch_1):page230_i30" )
				( pin "R6L8.1"
					( objectStatus "a" )
				)
				( pin "R6L8.2"
					( objectStatus "b" )
				)
			)
			( gate "EU4A2"
				( objectStatus "@baseboard_fab2_lib.baseboard_fab2(sch_1):page230_i31" )
				( pin "EU4A2.3"
					( objectStatus "agnd" )
				)
				( pin "EU4A2.2"
					( objectStatus "bias" )
				)
				( pin "EU4A2.7"
					( objectStatus "en" )
				)
				( pin "EU4A2.5"
					( objectStatus "pg" )
				)
				( pin "EU4A2.8"
					( objectStatus "pgnd" )
				)
				( pin "EU4A2.6"
					( objectStatus "sns" )
				)
				( pin "EU4A2.11"
					( objectStatus "thpad" )
				)
				( pin "EU4A2.4"
					( objectStatus "vddq" )
				)
				( pin "EU4A2.10"
					( objectStatus "vin" )
				)
				( pin "EU4A2.1"
					( objectStatus "vref" )
				)
				( pin "EU4A2.9"
					( objectStatus "vtt" )
				)
			)
			( gate "R6L6"
				( objectStatus "@baseboard_fab2_lib.baseboard_fab2(sch_1):page230_i34" )
				( pin "R6L6.1"
					( objectStatus "a" )
				)
				( pin "R6L6.2"
					( objectStatus "b" )
				)
			)
			( gate "R6L5"
				( objectStatus "@baseboard_fab2_lib.baseboard_fab2(sch_1):page230_i37" )
				( pin "R6L5.1"
					( objectStatus "a" )
				)
				( pin "R6L5.2"
					( objectStatus "b" )
				)
			)
			( gate "R4A3"
				( objectStatus "@baseboard_fab2_lib.baseboard_fab2(sch_1):page230_i38" )
				( pin "R4A3.1"
					( objectStatus "a" )
				)
				( pin "R4A3.2"
					( objectStatus "b" )
				)
			)
			( gate "C4A6"
				( objectStatus "@baseboard_fab2_lib.baseboard_fab2(sch_1):page230_i39" )
				( pin "C4A6.1"
					( objectStatus "a" )
				)
				( pin "C4A6.2"
					( objectStatus "b" )
				)
			)
			( gate "C4A7"
				( objectStatus "@baseboard_fab2_lib.baseboard_fab2(sch_1):page230_i46" )
				( pin "C4A7.1"
					( objectStatus "a" )
				)
				( pin "C4A7.2"
					( objectStatus "b" )
				)
			)
			( gate "C8M12"
				( objectStatus "@baseboard_fab2_lib.baseboard_fab2(sch_1):page230_i47" )
				( pin "C8M12.1"
					( objectStatus "a" )
				)
				( pin "C8M12.2"
					( objectStatus "b" )
				)
			)
			( gate "C8L3"
				( objectStatus "@baseboard_fab2_lib.baseboard_fab2(sch_1):page230_i48" )
				( pin "C8L3.1"
					( objectStatus "a" )
				)
				( pin "C8L3.2"
					( objectStatus "b" )
				)
			)
			( gate "C8L4"
				( objectStatus "@baseboard_fab2_lib.baseboard_fab2(sch_1):page230_i49" )
				( pin "C8L4.1"
					( objectStatus "a" )
				)
				( pin "C8L4.2"
					( objectStatus "b" )
				)
			)
			( gate "R4A4"
				( objectStatus "@baseboard_fab2_lib.baseboard_fab2(sch_1):page230_i51" )
				( pin "R4A4.1"
					( objectStatus "a" )
				)
				( pin "R4A4.2"
					( objectStatus "b" )
				)
			)
			( gate "R6L7"
				( objectStatus "@baseboard_fab2_lib.baseboard_fab2(sch_1):page230_i52" )
				( pin "R6L7.1"
					( objectStatus "a" )
				)
				( pin "R6L7.2"
					( objectStatus "b" )
				)
			)
			( gate "C6F6"
				( objectStatus "@baseboard_fab2_lib.baseboard_fab2(sch_1):page231_i122" )
				( pin "C6F6.1"
					( objectStatus "a" )
				)
				( pin "C6F6.2"
					( objectStatus "b" )
				)
			)
			( gate "C4T6"
				( objectStatus "@baseboard_fab2_lib.baseboard_fab2(sch_1):page231_i124" )
				( pin "C4T6.1"
					( objectStatus "a" )
				)
				( pin "C4T6.2"
					( objectStatus "b" )
				)
			)
			( gate "C4T5"
				( objectStatus "@baseboard_fab2_lib.baseboard_fab2(sch_1):page231_i125" )
				( pin "C4T5.1"
					( objectStatus "a" )
				)
				( pin "C4T5.2"
					( objectStatus "b" )
				)
			)
			( gate "C6G1"
				( objectStatus "@baseboard_fab2_lib.baseboard_fab2(sch_1):page231_i126" )
				( pin "C6G1.1"
					( objectStatus "a" )
				)
				( pin "C6G1.2"
					( objectStatus "b" )
				)
			)
			( gate "C6G2"
				( objectStatus "@baseboard_fab2_lib.baseboard_fab2(sch_1):page231_i128" )
				( pin "C6G2.1"
					( objectStatus "a" )
				)
				( pin "C6G2.2"
					( objectStatus "b" )
				)
			)
			( gate "C4U2"
				( objectStatus "@baseboard_fab2_lib.baseboard_fab2(sch_1):page231_i129" )
				( pin "C4U2.1"
					( objectStatus "a" )
				)
				( pin "C4U2.2"
					( objectStatus "b" )
				)
			)
			( gate "C4U1"
				( objectStatus "@baseboard_fab2_lib.baseboard_fab2(sch_1):page231_i130" )
				( pin "C4U1.1"
					( objectStatus "a" )
				)
				( pin "C4U1.2"
					( objectStatus "b" )
				)
			)
			( gate "C6G4"
				( objectStatus "@baseboard_fab2_lib.baseboard_fab2(sch_1):page231_i131" )
				( pin "C6G4.1"
					( objectStatus "a" )
				)
				( pin "C6G4.2"
					( objectStatus "b" )
				)
			)
			( gate "R7F15"
				( objectStatus "@baseboard_fab2_lib.baseboard_fab2(sch_1):page231_i134" )
				( pin "R7F15.1"
					( objectStatus "a" )
				)
				( pin "R7F15.2"
					( objectStatus "b" )
				)
			)
			( gate "R7F14"
				( objectStatus "@baseboard_fab2_lib.baseboard_fab2(sch_1):page231_i136" )
				( pin "R7F14.1"
					( objectStatus "a" )
				)
				( pin "R7F14.2"
					( objectStatus "b" )
				)
			)
			( gate "C7F8"
				( objectStatus "@baseboard_fab2_lib.baseboard_fab2(sch_1):page231_i140" )
				( pin "C7F8.1"
					( objectStatus "a" )
				)
				( pin "C7F8.2"
					( objectStatus "b" )
				)
			)
			( gate "C7F11"
				( objectStatus "@baseboard_fab2_lib.baseboard_fab2(sch_1):page231_i142" )
				( pin "C7F11.1"
					( objectStatus "a" )
				)
				( pin "C7F11.2"
					( objectStatus "b" )
				)
			)
			( gate "R7F19"
				( objectStatus "@baseboard_fab2_lib.baseboard_fab2(sch_1):page231_i143" )
				( pin "R7F19.1"
					( objectStatus "a" )
				)
				( pin "R7F19.2"
					( objectStatus "b" )
				)
			)
			( gate "C6G5"
				( objectStatus "@baseboard_fab2_lib.baseboard_fab2(sch_1):page231_i145" )
				( pin "C6G5.1"
					( objectStatus "a" )
				)
				( pin "C6G5.2"
					( objectStatus "b" )
				)
			)
			( gate "C4U4"
				( objectStatus "@baseboard_fab2_lib.baseboard_fab2(sch_1):page231_i146" )
				( pin "C4U4.1"
					( objectStatus "a" )
				)
				( pin "C4U4.2"
					( objectStatus "b" )
				)
			)
			( gate "C4U3"
				( objectStatus "@baseboard_fab2_lib.baseboard_fab2(sch_1):page231_i148" )
				( pin "C4U3.1"
					( objectStatus "a" )
				)
				( pin "C4U3.2"
					( objectStatus "b" )
				)
			)
			( gate "C6F5"
				( objectStatus "@baseboard_fab2_lib.baseboard_fab2(sch_1):page231_i149" )
				( pin "C6F5.1"
					( objectStatus "a" )
				)
				( pin "C6F5.2"
					( objectStatus "b" )
				)
			)
			( gate "C7F7"
				( objectStatus "@baseboard_fab2_lib.baseboard_fab2(sch_1):page231_i151" )
				( pin "C7F7.1"
					( objectStatus "a" )
				)
				( pin "C7F7.2"
					( objectStatus "b" )
				)
			)
			( gate "R7F8"
				( objectStatus "@baseboard_fab2_lib.baseboard_fab2(sch_1):page231_i154" )
				( pin "R7F8.1"
					( objectStatus "a" )
				)
				( pin "R7F8.2"
					( objectStatus "b" )
				)
			)
			( gate "C7F4"
				( objectStatus "@baseboard_fab2_lib.baseboard_fab2(sch_1):page231_i159" )
				( pin "C7F4.1"
					( objectStatus "a" )
				)
				( pin "C7F4.2"
					( objectStatus "b" )
				)
			)
			( gate "C3T10"
				( objectStatus "@baseboard_fab2_lib.baseboard_fab2(sch_1):page231_i161" )
				( pin "C3T10.1"
					( objectStatus "a" )
				)
				( pin "C3T10.2"
					( objectStatus "b" )
				)
			)
			( gate "FB7F1"
				( objectStatus "@baseboard_fab2_lib.baseboard_fab2(sch_1):page231_i162" )
				( pin "FB7F1.1"
					( objectStatus "a" )
				)
				( pin "FB7F1.2"
					( objectStatus "b" )
				)
			)
			( gate "R7F11"
				( objectStatus "@baseboard_fab2_lib.baseboard_fab2(sch_1):page231_i166" )
				( pin "R7F11.1"
					( objectStatus "a" )
				)
				( pin "R7F11.2"
					( objectStatus "b" )
				)
			)
			( gate "R7F13"
				( objectStatus "@baseboard_fab2_lib.baseboard_fab2(sch_1):page231_i167" )
				( pin "R7F13.1"
					( objectStatus "a" )
				)
				( pin "R7F13.2"
					( objectStatus "b" )
				)
			)
			( gate "R7F12"
				( objectStatus "@baseboard_fab2_lib.baseboard_fab2(sch_1):page231_i168" )
				( pin "R7F12.1"
					( objectStatus "a" )
				)
				( pin "R7F12.2"
					( objectStatus "b" )
				)
			)
			( gate "R3T6"
				( objectStatus "@baseboard_fab2_lib.baseboard_fab2(sch_1):page231_i170" )
				( pin "R3T6.1"
					( objectStatus "a" )
				)
				( pin "R3T6.2"
					( objectStatus "b" )
				)
			)
			( gate "R7F7"
				( objectStatus "@baseboard_fab2_lib.baseboard_fab2(sch_1):page231_i174" )
				( pin "R7F7.1"
					( objectStatus "a" )
				)
				( pin "R7F7.2"
					( objectStatus "b" )
				)
			)
			( gate "C7F3"
				( objectStatus "@baseboard_fab2_lib.baseboard_fab2(sch_1):page231_i175" )
				( pin "C7F3.1"
					( objectStatus "a" )
				)
				( pin "C7F3.2"
					( objectStatus "b" )
				)
			)
			( gate "R7F10"
				( objectStatus "@baseboard_fab2_lib.baseboard_fab2(sch_1):page231_i177" )
				( pin "R7F10.1"
					( objectStatus "a" )
				)
				( pin "R7F10.2"
					( objectStatus "b" )
				)
			)
			( gate "L7F1"
				( objectStatus "@baseboard_fab2_lib.baseboard_fab2(sch_1):page231_i178" )
				( pin "L7F1.1"
					( objectStatus "ina" )
				)
				( pin "L7F1.2"
					( objectStatus "inb" )
				)
			)
			( gate "C6F4"
				( objectStatus "@baseboard_fab2_lib.baseboard_fab2(sch_1):page231_i180" )
				( pin "C6F4.1"
					( objectStatus "a" )
				)
				( pin "C6F4.2"
					( objectStatus "b" )
				)
			)
			( gate "C3T7"
				( objectStatus "@baseboard_fab2_lib.baseboard_fab2(sch_1):page231_i184" )
				( pin "C3T7.1"
					( objectStatus "a" )
				)
				( pin "C3T7.2"
					( objectStatus "b" )
				)
			)
			( gate "C3T9"
				( objectStatus "@baseboard_fab2_lib.baseboard_fab2(sch_1):page231_i186" )
				( pin "C3T9.1"
					( objectStatus "a" )
				)
				( pin "C3T9.2"
					( objectStatus "b" )
				)
			)
			( gate "EU7F1"
				( objectStatus "@baseboard_fab2_lib.baseboard_fab2(sch_1):page231_i193" )
				( pin "EU7F1.5"
					( objectStatus "agnd" )
				)
				( pin "EU7F1.36"
					( objectStatus "bst" )
				)
				( pin "EU7F1.3"
					( objectStatus "comp" )
				)
				( pin "EU7F1.40"
					( objectStatus "en" )
				)
				( pin "EU7F1.2"
					( objectStatus "fb" )
				)
				( pin "EU7F1.41"
					( objectStatus "gnd" )
				)
				( pin "EU7F1.4"
					( objectStatus "iset" )
				)
				( pin "EU7F1.6"
					( objectStatus "ots" )
				)
				( pin "EU7F1.7"
					( objectStatus "pg" )
				)
				( pin "EU7F1.16"
					( objectStatus "pgnd(0)" )
				)
				( pin "EU7F1.17"
					( objectStatus "pgnd(1)" )
				)
				( pin "EU7F1.18"
					( objectStatus "pgnd(2)" )
				)
				( pin "EU7F1.19"
					( objectStatus "pgnd(3)" )
				)
				( pin "EU7F1.20"
					( objectStatus "pgnd(4)" )
				)
				( pin "EU7F1.21"
					( objectStatus "pgnd(5)" )
				)
				( pin "EU7F1.22"
					( objectStatus "pgnd(6)" )
				)
				( pin "EU7F1.23"
					( objectStatus "pgnd(7)" )
				)
				( pin "EU7F1.24"
					( objectStatus "pgnd(8)" )
				)
				( pin "EU7F1.25"
					( objectStatus "pgnd(9)" )
				)
				( pin "EU7F1.26"
					( objectStatus "pgnd(10)" )
				)
				( pin "EU7F1.27"
					( objectStatus "pgnd(11)" )
				)
				( pin "EU7F1.28"
					( objectStatus "pgnd(12)" )
				)
				( pin "EU7F1.37"
					( objectStatus "pgnd(13)" )
				)
				( pin "EU7F1.1"
					( objectStatus "ss" )
				)
				( pin "EU7F1.38"
					( objectStatus "vb" )
				)
				( pin "EU7F1.39"
					( objectStatus "vcc" )
				)
				( pin "EU7F1.8"
					( objectStatus "vin(0)" )
				)
				( pin "EU7F1.9"
					( objectStatus "vin(1)" )
				)
				( pin "EU7F1.10"
					( objectStatus "vin(2)" )
				)
				( pin "EU7F1.11"
					( objectStatus "vin(3)" )
				)
				( pin "EU7F1.12"
					( objectStatus "vin(4)" )
				)
				( pin "EU7F1.13"
					( objectStatus "vin(5)" )
				)
				( pin "EU7F1.14"
					( objectStatus "vin(6)" )
				)
				( pin "EU7F1.42"
					( objectStatus "vin(7)" )
				)
				( pin "EU7F1.35"
					( objectStatus "vsw" )
				)
				( pin "EU7F1.15"
					( objectStatus "vswh(0)" )
				)
				( pin "EU7F1.29"
					( objectStatus "vswh(1)" )
				)
				( pin "EU7F1.30"
					( objectStatus "vswh(2)" )
				)
				( pin "EU7F1.31"
					( objectStatus "vswh(3)" )
				)
				( pin "EU7F1.32"
					( objectStatus "vswh(4)" )
				)
				( pin "EU7F1.33"
					( objectStatus "vswh(5)" )
				)
				( pin "EU7F1.34"
					( objectStatus "vswh(6)" )
				)
				( pin "EU7F1.43"
					( objectStatus "vswh(7)" )
				)
			)
			( gate "C7F10"
				( objectStatus "@baseboard_fab2_lib.baseboard_fab2(sch_1):page231_i194" )
				( pin "C7F10.1"
					( objectStatus "a" )
				)
				( pin "C7F10.2"
					( objectStatus "b" )
				)
			)
			( gate "C7F9"
				( objectStatus "@baseboard_fab2_lib.baseboard_fab2(sch_1):page231_i199" )
				( pin "C7F9.1"
					( objectStatus "a" )
				)
				( pin "C7F9.2"
					( objectStatus "b" )
				)
			)
			( gate "C7F12"
				( objectStatus "@baseboard_fab2_lib.baseboard_fab2(sch_1):page231_i200" )
				( pin "C7F12.1"
					( objectStatus "a" )
				)
				( pin "C7F12.2"
					( objectStatus "b" )
				)
			)
			( gate "R7F18"
				( objectStatus "@baseboard_fab2_lib.baseboard_fab2(sch_1):page231_i201" )
				( pin "R7F18.1"
					( objectStatus "a" )
				)
				( pin "R7F18.2"
					( objectStatus "b" )
				)
			)
			( gate "C3T11"
				( objectStatus "@baseboard_fab2_lib.baseboard_fab2(sch_1):page231_i202" )
				( pin "C3T11.1"
					( objectStatus "a" )
				)
				( pin "C3T11.2"
					( objectStatus "b" )
				)
			)
			( gate "C7F6"
				( objectStatus "@baseboard_fab2_lib.baseboard_fab2(sch_1):page231_i205" )
				( pin "C7F6.1"
					( objectStatus "a" )
				)
				( pin "C7F6.2"
					( objectStatus "b" )
				)
			)
			( gate "R7F16"
				( objectStatus "@baseboard_fab2_lib.baseboard_fab2(sch_1):page231_i208" )
				( pin "R7F16.1"
					( objectStatus "a" )
				)
				( pin "R7F16.2"
					( objectStatus "b" )
				)
			)
			( gate "C7F5"
				( objectStatus "@baseboard_fab2_lib.baseboard_fab2(sch_1):page231_i209" )
				( pin "C7F5.1"
					( objectStatus "a" )
				)
				( pin "C7F5.2"
					( objectStatus "b" )
				)
			)
			( gate "C3T8"
				( objectStatus "@baseboard_fab2_lib.baseboard_fab2(sch_1):page231_i210" )
				( pin "C3T8.1"
					( objectStatus "a" )
				)
				( pin "C3T8.2"
					( objectStatus "b" )
				)
			)
			( gate "C3T14"
				( objectStatus "@baseboard_fab2_lib.baseboard_fab2(sch_1):page231_i211" )
				( pin "C3T14.1"
					( objectStatus "a" )
				)
				( pin "C3T14.2"
					( objectStatus "b" )
				)
			)
			( gate "C3T12"
				( objectStatus "@baseboard_fab2_lib.baseboard_fab2(sch_1):page231_i215" )
				( pin "C3T12.1"
					( objectStatus "a" )
				)
				( pin "C3T12.2"
					( objectStatus "b" )
				)
			)
			( gate "C4T3"
				( objectStatus "@baseboard_fab2_lib.baseboard_fab2(sch_1):page231_i217" )
				( pin "C4T3.1"
					( objectStatus "a" )
				)
				( pin "C4T3.2"
					( objectStatus "b" )
				)
			)
			( gate "R7F17"
				( objectStatus "@baseboard_fab2_lib.baseboard_fab2(sch_1):page231_i218" )
				( pin "R7F17.1"
					( objectStatus "a" )
				)
				( pin "R7F17.2"
					( objectStatus "b" )
				)
			)
			( gate "C7F13"
				( objectStatus "@baseboard_fab2_lib.baseboard_fab2(sch_1):page231_i219" )
				( pin "C7F13.1"
					( objectStatus "a" )
				)
				( pin "C7F13.2"
					( objectStatus "b" )
				)
			)
			( gate "R7F9"
				( objectStatus "@baseboard_fab2_lib.baseboard_fab2(sch_1):page231_i220" )
				( pin "R7F9.1"
					( objectStatus "a" )
				)
				( pin "R7F9.2"
					( objectStatus "b" )
				)
			)
			( gate "C4L2"
				( objectStatus "@baseboard_fab2_lib.baseboard_fab2(sch_1):page232_i102" )
				( pin "C4L2.1"
					( objectStatus "a" )
				)
				( pin "C4L2.2"
					( objectStatus "b" )
				)
			)
			( gate "C6A3"
				( objectStatus "@baseboard_fab2_lib.baseboard_fab2(sch_1):page232_i104" )
				( pin "C6A3.1"
					( objectStatus "a" )
				)
				( pin "C6A3.2"
					( objectStatus "b" )
				)
			)
			( gate "C6A2"
				( objectStatus "@baseboard_fab2_lib.baseboard_fab2(sch_1):page232_i105" )
				( pin "C6A2.1"
					( objectStatus "a" )
				)
				( pin "C6A2.2"
					( objectStatus "b" )
				)
			)
			( gate "C4L3"
				( objectStatus "@baseboard_fab2_lib.baseboard_fab2(sch_1):page232_i106" )
				( pin "C4L3.1"
					( objectStatus "a" )
				)
				( pin "C4L3.2"
					( objectStatus "b" )
				)
			)
			( gate "C4L4"
				( objectStatus "@baseboard_fab2_lib.baseboard_fab2(sch_1):page232_i108" )
				( pin "C4L4.1"
					( objectStatus "a" )
				)
				( pin "C4L4.2"
					( objectStatus "b" )
				)
			)
			( gate "C6A7"
				( objectStatus "@baseboard_fab2_lib.baseboard_fab2(sch_1):page232_i109" )
				( pin "C6A7.1"
					( objectStatus "a" )
				)
				( pin "C6A7.2"
					( objectStatus "b" )
				)
			)
			( gate "C6A6"
				( objectStatus "@baseboard_fab2_lib.baseboard_fab2(sch_1):page232_i110" )
				( pin "C6A6.1"
					( objectStatus "a" )
				)
				( pin "C6A6.2"
					( objectStatus "b" )
				)
			)
			( gate "C4M3"
				( objectStatus "@baseboard_fab2_lib.baseboard_fab2(sch_1):page232_i111" )
				( pin "C4M3.1"
					( objectStatus "a" )
				)
				( pin "C4M3.2"
					( objectStatus "b" )
				)
			)
			( gate "C4M4"
				( objectStatus "@baseboard_fab2_lib.baseboard_fab2(sch_1):page232_i125" )
				( pin "C4M4.1"
					( objectStatus "a" )
				)
				( pin "C4M4.2"
					( objectStatus "b" )
				)
			)
			( gate "C6B2"
				( objectStatus "@baseboard_fab2_lib.baseboard_fab2(sch_1):page232_i126" )
				( pin "C6B2.1"
					( objectStatus "a" )
				)
				( pin "C6B2.2"
					( objectStatus "b" )
				)
			)
			( gate "C6B1"
				( objectStatus "@baseboard_fab2_lib.baseboard_fab2(sch_1):page232_i128" )
				( pin "C6B1.1"
					( objectStatus "a" )
				)
				( pin "C6B1.2"
					( objectStatus "b" )
				)
			)
			( gate "C4L1"
				( objectStatus "@baseboard_fab2_lib.baseboard_fab2(sch_1):page232_i129" )
				( pin "C4L1.1"
					( objectStatus "a" )
				)
				( pin "C4L1.2"
					( objectStatus "b" )
				)
			)
			( gate "R3M7"
				( objectStatus "@baseboard_fab2_lib.baseboard_fab2(sch_1):page232_i150" )
				( pin "R3M7.1"
					( objectStatus "a" )
				)
				( pin "R3M7.2"
					( objectStatus "b" )
				)
			)
			( gate "C7B9"
				( objectStatus "@baseboard_fab2_lib.baseboard_fab2(sch_1):page232_i185" )
				( pin "C7B9.1"
					( objectStatus "a" )
				)
				( pin "C7B9.2"
					( objectStatus "b" )
				)
			)
			( gate "R7B14"
				( objectStatus "@baseboard_fab2_lib.baseboard_fab2(sch_1):page232_i193" )
				( pin "R7B14.1"
					( objectStatus "a" )
				)
				( pin "R7B14.2"
					( objectStatus "b" )
				)
			)
			( gate "C7B11"
				( objectStatus "@baseboard_fab2_lib.baseboard_fab2(sch_1):page232_i197" )
				( pin "C7B11.1"
					( objectStatus "a" )
				)
				( pin "C7B11.2"
					( objectStatus "b" )
				)
			)
			( gate "FB7B1"
				( objectStatus "@baseboard_fab2_lib.baseboard_fab2(sch_1):page232_i200" )
				( pin "FB7B1.1"
					( objectStatus "a" )
				)
				( pin "FB7B1.2"
					( objectStatus "b" )
				)
			)
			( gate "C7B8"
				( objectStatus "@baseboard_fab2_lib.baseboard_fab2(sch_1):page232_i202" )
				( pin "C7B8.1"
					( objectStatus "a" )
				)
				( pin "C7B8.2"
					( objectStatus "b" )
				)
			)
			( gate "C3M9"
				( objectStatus "@baseboard_fab2_lib.baseboard_fab2(sch_1):page232_i207" )
				( pin "C3M9.1"
					( objectStatus "a" )
				)
				( pin "C3M9.2"
					( objectStatus "b" )
				)
			)
			( gate "C7B12"
				( objectStatus "@baseboard_fab2_lib.baseboard_fab2(sch_1):page232_i209" )
				( pin "C7B12.1"
					( objectStatus "a" )
				)
				( pin "C7B12.2"
					( objectStatus "b" )
				)
			)
			( gate "R7B17"
				( objectStatus "@baseboard_fab2_lib.baseboard_fab2(sch_1):page232_i210" )
				( pin "R7B17.1"
					( objectStatus "a" )
				)
				( pin "R7B17.2"
					( objectStatus "b" )
				)
			)
			( gate "EU7B1"
				( objectStatus "@baseboard_fab2_lib.baseboard_fab2(sch_1):page232_i214" )
				( pin "EU7B1.5"
					( objectStatus "agnd" )
				)
				( pin "EU7B1.36"
					( objectStatus "bst" )
				)
				( pin "EU7B1.3"
					( objectStatus "comp" )
				)
				( pin "EU7B1.40"
					( objectStatus "en" )
				)
				( pin "EU7B1.2"
					( objectStatus "fb" )
				)
				( pin "EU7B1.41"
					( objectStatus "gnd" )
				)
				( pin "EU7B1.4"
					( objectStatus "iset" )
				)
				( pin "EU7B1.6"
					( objectStatus "ots" )
				)
				( pin "EU7B1.7"
					( objectStatus "pg" )
				)
				( pin "EU7B1.16"
					( objectStatus "pgnd(0)" )
				)
				( pin "EU7B1.17"
					( objectStatus "pgnd(1)" )
				)
				( pin "EU7B1.18"
					( objectStatus "pgnd(2)" )
				)
				( pin "EU7B1.19"
					( objectStatus "pgnd(3)" )
				)
				( pin "EU7B1.20"
					( objectStatus "pgnd(4)" )
				)
				( pin "EU7B1.21"
					( objectStatus "pgnd(5)" )
				)
				( pin "EU7B1.22"
					( objectStatus "pgnd(6)" )
				)
				( pin "EU7B1.23"
					( objectStatus "pgnd(7)" )
				)
				( pin "EU7B1.24"
					( objectStatus "pgnd(8)" )
				)
				( pin "EU7B1.25"
					( objectStatus "pgnd(9)" )
				)
				( pin "EU7B1.26"
					( objectStatus "pgnd(10)" )
				)
				( pin "EU7B1.27"
					( objectStatus "pgnd(11)" )
				)
				( pin "EU7B1.28"
					( objectStatus "pgnd(12)" )
				)
				( pin "EU7B1.37"
					( objectStatus "pgnd(13)" )
				)
				( pin "EU7B1.1"
					( objectStatus "ss" )
				)
				( pin "EU7B1.38"
					( objectStatus "vb" )
				)
				( pin "EU7B1.39"
					( objectStatus "vcc" )
				)
				( pin "EU7B1.8"
					( objectStatus "vin(0)" )
				)
				( pin "EU7B1.9"
					( objectStatus "vin(1)" )
				)
				( pin "EU7B1.10"
					( objectStatus "vin(2)" )
				)
				( pin "EU7B1.11"
					( objectStatus "vin(3)" )
				)
				( pin "EU7B1.12"
					( objectStatus "vin(4)" )
				)
				( pin "EU7B1.13"
					( objectStatus "vin(5)" )
				)
				( pin "EU7B1.14"
					( objectStatus "vin(6)" )
				)
				( pin "EU7B1.42"
					( objectStatus "vin(7)" )
				)
				( pin "EU7B1.35"
					( objectStatus "vsw" )
				)
				( pin "EU7B1.15"
					( objectStatus "vswh(0)" )
				)
				( pin "EU7B1.29"
					( objectStatus "vswh(1)" )
				)
				( pin "EU7B1.30"
					( objectStatus "vswh(2)" )
				)
				( pin "EU7B1.31"
					( objectStatus "vswh(3)" )
				)
				( pin "EU7B1.32"
					( objectStatus "vswh(4)" )
				)
				( pin "EU7B1.33"
					( objectStatus "vswh(5)" )
				)
				( pin "EU7B1.34"
					( objectStatus "vswh(6)" )
				)
				( pin "EU7B1.43"
					( objectStatus "vswh(7)" )
				)
			)
			( gate "R7A15"
				( objectStatus "@baseboard_fab2_lib.baseboard_fab2(sch_1):page232_i218" )
				( pin "R7A15.1"
					( objectStatus "a" )
				)
				( pin "R7A15.2"
					( objectStatus "b" )
				)
			)
			( gate "C7A34"
				( objectStatus "@baseboard_fab2_lib.baseboard_fab2(sch_1):page232_i220" )
				( pin "C7A34.1"
					( objectStatus "a" )
				)
				( pin "C7A34.2"
					( objectStatus "b" )
				)
			)
			( gate "R7B10"
				( objectStatus "@baseboard_fab2_lib.baseboard_fab2(sch_1):page232_i227" )
				( pin "R7B10.1"
					( objectStatus "a" )
				)
				( pin "R7B10.2"
					( objectStatus "b" )
				)
			)
			( gate "C6B7"
				( objectStatus "@baseboard_fab2_lib.baseboard_fab2(sch_1):page232_i229" )
				( pin "C6B7.1"
					( objectStatus "a" )
				)
				( pin "C6B7.2"
					( objectStatus "b" )
				)
			)
			( gate "C6B3"
				( objectStatus "@baseboard_fab2_lib.baseboard_fab2(sch_1):page232_i236" )
				( pin "C6B3.1"
					( objectStatus "a" )
				)
				( pin "C6B3.2"
					( objectStatus "b" )
				)
			)
			( gate "C7B7"
				( objectStatus "@baseboard_fab2_lib.baseboard_fab2(sch_1):page232_i238" )
				( pin "C7B7.1"
					( objectStatus "a" )
				)
				( pin "C7B7.2"
					( objectStatus "b" )
				)
			)
			( gate "L7B1"
				( objectStatus "@baseboard_fab2_lib.baseboard_fab2(sch_1):page232_i239" )
				( pin "L7B1.1"
					( objectStatus "ina" )
				)
				( pin "L7B1.2"
					( objectStatus "inb" )
				)
			)
			( gate "R3M4"
				( objectStatus "@baseboard_fab2_lib.baseboard_fab2(sch_1):page232_i240" )
				( pin "R3M4.1"
					( objectStatus "a" )
				)
				( pin "R3M4.2"
					( objectStatus "b" )
				)
			)
			( gate "C3M5"
				( objectStatus "@baseboard_fab2_lib.baseboard_fab2(sch_1):page232_i241" )
				( pin "C3M5.1"
					( objectStatus "a" )
				)
				( pin "C3M5.2"
					( objectStatus "b" )
				)
			)
			( gate "C7B6"
				( objectStatus "@baseboard_fab2_lib.baseboard_fab2(sch_1):page232_i252" )
				( pin "C7B6.1"
					( objectStatus "a" )
				)
				( pin "C7B6.2"
					( objectStatus "b" )
				)
			)
			( gate "C3M10"
				( objectStatus "@baseboard_fab2_lib.baseboard_fab2(sch_1):page232_i253" )
				( pin "C3M10.1"
					( objectStatus "a" )
				)
				( pin "C3M10.2"
					( objectStatus "b" )
				)
			)
			( gate "R7B12"
				( objectStatus "@baseboard_fab2_lib.baseboard_fab2(sch_1):page232_i257" )
				( pin "R7B12.1"
					( objectStatus "a" )
				)
				( pin "R7B12.2"
					( objectStatus "b" )
				)
			)
			( gate "C3M8"
				( objectStatus "@baseboard_fab2_lib.baseboard_fab2(sch_1):page232_i259" )
				( pin "C3M8.1"
					( objectStatus "a" )
				)
				( pin "C3M8.2"
					( objectStatus "b" )
				)
			)
			( gate "C3M15"
				( objectStatus "@baseboard_fab2_lib.baseboard_fab2(sch_1):page232_i260" )
				( pin "C3M15.1"
					( objectStatus "a" )
				)
				( pin "C3M15.2"
					( objectStatus "b" )
				)
			)
			( gate "C3M16"
				( objectStatus "@baseboard_fab2_lib.baseboard_fab2(sch_1):page232_i261" )
				( pin "C3M16.1"
					( objectStatus "a" )
				)
				( pin "C3M16.2"
					( objectStatus "b" )
				)
			)
			( gate "C7B5"
				( objectStatus "@baseboard_fab2_lib.baseboard_fab2(sch_1):page232_i262" )
				( pin "C7B5.1"
					( objectStatus "a" )
				)
				( pin "C7B5.2"
					( objectStatus "b" )
				)
			)
			( gate "C4M1"
				( objectStatus "@baseboard_fab2_lib.baseboard_fab2(sch_1):page232_i267" )
				( pin "C4M1.1"
					( objectStatus "a" )
				)
				( pin "C4M1.2"
					( objectStatus "b" )
				)
			)
			( gate "R7B18"
				( objectStatus "@baseboard_fab2_lib.baseboard_fab2(sch_1):page232_i298" )
				( pin "R7B18.1"
					( objectStatus "a" )
				)
				( pin "R7B18.2"
					( objectStatus "b" )
				)
			)
			( gate "R7B11"
				( objectStatus "@baseboard_fab2_lib.baseboard_fab2(sch_1):page232_i299" )
				( pin "R7B11.1"
					( objectStatus "a" )
				)
				( pin "R7B11.2"
					( objectStatus "b" )
				)
			)
			( gate "R7B16"
				( objectStatus "@baseboard_fab2_lib.baseboard_fab2(sch_1):page232_i300" )
				( pin "R7B16.1"
					( objectStatus "a" )
				)
				( pin "R7B16.2"
					( objectStatus "b" )
				)
			)
			( gate "C7B10"
				( objectStatus "@baseboard_fab2_lib.baseboard_fab2(sch_1):page232_i301" )
				( pin "C7B10.1"
					( objectStatus "a" )
				)
				( pin "C7B10.2"
					( objectStatus "b" )
				)
			)
			( gate "C7B13"
				( objectStatus "@baseboard_fab2_lib.baseboard_fab2(sch_1):page232_i302" )
				( pin "C7B13.1"
					( objectStatus "a" )
				)
				( pin "C7B13.2"
					( objectStatus "b" )
				)
			)
			( gate "R7B15"
				( objectStatus "@baseboard_fab2_lib.baseboard_fab2(sch_1):page232_i303" )
				( pin "R7B15.1"
					( objectStatus "a" )
				)
				( pin "R7B15.2"
					( objectStatus "b" )
				)
			)
			( gate "R7B13"
				( objectStatus "@baseboard_fab2_lib.baseboard_fab2(sch_1):page232_i304" )
				( pin "R7B13.1"
					( objectStatus "a" )
				)
				( pin "R7B13.2"
					( objectStatus "b" )
				)
			)
			( gate "C7B14"
				( objectStatus "@baseboard_fab2_lib.baseboard_fab2(sch_1):page232_i306" )
				( pin "C7B14.1"
					( objectStatus "a" )
				)
				( pin "C7B14.2"
					( objectStatus "b" )
				)
			)
			( gate "R7B9"
				( objectStatus "@baseboard_fab2_lib.baseboard_fab2(sch_1):page232_i307" )
				( pin "R7B9.1"
					( objectStatus "a" )
				)
				( pin "R7B9.2"
					( objectStatus "b" )
				)
			)
			( gate "C7U4"
				( objectStatus "@baseboard_fab2_lib.baseboard_fab2(sch_1):page233_i109" )
				( pin "C7U4.1"
					( objectStatus "a" )
				)
				( pin "C7U4.2"
					( objectStatus "b" )
				)
			)
			( gate "C7U5"
				( objectStatus "@baseboard_fab2_lib.baseboard_fab2(sch_1):page233_i111" )
				( pin "C7U5.1"
					( objectStatus "a" )
				)
				( pin "C7U5.2"
					( objectStatus "b" )
				)
			)
			( gate "C7T2"
				( objectStatus "@baseboard_fab2_lib.baseboard_fab2(sch_1):page233_i112" )
				( pin "C7T2.1"
					( objectStatus "a" )
				)
				( pin "C7T2.2"
					( objectStatus "b" )
				)
			)
			( gate "C7T3"
				( objectStatus "@baseboard_fab2_lib.baseboard_fab2(sch_1):page233_i113" )
				( pin "C7T3.1"
					( objectStatus "a" )
				)
				( pin "C7T3.2"
					( objectStatus "b" )
				)
			)
			( gate "C7U6"
				( objectStatus "@baseboard_fab2_lib.baseboard_fab2(sch_1):page233_i115" )
				( pin "C7U6.1"
					( objectStatus "a" )
				)
				( pin "C7U6.2"
					( objectStatus "b" )
				)
			)
			( gate "C3F3"
				( objectStatus "@baseboard_fab2_lib.baseboard_fab2(sch_1):page233_i116" )
				( pin "C3F3.1"
					( objectStatus "a" )
				)
				( pin "C3F3.2"
					( objectStatus "b" )
				)
			)
			( gate "C3F4"
				( objectStatus "@baseboard_fab2_lib.baseboard_fab2(sch_1):page233_i117" )
				( pin "C3F4.1"
					( objectStatus "a" )
				)
				( pin "C3F4.2"
					( objectStatus "b" )
				)
			)
			( gate "C3G3"
				( objectStatus "@baseboard_fab2_lib.baseboard_fab2(sch_1):page233_i118" )
				( pin "C3G3.1"
					( objectStatus "a" )
				)
				( pin "C3G3.2"
					( objectStatus "b" )
				)
			)
			( gate "C3G7"
				( objectStatus "@baseboard_fab2_lib.baseboard_fab2(sch_1):page233_i132" )
				( pin "C3G7.1"
					( objectStatus "a" )
				)
				( pin "C3G7.2"
					( objectStatus "b" )
				)
			)
			( gate "C3G4"
				( objectStatus "@baseboard_fab2_lib.baseboard_fab2(sch_1):page233_i133" )
				( pin "C3G4.1"
					( objectStatus "a" )
				)
				( pin "C3G4.2"
					( objectStatus "b" )
				)
			)
			( gate "C3G8"
				( objectStatus "@baseboard_fab2_lib.baseboard_fab2(sch_1):page233_i135" )
				( pin "C3G8.1"
					( objectStatus "a" )
				)
				( pin "C3G8.2"
					( objectStatus "b" )
				)
			)
			( gate "C7U3"
				( objectStatus "@baseboard_fab2_lib.baseboard_fab2(sch_1):page233_i136" )
				( pin "C7U3.1"
					( objectStatus "a" )
				)
				( pin "C7U3.2"
					( objectStatus "b" )
				)
			)
			( gate "R6U2"
				( objectStatus "@baseboard_fab2_lib.baseboard_fab2(sch_1):page233_i157" )
				( pin "R6U2.1"
					( objectStatus "a" )
				)
				( pin "R6U2.2"
					( objectStatus "b" )
				)
			)
			( gate "R4G5"
				( objectStatus "@baseboard_fab2_lib.baseboard_fab2(sch_1):page233_i182" )
				( pin "R4G5.1"
					( objectStatus "a" )
				)
				( pin "R4G5.2"
					( objectStatus "b" )
				)
			)
			( gate "C4G7"
				( objectStatus "@baseboard_fab2_lib.baseboard_fab2(sch_1):page233_i183" )
				( pin "C4G7.1"
					( objectStatus "a" )
				)
				( pin "C4G7.2"
					( objectStatus "b" )
				)
			)
			( gate "R4G11"
				( objectStatus "@baseboard_fab2_lib.baseboard_fab2(sch_1):page233_i184" )
				( pin "R4G11.1"
					( objectStatus "a" )
				)
				( pin "R4G11.2"
					( objectStatus "b" )
				)
			)
			( gate "R4G14"
				( objectStatus "@baseboard_fab2_lib.baseboard_fab2(sch_1):page233_i185" )
				( pin "R4G14.1"
					( objectStatus "a" )
				)
				( pin "R4G14.2"
					( objectStatus "b" )
				)
			)
			( gate "C6U6"
				( objectStatus "@baseboard_fab2_lib.baseboard_fab2(sch_1):page233_i187" )
				( pin "C6U6.1"
					( objectStatus "a" )
				)
				( pin "C6U6.2"
					( objectStatus "b" )
				)
			)
			( gate "C4G5"
				( objectStatus "@baseboard_fab2_lib.baseboard_fab2(sch_1):page233_i189" )
				( pin "C4G5.1"
					( objectStatus "a" )
				)
				( pin "C4G5.2"
					( objectStatus "b" )
				)
			)
			( gate "C4G8"
				( objectStatus "@baseboard_fab2_lib.baseboard_fab2(sch_1):page233_i194" )
				( pin "C4G8.1"
					( objectStatus "a" )
				)
				( pin "C4G8.2"
					( objectStatus "b" )
				)
			)
			( gate "C4G4"
				( objectStatus "@baseboard_fab2_lib.baseboard_fab2(sch_1):page233_i196" )
				( pin "C4G4.1"
					( objectStatus "a" )
				)
				( pin "C4G4.2"
					( objectStatus "b" )
				)
			)
			( gate "FB4G1"
				( objectStatus "@baseboard_fab2_lib.baseboard_fab2(sch_1):page233_i198" )
				( pin "FB4G1.1"
					( objectStatus "a" )
				)
				( pin "FB4G1.2"
					( objectStatus "b" )
				)
			)
			( gate "R6U1"
				( objectStatus "@baseboard_fab2_lib.baseboard_fab2(sch_1):page233_i199" )
				( pin "R6U1.1"
					( objectStatus "a" )
				)
				( pin "R6U1.2"
					( objectStatus "b" )
				)
			)
			( gate "C4G9"
				( objectStatus "@baseboard_fab2_lib.baseboard_fab2(sch_1):page233_i201" )
				( pin "C4G9.1"
					( objectStatus "a" )
				)
				( pin "C4G9.2"
					( objectStatus "b" )
				)
			)
			( gate "R4F6"
				( objectStatus "@baseboard_fab2_lib.baseboard_fab2(sch_1):page233_i208" )
				( pin "R4F6.1"
					( objectStatus "a" )
				)
				( pin "R4F6.2"
					( objectStatus "b" )
				)
			)
			( gate "C4F12"
				( objectStatus "@baseboard_fab2_lib.baseboard_fab2(sch_1):page233_i209" )
				( pin "C4F12.1"
					( objectStatus "a" )
				)
				( pin "C4F12.2"
					( objectStatus "b" )
				)
			)
			( gate "R4G6"
				( objectStatus "@baseboard_fab2_lib.baseboard_fab2(sch_1):page233_i211" )
				( pin "R4G6.1"
					( objectStatus "a" )
				)
				( pin "R4G6.2"
					( objectStatus "b" )
				)
			)
			( gate "C4F7"
				( objectStatus "@baseboard_fab2_lib.baseboard_fab2(sch_1):page233_i217" )
				( pin "C4F7.1"
					( objectStatus "a" )
				)
				( pin "C4F7.2"
					( objectStatus "b" )
				)
			)
			( gate "C6U3"
				( objectStatus "@baseboard_fab2_lib.baseboard_fab2(sch_1):page233_i221" )
				( pin "C6U3.1"
					( objectStatus "a" )
				)
				( pin "C6U3.2"
					( objectStatus "b" )
				)
			)
			( gate "C6U2"
				( objectStatus "@baseboard_fab2_lib.baseboard_fab2(sch_1):page233_i223" )
				( pin "C6U2.1"
					( objectStatus "a" )
				)
				( pin "C6U2.2"
					( objectStatus "b" )
				)
			)
			( gate "C6U1"
				( objectStatus "@baseboard_fab2_lib.baseboard_fab2(sch_1):page233_i224" )
				( pin "C6U1.1"
					( objectStatus "a" )
				)
				( pin "C6U1.2"
					( objectStatus "b" )
				)
			)
			( gate "EU4G1"
				( objectStatus "@baseboard_fab2_lib.baseboard_fab2(sch_1):page233_i225" )
				( pin "EU4G1.5"
					( objectStatus "agnd" )
				)
				( pin "EU4G1.36"
					( objectStatus "bst" )
				)
				( pin "EU4G1.3"
					( objectStatus "comp" )
				)
				( pin "EU4G1.40"
					( objectStatus "en" )
				)
				( pin "EU4G1.2"
					( objectStatus "fb" )
				)
				( pin "EU4G1.41"
					( objectStatus "gnd" )
				)
				( pin "EU4G1.4"
					( objectStatus "iset" )
				)
				( pin "EU4G1.6"
					( objectStatus "ots" )
				)
				( pin "EU4G1.7"
					( objectStatus "pg" )
				)
				( pin "EU4G1.16"
					( objectStatus "pgnd(0)" )
				)
				( pin "EU4G1.17"
					( objectStatus "pgnd(1)" )
				)
				( pin "EU4G1.18"
					( objectStatus "pgnd(2)" )
				)
				( pin "EU4G1.19"
					( objectStatus "pgnd(3)" )
				)
				( pin "EU4G1.20"
					( objectStatus "pgnd(4)" )
				)
				( pin "EU4G1.21"
					( objectStatus "pgnd(5)" )
				)
				( pin "EU4G1.22"
					( objectStatus "pgnd(6)" )
				)
				( pin "EU4G1.23"
					( objectStatus "pgnd(7)" )
				)
				( pin "EU4G1.24"
					( objectStatus "pgnd(8)" )
				)
				( pin "EU4G1.25"
					( objectStatus "pgnd(9)" )
				)
				( pin "EU4G1.26"
					( objectStatus "pgnd(10)" )
				)
				( pin "EU4G1.27"
					( objectStatus "pgnd(11)" )
				)
				( pin "EU4G1.28"
					( objectStatus "pgnd(12)" )
				)
				( pin "EU4G1.37"
					( objectStatus "pgnd(13)" )
				)
				( pin "EU4G1.1"
					( objectStatus "ss" )
				)
				( pin "EU4G1.38"
					( objectStatus "vb" )
				)
				( pin "EU4G1.39"
					( objectStatus "vcc" )
				)
				( pin "EU4G1.8"
					( objectStatus "vin(0)" )
				)
				( pin "EU4G1.9"
					( objectStatus "vin(1)" )
				)
				( pin "EU4G1.10"
					( objectStatus "vin(2)" )
				)
				( pin "EU4G1.11"
					( objectStatus "vin(3)" )
				)
				( pin "EU4G1.12"
					( objectStatus "vin(4)" )
				)
				( pin "EU4G1.13"
					( objectStatus "vin(5)" )
				)
				( pin "EU4G1.14"
					( objectStatus "vin(6)" )
				)
				( pin "EU4G1.42"
					( objectStatus "vin(7)" )
				)
				( pin "EU4G1.35"
					( objectStatus "vsw" )
				)
				( pin "EU4G1.15"
					( objectStatus "vswh(0)" )
				)
				( pin "EU4G1.29"
					( objectStatus "vswh(1)" )
				)
				( pin "EU4G1.30"
					( objectStatus "vswh(2)" )
				)
				( pin "EU4G1.31"
					( objectStatus "vswh(3)" )
				)
				( pin "EU4G1.32"
					( objectStatus "vswh(4)" )
				)
				( pin "EU4G1.33"
					( objectStatus "vswh(5)" )
				)
				( pin "EU4G1.34"
					( objectStatus "vswh(6)" )
				)
				( pin "EU4G1.43"
					( objectStatus "vswh(7)" )
				)
			)
			( gate "C6U5"
				( objectStatus "@baseboard_fab2_lib.baseboard_fab2(sch_1):page233_i242" )
				( pin "C6U5.1"
					( objectStatus "a" )
				)
				( pin "C6U5.2"
					( objectStatus "b" )
				)
			)
			( gate "R4G12"
				( objectStatus "@baseboard_fab2_lib.baseboard_fab2(sch_1):page233_i247" )
				( pin "R4G12.1"
					( objectStatus "a" )
				)
				( pin "R4G12.2"
					( objectStatus "b" )
				)
			)
			( gate "C6U4"
				( objectStatus "@baseboard_fab2_lib.baseboard_fab2(sch_1):page233_i248" )
				( pin "C6U4.1"
					( objectStatus "a" )
				)
				( pin "C6U4.2"
					( objectStatus "b" )
				)
			)
			( gate "C4G2"
				( objectStatus "@baseboard_fab2_lib.baseboard_fab2(sch_1):page233_i253" )
				( pin "C4G2.1"
					( objectStatus "a" )
				)
				( pin "C4G2.2"
					( objectStatus "b" )
				)
			)
			( gate "C6U7"
				( objectStatus "@baseboard_fab2_lib.baseboard_fab2(sch_1):page233_i254" )
				( pin "C6U7.1"
					( objectStatus "a" )
				)
				( pin "C6U7.2"
					( objectStatus "b" )
				)
			)
			( gate "C6U8"
				( objectStatus "@baseboard_fab2_lib.baseboard_fab2(sch_1):page233_i255" )
				( pin "C6U8.1"
					( objectStatus "a" )
				)
				( pin "C6U8.2"
					( objectStatus "b" )
				)
			)
			( gate "C4F11"
				( objectStatus "@baseboard_fab2_lib.baseboard_fab2(sch_1):page233_i256" )
				( pin "C4F11.1"
					( objectStatus "a" )
				)
				( pin "C4F11.2"
					( objectStatus "b" )
				)
			)
			( gate "R4G10"
				( objectStatus "@baseboard_fab2_lib.baseboard_fab2(sch_1):page233_i266" )
				( pin "R4G10.1"
					( objectStatus "a" )
				)
				( pin "R4G10.2"
					( objectStatus "b" )
				)
			)
			( gate "C4G11"
				( objectStatus "@baseboard_fab2_lib.baseboard_fab2(sch_1):page233_i267" )
				( pin "C4G11.1"
					( objectStatus "a" )
				)
				( pin "C4G11.2"
					( objectStatus "b" )
				)
			)
			( gate "R4G9"
				( objectStatus "@baseboard_fab2_lib.baseboard_fab2(sch_1):page233_i269" )
				( pin "R4G9.1"
					( objectStatus "a" )
				)
				( pin "R4G9.2"
					( objectStatus "b" )
				)
			)
			( gate "R4G7"
				( objectStatus "@baseboard_fab2_lib.baseboard_fab2(sch_1):page233_i270" )
				( pin "R4G7.1"
					( objectStatus "a" )
				)
				( pin "R4G7.2"
					( objectStatus "b" )
				)
			)
			( gate "R4G8"
				( objectStatus "@baseboard_fab2_lib.baseboard_fab2(sch_1):page233_i271" )
				( pin "R4G8.1"
					( objectStatus "a" )
				)
				( pin "R4G8.2"
					( objectStatus "b" )
				)
			)
			( gate "R4G13"
				( objectStatus "@baseboard_fab2_lib.baseboard_fab2(sch_1):page233_i272" )
				( pin "R4G13.1"
					( objectStatus "a" )
				)
				( pin "R4G13.2"
					( objectStatus "b" )
				)
			)
			( gate "C4G6"
				( objectStatus "@baseboard_fab2_lib.baseboard_fab2(sch_1):page233_i273" )
				( pin "C4G6.1"
					( objectStatus "a" )
				)
				( pin "C4G6.2"
					( objectStatus "b" )
				)
			)
			( gate "C4G10"
				( objectStatus "@baseboard_fab2_lib.baseboard_fab2(sch_1):page233_i274" )
				( pin "C4G10.1"
					( objectStatus "a" )
				)
				( pin "C4G10.2"
					( objectStatus "b" )
				)
			)
			( gate "R4G4"
				( objectStatus "@baseboard_fab2_lib.baseboard_fab2(sch_1):page233_i275" )
				( pin "R4G4.1"
					( objectStatus "a" )
				)
				( pin "R4G4.2"
					( objectStatus "b" )
				)
			)
			( gate "L4G1"
				( objectStatus "@baseboard_fab2_lib.baseboard_fab2(sch_1):page233_i277" )
				( pin "L4G1.1"
					( objectStatus "ina" )
				)
				( pin "L4G1.2"
					( objectStatus "inb" )
				)
			)
			( gate "R6M3"
				( objectStatus "@baseboard_fab2_lib.baseboard_fab2(sch_1):page234_i29" )
				( pin "R6M3.1"
					( objectStatus "a" )
				)
				( pin "R6M3.2"
					( objectStatus "b" )
				)
			)
			( gate "C3B2"
				( objectStatus "@baseboard_fab2_lib.baseboard_fab2(sch_1):page234_i84" )
				( pin "C3B2.1"
					( objectStatus "a" )
				)
				( pin "C3B2.2"
					( objectStatus "b" )
				)
			)
			( gate "C3A8"
				( objectStatus "@baseboard_fab2_lib.baseboard_fab2(sch_1):page234_i86" )
				( pin "C3A8.1"
					( objectStatus "a" )
				)
				( pin "C3A8.2"
					( objectStatus "b" )
				)
			)
			( gate "C7L3"
				( objectStatus "@baseboard_fab2_lib.baseboard_fab2(sch_1):page234_i87" )
				( pin "C7L3.1"
					( objectStatus "a" )
				)
				( pin "C7L3.2"
					( objectStatus "b" )
				)
			)
			( gate "C7L2"
				( objectStatus "@baseboard_fab2_lib.baseboard_fab2(sch_1):page234_i88" )
				( pin "C7L2.1"
					( objectStatus "a" )
				)
				( pin "C7L2.2"
					( objectStatus "b" )
				)
			)
			( gate "C7L7"
				( objectStatus "@baseboard_fab2_lib.baseboard_fab2(sch_1):page234_i89" )
				( pin "C7L7.1"
					( objectStatus "a" )
				)
				( pin "C7L7.2"
					( objectStatus "b" )
				)
			)
			( gate "C7L6"
				( objectStatus "@baseboard_fab2_lib.baseboard_fab2(sch_1):page234_i90" )
				( pin "C7L6.1"
					( objectStatus "a" )
				)
				( pin "C7L6.2"
					( objectStatus "b" )
				)
			)
			( gate "C7M4"
				( objectStatus "@baseboard_fab2_lib.baseboard_fab2(sch_1):page234_i91" )
				( pin "C7M4.1"
					( objectStatus "a" )
				)
				( pin "C7M4.2"
					( objectStatus "b" )
				)
			)
			( gate "C7M3"
				( objectStatus "@baseboard_fab2_lib.baseboard_fab2(sch_1):page234_i92" )
				( pin "C7M3.1"
					( objectStatus "a" )
				)
				( pin "C7M3.2"
					( objectStatus "b" )
				)
			)
			( gate "C3A4"
				( objectStatus "@baseboard_fab2_lib.baseboard_fab2(sch_1):page234_i93" )
				( pin "C3A4.1"
					( objectStatus "a" )
				)
				( pin "C3A4.2"
					( objectStatus "b" )
				)
			)
			( gate "C3B1"
				( objectStatus "@baseboard_fab2_lib.baseboard_fab2(sch_1):page234_i94" )
				( pin "C3B1.1"
					( objectStatus "a" )
				)
				( pin "C3B1.2"
					( objectStatus "b" )
				)
			)
			( gate "C3A7"
				( objectStatus "@baseboard_fab2_lib.baseboard_fab2(sch_1):page234_i95" )
				( pin "C3A7.1"
					( objectStatus "a" )
				)
				( pin "C3A7.2"
					( objectStatus "b" )
				)
			)
			( gate "C3A3"
				( objectStatus "@baseboard_fab2_lib.baseboard_fab2(sch_1):page234_i97" )
				( pin "C3A3.1"
					( objectStatus "a" )
				)
				( pin "C3A3.2"
					( objectStatus "b" )
				)
			)
			( gate "C4B5"
				( objectStatus "@baseboard_fab2_lib.baseboard_fab2(sch_1):page234_i129" )
				( pin "C4B5.1"
					( objectStatus "a" )
				)
				( pin "C4B5.2"
					( objectStatus "b" )
				)
			)
			( gate "C4B1"
				( objectStatus "@baseboard_fab2_lib.baseboard_fab2(sch_1):page234_i130" )
				( pin "C4B1.1"
					( objectStatus "a" )
				)
				( pin "C4B1.2"
					( objectStatus "b" )
				)
			)
			( gate "C4B8"
				( objectStatus "@baseboard_fab2_lib.baseboard_fab2(sch_1):page234_i139" )
				( pin "C4B8.1"
					( objectStatus "a" )
				)
				( pin "C4B8.2"
					( objectStatus "b" )
				)
			)
			( gate "R4B6"
				( objectStatus "@baseboard_fab2_lib.baseboard_fab2(sch_1):page234_i140" )
				( pin "R4B6.1"
					( objectStatus "a" )
				)
				( pin "R4B6.2"
					( objectStatus "b" )
				)
			)
			( gate "R4B10"
				( objectStatus "@baseboard_fab2_lib.baseboard_fab2(sch_1):page234_i143" )
				( pin "R4B10.1"
					( objectStatus "a" )
				)
				( pin "R4B10.2"
					( objectStatus "b" )
				)
			)
			( gate "C6M4"
				( objectStatus "@baseboard_fab2_lib.baseboard_fab2(sch_1):page234_i144" )
				( pin "C6M4.1"
					( objectStatus "a" )
				)
				( pin "C6M4.2"
					( objectStatus "b" )
				)
			)
			( gate "C4B6"
				( objectStatus "@baseboard_fab2_lib.baseboard_fab2(sch_1):page234_i146" )
				( pin "C4B6.1"
					( objectStatus "a" )
				)
				( pin "C4B6.2"
					( objectStatus "b" )
				)
			)
			( gate "C6L11"
				( objectStatus "@baseboard_fab2_lib.baseboard_fab2(sch_1):page234_i152" )
				( pin "C6L11.1"
					( objectStatus "a" )
				)
				( pin "C6L11.2"
					( objectStatus "b" )
				)
			)
			( gate "FB4A1"
				( objectStatus "@baseboard_fab2_lib.baseboard_fab2(sch_1):page234_i154" )
				( pin "FB4A1.1"
					( objectStatus "a" )
				)
				( pin "FB4A1.2"
					( objectStatus "b" )
				)
			)
			( gate "R6L15"
				( objectStatus "@baseboard_fab2_lib.baseboard_fab2(sch_1):page234_i155" )
				( pin "R6L15.1"
					( objectStatus "a" )
				)
				( pin "R6L15.2"
					( objectStatus "b" )
				)
			)
			( gate "R4A7"
				( objectStatus "@baseboard_fab2_lib.baseboard_fab2(sch_1):page234_i162" )
				( pin "R4A7.1"
					( objectStatus "a" )
				)
				( pin "R4A7.2"
					( objectStatus "b" )
				)
			)
			( gate "C4A16"
				( objectStatus "@baseboard_fab2_lib.baseboard_fab2(sch_1):page234_i163" )
				( pin "C4A16.1"
					( objectStatus "a" )
				)
				( pin "C4A16.2"
					( objectStatus "b" )
				)
			)
			( gate "L4A1"
				( objectStatus "@baseboard_fab2_lib.baseboard_fab2(sch_1):page234_i164" )
				( pin "L4A1.1"
					( objectStatus "ina" )
				)
				( pin "L4A1.2"
					( objectStatus "inb" )
				)
			)
			( gate "C3B3"
				( objectStatus "@baseboard_fab2_lib.baseboard_fab2(sch_1):page234_i167" )
				( pin "C3B3.1"
					( objectStatus "a" )
				)
				( pin "C3B3.2"
					( objectStatus "b" )
				)
			)
			( gate "C4B3"
				( objectStatus "@baseboard_fab2_lib.baseboard_fab2(sch_1):page234_i177" )
				( pin "C4B3.1"
					( objectStatus "a" )
				)
				( pin "C4B3.2"
					( objectStatus "b" )
				)
			)
			( gate "C4B2"
				( objectStatus "@baseboard_fab2_lib.baseboard_fab2(sch_1):page234_i180" )
				( pin "C4B2.1"
					( objectStatus "a" )
				)
				( pin "C4B2.2"
					( objectStatus "b" )
				)
			)
			( gate "C6L9"
				( objectStatus "@baseboard_fab2_lib.baseboard_fab2(sch_1):page234_i182" )
				( pin "C6L9.1"
					( objectStatus "a" )
				)
				( pin "C6L9.2"
					( objectStatus "b" )
				)
			)
			( gate "R4B2"
				( objectStatus "@baseboard_fab2_lib.baseboard_fab2(sch_1):page234_i183" )
				( pin "R4B2.1"
					( objectStatus "a" )
				)
				( pin "R4B2.2"
					( objectStatus "b" )
				)
			)
			( gate "EU4A3"
				( objectStatus "@baseboard_fab2_lib.baseboard_fab2(sch_1):page234_i184" )
				( pin "EU4A3.5"
					( objectStatus "agnd" )
				)
				( pin "EU4A3.36"
					( objectStatus "bst" )
				)
				( pin "EU4A3.3"
					( objectStatus "comp" )
				)
				( pin "EU4A3.40"
					( objectStatus "en" )
				)
				( pin "EU4A3.2"
					( objectStatus "fb" )
				)
				( pin "EU4A3.41"
					( objectStatus "gnd" )
				)
				( pin "EU4A3.4"
					( objectStatus "iset" )
				)
				( pin "EU4A3.6"
					( objectStatus "ots" )
				)
				( pin "EU4A3.7"
					( objectStatus "pg" )
				)
				( pin "EU4A3.16"
					( objectStatus "pgnd(0)" )
				)
				( pin "EU4A3.17"
					( objectStatus "pgnd(1)" )
				)
				( pin "EU4A3.18"
					( objectStatus "pgnd(2)" )
				)
				( pin "EU4A3.19"
					( objectStatus "pgnd(3)" )
				)
				( pin "EU4A3.20"
					( objectStatus "pgnd(4)" )
				)
				( pin "EU4A3.21"
					( objectStatus "pgnd(5)" )
				)
				( pin "EU4A3.22"
					( objectStatus "pgnd(6)" )
				)
				( pin "EU4A3.23"
					( objectStatus "pgnd(7)" )
				)
				( pin "EU4A3.24"
					( objectStatus "pgnd(8)" )
				)
				( pin "EU4A3.25"
					( objectStatus "pgnd(9)" )
				)
				( pin "EU4A3.26"
					( objectStatus "pgnd(10)" )
				)
				( pin "EU4A3.27"
					( objectStatus "pgnd(11)" )
				)
				( pin "EU4A3.28"
					( objectStatus "pgnd(12)" )
				)
				( pin "EU4A3.37"
					( objectStatus "pgnd(13)" )
				)
				( pin "EU4A3.1"
					( objectStatus "ss" )
				)
				( pin "EU4A3.38"
					( objectStatus "vb" )
				)
				( pin "EU4A3.39"
					( objectStatus "vcc" )
				)
				( pin "EU4A3.8"
					( objectStatus "vin(0)" )
				)
				( pin "EU4A3.9"
					( objectStatus "vin(1)" )
				)
				( pin "EU4A3.10"
					( objectStatus "vin(2)" )
				)
				( pin "EU4A3.11"
					( objectStatus "vin(3)" )
				)
				( pin "EU4A3.12"
					( objectStatus "vin(4)" )
				)
				( pin "EU4A3.13"
					( objectStatus "vin(5)" )
				)
				( pin "EU4A3.14"
					( objectStatus "vin(6)" )
				)
				( pin "EU4A3.42"
					( objectStatus "vin(7)" )
				)
				( pin "EU4A3.35"
					( objectStatus "vsw" )
				)
				( pin "EU4A3.15"
					( objectStatus "vswh(0)" )
				)
				( pin "EU4A3.29"
					( objectStatus "vswh(1)" )
				)
				( pin "EU4A3.30"
					( objectStatus "vswh(2)" )
				)
				( pin "EU4A3.31"
					( objectStatus "vswh(3)" )
				)
				( pin "EU4A3.32"
					( objectStatus "vswh(4)" )
				)
				( pin "EU4A3.33"
					( objectStatus "vswh(5)" )
				)
				( pin "EU4A3.34"
					( objectStatus "vswh(6)" )
				)
				( pin "EU4A3.43"
					( objectStatus "vswh(7)" )
				)
			)
			( gate "C4A20"
				( objectStatus "@baseboard_fab2_lib.baseboard_fab2(sch_1):page234_i199" )
				( pin "C4A20.1"
					( objectStatus "a" )
				)
				( pin "C4A20.2"
					( objectStatus "b" )
				)
			)
			( gate "R4B7"
				( objectStatus "@baseboard_fab2_lib.baseboard_fab2(sch_1):page234_i201" )
				( pin "R4B7.1"
					( objectStatus "a" )
				)
				( pin "R4B7.2"
					( objectStatus "b" )
				)
			)
			( gate "C6L10"
				( objectStatus "@baseboard_fab2_lib.baseboard_fab2(sch_1):page234_i202" )
				( pin "C6L10.1"
					( objectStatus "a" )
				)
				( pin "C6L10.2"
					( objectStatus "b" )
				)
			)
			( gate "C6M3"
				( objectStatus "@baseboard_fab2_lib.baseboard_fab2(sch_1):page234_i203" )
				( pin "C6M3.1"
					( objectStatus "a" )
				)
				( pin "C6M3.2"
					( objectStatus "b" )
				)
			)
			( gate "C6M5"
				( objectStatus "@baseboard_fab2_lib.baseboard_fab2(sch_1):page234_i204" )
				( pin "C6M5.1"
					( objectStatus "a" )
				)
				( pin "C6M5.2"
					( objectStatus "b" )
				)
			)
			( gate "C4A19"
				( objectStatus "@baseboard_fab2_lib.baseboard_fab2(sch_1):page234_i205" )
				( pin "C4A19.1"
					( objectStatus "a" )
				)
				( pin "C4A19.2"
					( objectStatus "b" )
				)
			)
			( gate "C6L8"
				( objectStatus "@baseboard_fab2_lib.baseboard_fab2(sch_1):page234_i210" )
				( pin "C6L8.1"
					( objectStatus "a" )
				)
				( pin "C6L8.2"
					( objectStatus "b" )
				)
			)
			( gate "C4B9"
				( objectStatus "@baseboard_fab2_lib.baseboard_fab2(sch_1):page234_i211" )
				( pin "C4B9.1"
					( objectStatus "a" )
				)
				( pin "C4B9.2"
					( objectStatus "b" )
				)
			)
			( gate "C4B4"
				( objectStatus "@baseboard_fab2_lib.baseboard_fab2(sch_1):page234_i212" )
				( pin "C4B4.1"
					( objectStatus "a" )
				)
				( pin "C4B4.2"
					( objectStatus "b" )
				)
			)
			( gate "R4B8"
				( objectStatus "@baseboard_fab2_lib.baseboard_fab2(sch_1):page234_i213" )
				( pin "R4B8.1"
					( objectStatus "a" )
				)
				( pin "R4B8.2"
					( objectStatus "b" )
				)
			)
			( gate "R4B3"
				( objectStatus "@baseboard_fab2_lib.baseboard_fab2(sch_1):page234_i214" )
				( pin "R4B3.1"
					( objectStatus "a" )
				)
				( pin "R4B3.2"
					( objectStatus "b" )
				)
			)
			( gate "R4B5"
				( objectStatus "@baseboard_fab2_lib.baseboard_fab2(sch_1):page234_i215" )
				( pin "R4B5.1"
					( objectStatus "a" )
				)
				( pin "R4B5.2"
					( objectStatus "b" )
				)
			)
			( gate "R4B4"
				( objectStatus "@baseboard_fab2_lib.baseboard_fab2(sch_1):page234_i216" )
				( pin "R4B4.1"
					( objectStatus "a" )
				)
				( pin "R4B4.2"
					( objectStatus "b" )
				)
			)
			( gate "C4B7"
				( objectStatus "@baseboard_fab2_lib.baseboard_fab2(sch_1):page234_i218" )
				( pin "C4B7.1"
					( objectStatus "a" )
				)
				( pin "C4B7.2"
					( objectStatus "b" )
				)
			)
			( gate "R4B9"
				( objectStatus "@baseboard_fab2_lib.baseboard_fab2(sch_1):page234_i219" )
				( pin "R4B9.1"
					( objectStatus "a" )
				)
				( pin "R4B9.2"
					( objectStatus "b" )
				)
			)
			( gate "R4B1"
				( objectStatus "@baseboard_fab2_lib.baseboard_fab2(sch_1):page234_i220" )
				( pin "R4B1.1"
					( objectStatus "a" )
				)
				( pin "R4B1.2"
					( objectStatus "b" )
				)
			)
			( gate "C8A7"
				( objectStatus "@baseboard_fab2_lib.baseboard_fab2(sch_1):page235_i143" )
				( pin "C8A7.1"
					( objectStatus "a" )
				)
				( pin "C8A7.2"
					( objectStatus "b" )
				)
			)
			( gate "C8A8"
				( objectStatus "@baseboard_fab2_lib.baseboard_fab2(sch_1):page235_i145" )
				( pin "C8A8.1"
					( objectStatus "a" )
				)
				( pin "C8A8.2"
					( objectStatus "b" )
				)
			)
			( gate "R2L16"
				( objectStatus "@baseboard_fab2_lib.baseboard_fab2(sch_1):page235_i147" )
				( pin "R2L16.1"
					( objectStatus "a" )
				)
				( pin "R2L16.2"
					( objectStatus "b" )
				)
			)
			( gate "R8A3"
				( objectStatus "@baseboard_fab2_lib.baseboard_fab2(sch_1):page235_i148" )
				( pin "R8A3.1"
					( objectStatus "a" )
				)
				( pin "R8A3.2"
					( objectStatus "b" )
				)
			)
			( gate "R8A6"
				( objectStatus "@baseboard_fab2_lib.baseboard_fab2(sch_1):page235_i149" )
				( pin "R8A6.1"
					( objectStatus "a" )
				)
				( pin "R8A6.2"
					( objectStatus "b" )
				)
			)
			( gate "C2L8"
				( objectStatus "@baseboard_fab2_lib.baseboard_fab2(sch_1):page235_i151" )
				( pin "C2L8.1"
					( objectStatus "a" )
				)
				( pin "C2L8.2"
					( objectStatus "b" )
				)
			)
			( gate "C2L2"
				( objectStatus "@baseboard_fab2_lib.baseboard_fab2(sch_1):page235_i153" )
				( pin "C2L2.1"
					( objectStatus "a" )
				)
				( pin "C2L2.2"
					( objectStatus "b" )
				)
			)
			( gate "R2L8"
				( objectStatus "@baseboard_fab2_lib.baseboard_fab2(sch_1):page235_i154" )
				( pin "R2L8.1"
					( objectStatus "a" )
				)
				( pin "R2L8.2"
					( objectStatus "b" )
				)
			)
			( gate "R2L14"
				( objectStatus "@baseboard_fab2_lib.baseboard_fab2(sch_1):page235_i159" )
				( pin "R2L14.1"
					( objectStatus "a" )
				)
				( pin "R2L14.2"
					( objectStatus "b" )
				)
			)
			( gate "R8A4"
				( objectStatus "@baseboard_fab2_lib.baseboard_fab2(sch_1):page235_i165" )
				( pin "R8A4.1"
					( objectStatus "a" )
				)
				( pin "R8A4.2"
					( objectStatus "b" )
				)
			)
			( gate "R2L10"
				( objectStatus "@baseboard_fab2_lib.baseboard_fab2(sch_1):page235_i166" )
				( pin "R2L10.1"
					( objectStatus "a" )
				)
				( pin "R2L10.2"
					( objectStatus "b" )
				)
			)
			( gate "C8A3"
				( objectStatus "@baseboard_fab2_lib.baseboard_fab2(sch_1):page235_i167" )
				( pin "C8A3.1"
					( objectStatus "a" )
				)
				( pin "C8A3.2"
					( objectStatus "b" )
				)
			)
			( gate "C2L11"
				( objectStatus "@baseboard_fab2_lib.baseboard_fab2(sch_1):page235_i169" )
				( pin "C2L11.1"
					( objectStatus "a" )
				)
				( pin "C2L11.2"
					( objectStatus "b" )
				)
			)
			( gate "R8A8"
				( objectStatus "@baseboard_fab2_lib.baseboard_fab2(sch_1):page235_i172" )
				( pin "R8A8.1"
					( objectStatus "a" )
				)
				( pin "R8A8.2"
					( objectStatus "b" )
				)
			)
			( gate "R8A9"
				( objectStatus "@baseboard_fab2_lib.baseboard_fab2(sch_1):page235_i173" )
				( pin "R8A9.1"
					( objectStatus "a" )
				)
				( pin "R8A9.2"
					( objectStatus "b" )
				)
			)
			( gate "R2L9"
				( objectStatus "@baseboard_fab2_lib.baseboard_fab2(sch_1):page235_i176" )
				( pin "R2L9.1"
					( objectStatus "a" )
				)
				( pin "R2L9.2"
					( objectStatus "b" )
				)
			)
			( gate "C8A2"
				( objectStatus "@baseboard_fab2_lib.baseboard_fab2(sch_1):page235_i209" )
				( pin "C8A2.1"
					( objectStatus "a" )
				)
				( pin "C8A2.2"
					( objectStatus "b" )
				)
			)
			( gate "R8A1"
				( objectStatus "@baseboard_fab2_lib.baseboard_fab2(sch_1):page235_i210" )
				( pin "R8A1.1"
					( objectStatus "a" )
				)
				( pin "R8A1.2"
					( objectStatus "b" )
				)
			)
			( gate "R8A5"
				( objectStatus "@baseboard_fab2_lib.baseboard_fab2(sch_1):page235_i216" )
				( pin "R8A5.1"
					( objectStatus "a" )
				)
				( pin "R8A5.2"
					( objectStatus "b" )
				)
			)
			( gate "R8A2"
				( objectStatus "@baseboard_fab2_lib.baseboard_fab2(sch_1):page235_i217" )
				( pin "R8A2.1"
					( objectStatus "a" )
				)
				( pin "R8A2.2"
					( objectStatus "b" )
				)
			)
			( gate "C8A9"
				( objectStatus "@baseboard_fab2_lib.baseboard_fab2(sch_1):page235_i218" )
				( pin "C8A9.1"
					( objectStatus "a" )
				)
				( pin "C8A9.2"
					( objectStatus "b" )
				)
			)
			( gate "R2L17"
				( objectStatus "@baseboard_fab2_lib.baseboard_fab2(sch_1):page235_i221" )
				( pin "R2L17.1"
					( objectStatus "a" )
				)
				( pin "R2L17.2"
					( objectStatus "b" )
				)
			)
			( gate "R8A7"
				( objectStatus "@baseboard_fab2_lib.baseboard_fab2(sch_1):page235_i222" )
				( pin "R8A7.1"
					( objectStatus "a" )
				)
				( pin "R8A7.2"
					( objectStatus "b" )
				)
			)
			( gate "R2L1"
				( objectStatus "@baseboard_fab2_lib.baseboard_fab2(sch_1):page235_i224" )
				( pin "R2L1.1"
					( objectStatus "a" )
				)
				( pin "R2L1.2"
					( objectStatus "b" )
				)
			)
			( gate "R2L7"
				( objectStatus "@baseboard_fab2_lib.baseboard_fab2(sch_1):page235_i225" )
				( pin "R2L7.1"
					( objectStatus "a" )
				)
				( pin "R2L7.2"
					( objectStatus "b" )
				)
			)
			( gate "EU8A1"
				( objectStatus "@baseboard_fab2_lib.baseboard_fab2(sch_1):page235_i229" )
				( pin "EU8A1.21"
					( objectStatus "airef1" )
				)
				( pin "EU8A1.22"
					( objectStatus "aisen1" )
				)
				( pin "EU8A1.5"
					( objectStatus "apwm1" )
				)
				( pin "EU8A1.35"
					( objectStatus "atsen" )
				)
				( pin "EU8A1.20"
					( objectStatus "avref" )
				)
				( pin "EU8A1.10"
					( objectStatus "avren" )
				)
				( pin "EU8A1.9"
					( objectStatus "avrrdy" )
				)
				( pin "EU8A1.19"
					( objectStatus "avsen" )
				)
				( pin "EU8A1.25"
					( objectStatus "biref1" )
				)
				( pin "EU8A1.26"
					( objectStatus "bisen1" )
				)
				( pin "EU8A1.3"
					( objectStatus "bpwm1" )
				)
				( pin "EU8A1.34"
					( objectStatus "btsen" )
				)
				( pin "EU8A1.30"
					( objectStatus "bvref" )
				)
				( pin "EU8A1.29"
					( objectStatus "bvsen" )
				)
				( pin "EU8A1.1"
					( objectStatus "dnc(0)" )
				)
				( pin "EU8A1.2"
					( objectStatus "dnc(1)" )
				)
				( pin "EU8A1.4"
					( objectStatus "dnc(2)" )
				)
				( pin "EU8A1.24"
					( objectStatus "dnc(3)" )
				)
				( pin "EU8A1.28"
					( objectStatus "dnc(4)" )
				)
				( pin "EU8A1.27"
					( objectStatus "gnd(0)" )
				)
				( pin "EU8A1.23"
					( objectStatus "gnd(1)" )
				)
				( pin "EU8A1.38"
					( objectStatus "iinsen" )
				)
				( pin "EU8A1.13"
					( objectStatus "mp0" )
				)
				( pin "EU8A1.14"
					( objectStatus "mp1" )
				)
				( pin "EU8A1.18"
					( objectStatus "mp2" )
				)
				( pin "EU8A1.31"
					( objectStatus "mp3" )
				)
				( pin "EU8A1.32"
					( objectStatus "mp4" )
				)
				( pin "EU8A1.12"
					( objectStatus "pinalrt_n" )
				)
				( pin "EU8A1.8"
					( objectStatus "reset_n" )
				)
				( pin "EU8A1.7"
					( objectStatus "scl" )
				)
				( pin "EU8A1.6"
					( objectStatus "sda" )
				)
				( pin "EU8A1.41"
					( objectStatus "thpad" )
				)
				( pin "EU8A1.17"
					( objectStatus "valrt_n" )
				)
				( pin "EU8A1.15"
					( objectStatus "vclk" )
				)
				( pin "EU8A1.40"
					( objectStatus "vd12" )
				)
				( pin "EU8A1.39"
					( objectStatus "vdd" )
				)
				( pin "EU8A1.16"
					( objectStatus "vdio" )
				)
				( pin "EU8A1.37"
					( objectStatus "vinsen" )
				)
				( pin "EU8A1.11"
					( objectStatus "vrhot_n" )
				)
				( pin "EU8A1.36"
					( objectStatus "xaddr1" )
				)
				( pin "EU8A1.33"
					( objectStatus "xaddr2" )
				)
			)
			( gate "R87"
				( objectStatus "@baseboard_fab2_lib.baseboard_fab2(sch_1):page235_i235" )
				( pin "R87.1"
					( objectStatus "a" )
				)
				( pin "R87.2"
					( objectStatus "b" )
				)
			)
			( gate "R88"
				( objectStatus "@baseboard_fab2_lib.baseboard_fab2(sch_1):page235_i236" )
				( pin "R88.1"
					( objectStatus "a" )
				)
				( pin "R88.2"
					( objectStatus "b" )
				)
			)
			( gate "C7A30"
				( objectStatus "@baseboard_fab2_lib.baseboard_fab2(sch_1):page236_i9" )
				( pin "C7A30.1"
					( objectStatus "a" )
				)
				( pin "C7A30.2"
					( objectStatus "b" )
				)
			)
			( gate "L7A2"
				( objectStatus "@baseboard_fab2_lib.baseboard_fab2(sch_1):page236_i10" )
				( pin "L7A2.1"
					( objectStatus "ina" )
				)
				( pin "L7A2.2"
					( objectStatus "inb" )
				)
			)
			( gate "R3L1"
				( objectStatus "@baseboard_fab2_lib.baseboard_fab2(sch_1):page236_i14" )
				( pin "R3L1.1"
					( objectStatus "a" )
				)
				( pin "R3L1.2"
					( objectStatus "b" )
				)
			)
			( gate "C7A8"
				( objectStatus "@baseboard_fab2_lib.baseboard_fab2(sch_1):page236_i16" )
				( pin "C7A8.1"
					( objectStatus "a" )
				)
				( pin "C7A8.2"
					( objectStatus "b" )
				)
			)
			( gate "C3L1"
				( objectStatus "@baseboard_fab2_lib.baseboard_fab2(sch_1):page236_i17" )
				( pin "C3L1.1"
					( objectStatus "a" )
				)
				( pin "C3L1.2"
					( objectStatus "b" )
				)
			)
			( gate "C7A6"
				( objectStatus "@baseboard_fab2_lib.baseboard_fab2(sch_1):page236_i19" )
				( pin "C7A6.1"
					( objectStatus "a" )
				)
				( pin "C7A6.2"
					( objectStatus "b" )
				)
			)
			( gate "C3L5"
				( objectStatus "@baseboard_fab2_lib.baseboard_fab2(sch_1):page236_i20" )
				( pin "C3L5.1"
					( objectStatus "a" )
				)
				( pin "C3L5.2"
					( objectStatus "b" )
				)
			)
			( gate "C7A1"
				( objectStatus "@baseboard_fab2_lib.baseboard_fab2(sch_1):page236_i21" )
				( pin "C7A1.1"
					( objectStatus "a" )
				)
				( pin "C7A1.2"
					( objectStatus "b" )
				)
			)
			( gate "C7A7"
				( objectStatus "@baseboard_fab2_lib.baseboard_fab2(sch_1):page236_i22" )
				( pin "C7A7.1"
					( objectStatus "a" )
				)
				( pin "C7A7.2"
					( objectStatus "b" )
				)
			)
			( gate "C3L12"
				( objectStatus "@baseboard_fab2_lib.baseboard_fab2(sch_1):page236_i23" )
				( pin "C3L12.1"
					( objectStatus "a" )
				)
				( pin "C3L12.2"
					( objectStatus "b" )
				)
			)
			( gate "C3L11"
				( objectStatus "@baseboard_fab2_lib.baseboard_fab2(sch_1):page236_i24" )
				( pin "C3L11.1"
					( objectStatus "a" )
				)
				( pin "C3L11.2"
					( objectStatus "b" )
				)
			)
			( gate "C3L8"
				( objectStatus "@baseboard_fab2_lib.baseboard_fab2(sch_1):page236_i26" )
				( pin "C3L8.1"
					( objectStatus "a" )
				)
				( pin "C3L8.2"
					( objectStatus "b" )
				)
			)
			( gate "C3L9"
				( objectStatus "@baseboard_fab2_lib.baseboard_fab2(sch_1):page236_i29" )
				( pin "C3L9.1"
					( objectStatus "a" )
				)
				( pin "C3L9.2"
					( objectStatus "b" )
				)
			)
			( gate "C3L7"
				( objectStatus "@baseboard_fab2_lib.baseboard_fab2(sch_1):page236_i31" )
				( pin "C3L7.1"
					( objectStatus "a" )
				)
				( pin "C3L7.2"
					( objectStatus "b" )
				)
			)
			( gate "C3L10"
				( objectStatus "@baseboard_fab2_lib.baseboard_fab2(sch_1):page236_i32" )
				( pin "C3L10.1"
					( objectStatus "a" )
				)
				( pin "C3L10.2"
					( objectStatus "b" )
				)
			)
			( gate "C7A9"
				( objectStatus "@baseboard_fab2_lib.baseboard_fab2(sch_1):page236_i33" )
				( pin "C7A9.1"
					( objectStatus "a" )
				)
				( pin "C7A9.2"
					( objectStatus "b" )
				)
			)
			( gate "C7A3"
				( objectStatus "@baseboard_fab2_lib.baseboard_fab2(sch_1):page236_i34" )
				( pin "C7A3.1"
					( objectStatus "a" )
				)
				( pin "C7A3.2"
					( objectStatus "b" )
				)
			)
			( gate "C3L3"
				( objectStatus "@baseboard_fab2_lib.baseboard_fab2(sch_1):page236_i35" )
				( pin "C3L3.1"
					( objectStatus "a" )
				)
				( pin "C3L3.2"
					( objectStatus "b" )
				)
			)
			( gate "C7A10"
				( objectStatus "@baseboard_fab2_lib.baseboard_fab2(sch_1):page236_i36" )
				( pin "C7A10.1"
					( objectStatus "a" )
				)
				( pin "C7A10.2"
					( objectStatus "b" )
				)
			)
			( gate "C8A1"
				( objectStatus "@baseboard_fab2_lib.baseboard_fab2(sch_1):page236_i38" )
				( pin "C8A1.1"
					( objectStatus "a" )
				)
				( pin "C8A1.2"
					( objectStatus "b" )
				)
			)
			( gate "C2L1"
				( objectStatus "@baseboard_fab2_lib.baseboard_fab2(sch_1):page236_i39" )
				( pin "C2L1.1"
					( objectStatus "a" )
				)
				( pin "C2L1.2"
					( objectStatus "b" )
				)
			)
			( gate "R3L4"
				( objectStatus "@baseboard_fab2_lib.baseboard_fab2(sch_1):page236_i41" )
				( pin "R3L4.1"
					( objectStatus "a" )
				)
				( pin "R3L4.2"
					( objectStatus "b" )
				)
			)
			( gate "L7A4"
				( objectStatus "@baseboard_fab2_lib.baseboard_fab2(sch_1):page236_i45" )
				( pin "L7A4.1"
					( objectStatus "ina" )
				)
				( pin "L7A4.2"
					( objectStatus "inb" )
				)
			)
			( gate "C8A16"
				( objectStatus "@baseboard_fab2_lib.baseboard_fab2(sch_1):page236_i46" )
				( pin "C8A16.1"
					( objectStatus "a" )
				)
				( pin "C8A16.2"
					( objectStatus "b" )
				)
			)
			( gate "R8B14"
				( objectStatus "@baseboard_fab2_lib.baseboard_fab2(sch_1):page236_i56" )
				( pin "R8B14.1"
					( objectStatus "a" )
				)
				( pin "R8B14.2"
					( objectStatus "b" )
				)
			)
			( gate "R8B15"
				( objectStatus "@baseboard_fab2_lib.baseboard_fab2(sch_1):page236_i57" )
				( pin "R8B15.1"
					( objectStatus "a" )
				)
				( pin "R8B15.2"
					( objectStatus "b" )
				)
			)
			( gate "R8B12"
				( objectStatus "@baseboard_fab2_lib.baseboard_fab2(sch_1):page236_i59" )
				( pin "R8B12.1"
					( objectStatus "a" )
				)
				( pin "R8B12.2"
					( objectStatus "b" )
				)
			)
			( gate "C7A13"
				( objectStatus "@baseboard_fab2_lib.baseboard_fab2(sch_1):page236_i63" )
				( pin "C7A13.1"
					( objectStatus "a" )
				)
				( pin "C7A13.2"
					( objectStatus "b" )
				)
			)
			( gate "C7A14"
				( objectStatus "@baseboard_fab2_lib.baseboard_fab2(sch_1):page236_i65" )
				( pin "C7A14.1"
					( objectStatus "a" )
				)
				( pin "C7A14.2"
					( objectStatus "b" )
				)
			)
			( gate "C3L18"
				( objectStatus "@baseboard_fab2_lib.baseboard_fab2(sch_1):page236_i71" )
				( pin "C3L18.1"
					( objectStatus "a" )
				)
				( pin "C3L18.2"
					( objectStatus "b" )
				)
			)
			( gate "C3L20"
				( objectStatus "@baseboard_fab2_lib.baseboard_fab2(sch_1):page236_i73" )
				( pin "C3L20.1"
					( objectStatus "a" )
				)
				( pin "C3L20.2"
					( objectStatus "b" )
				)
			)
			( gate "C3L21"
				( objectStatus "@baseboard_fab2_lib.baseboard_fab2(sch_1):page236_i74" )
				( pin "C3L21.1"
					( objectStatus "a" )
				)
				( pin "C3L21.2"
					( objectStatus "b" )
				)
			)
			( gate "C7A27"
				( objectStatus "@baseboard_fab2_lib.baseboard_fab2(sch_1):page236_i75" )
				( pin "C7A27.1"
					( objectStatus "a" )
				)
				( pin "C7A27.2"
					( objectStatus "b" )
				)
			)
			( gate "C3L19"
				( objectStatus "@baseboard_fab2_lib.baseboard_fab2(sch_1):page236_i76" )
				( pin "C3L19.1"
					( objectStatus "a" )
				)
				( pin "C3L19.2"
					( objectStatus "b" )
				)
			)
			( gate "C2L46"
				( objectStatus "@baseboard_fab2_lib.baseboard_fab2(sch_1):page236_i77" )
				( pin "C2L46.1"
					( objectStatus "a" )
				)
				( pin "C2L46.2"
					( objectStatus "b" )
				)
			)
			( gate "C8A15"
				( objectStatus "@baseboard_fab2_lib.baseboard_fab2(sch_1):page236_i78" )
				( pin "C8A15.1"
					( objectStatus "a" )
				)
				( pin "C8A15.2"
					( objectStatus "b" )
				)
			)
			( gate "C2L25"
				( objectStatus "@baseboard_fab2_lib.baseboard_fab2(sch_1):page236_i79" )
				( pin "C2L25.1"
					( objectStatus "a" )
				)
				( pin "C2L25.2"
					( objectStatus "b" )
				)
			)
			( gate "R7A13"
				( objectStatus "@baseboard_fab2_lib.baseboard_fab2(sch_1):page236_i90" )
				( pin "R7A13.1"
					( objectStatus "a" )
				)
				( pin "R7A13.2"
					( objectStatus "b" )
				)
			)
			( gate "R7A18"
				( objectStatus "@baseboard_fab2_lib.baseboard_fab2(sch_1):page236_i92" )
				( pin "R7A18.1"
					( objectStatus "a" )
				)
				( pin "R7A18.2"
					( objectStatus "b" )
				)
			)
			( gate "R7A19"
				( objectStatus "@baseboard_fab2_lib.baseboard_fab2(sch_1):page236_i93" )
				( pin "R7A19.1"
					( objectStatus "a" )
				)
				( pin "R7A19.2"
					( objectStatus "b" )
				)
			)
			( gate "R7A14"
				( objectStatus "@baseboard_fab2_lib.baseboard_fab2(sch_1):page236_i94" )
				( pin "R7A14.1"
					( objectStatus "a" )
				)
				( pin "R7A14.2"
					( objectStatus "b" )
				)
			)
			( gate "EU7A3"
				( objectStatus "@baseboard_fab2_lib.baseboard_fab2(sch_1):page236_i116" )
				( pin "EU7A3.33"
					( objectStatus "boost" )
				)
				( pin "EU7A3.35"
					( objectStatus "en" )
				)
				( pin "EU7A3.6"
					( objectStatus "gl(0)" )
				)
				( pin "EU7A3.41"
					( objectStatus "gl(1)" )
				)
				( pin "EU7A3.38"
					( objectStatus "iout" )
				)
				( pin "EU7A3.2"
					( objectStatus "lgnd" )
				)
				( pin "EU7A3.31"
					( objectStatus "nc" )
				)
				( pin "EU7A3.37"
					( objectStatus "ocset" )
				)
				( pin "EU7A3.5"
					( objectStatus "pgnd(0)" )
				)
				( pin "EU7A3.7"
					( objectStatus "pgnd(1)" )
				)
				( pin "EU7A3.40"
					( objectStatus "pgnd(2)" )
				)
				( pin "EU7A3.32"
					( objectStatus "phase" )
				)
				( pin "EU7A3.34"
					( objectStatus "pwm" )
				)
				( pin "EU7A3.39"
					( objectStatus "refin" )
				)
				( pin "EU7A3.10"
					( objectStatus "sw" )
				)
				( pin "EU7A3.36"
					( objectStatus "tout_flt" )
				)
				( pin "EU7A3.3"
					( objectStatus "vcc" )
				)
				( pin "EU7A3.4"
					( objectStatus "vdrv" )
				)
				( pin "EU7A3.25"
					( objectStatus "vin(0)" )
				)
				( pin "EU7A3.30"
					( objectStatus "vin(1)" )
				)
				( pin "EU7A3.1"
					( objectStatus "vos" )
				)
			)
			( gate "EU7A2"
				( objectStatus "@baseboard_fab2_lib.baseboard_fab2(sch_1):page236_i117" )
				( pin "EU7A2.33"
					( objectStatus "boost" )
				)
				( pin "EU7A2.35"
					( objectStatus "en" )
				)
				( pin "EU7A2.6"
					( objectStatus "gl(0)" )
				)
				( pin "EU7A2.41"
					( objectStatus "gl(1)" )
				)
				( pin "EU7A2.38"
					( objectStatus "iout" )
				)
				( pin "EU7A2.2"
					( objectStatus "lgnd" )
				)
				( pin "EU7A2.31"
					( objectStatus "nc" )
				)
				( pin "EU7A2.37"
					( objectStatus "ocset" )
				)
				( pin "EU7A2.5"
					( objectStatus "pgnd(0)" )
				)
				( pin "EU7A2.7"
					( objectStatus "pgnd(1)" )
				)
				( pin "EU7A2.40"
					( objectStatus "pgnd(2)" )
				)
				( pin "EU7A2.32"
					( objectStatus "phase" )
				)
				( pin "EU7A2.34"
					( objectStatus "pwm" )
				)
				( pin "EU7A2.39"
					( objectStatus "refin" )
				)
				( pin "EU7A2.10"
					( objectStatus "sw" )
				)
				( pin "EU7A2.36"
					( objectStatus "tout_flt" )
				)
				( pin "EU7A2.3"
					( objectStatus "vcc" )
				)
				( pin "EU7A2.4"
					( objectStatus "vdrv" )
				)
				( pin "EU7A2.25"
					( objectStatus "vin(0)" )
				)
				( pin "EU7A2.30"
					( objectStatus "vin(1)" )
				)
				( pin "EU7A2.1"
					( objectStatus "vos" )
				)
			)
			( gate "R45"
				( objectStatus "@baseboard_fab2_lib.baseboard_fab2(sch_1):page236_i118" )
				( pin "R45.1"
					( objectStatus "a" )
				)
				( pin "R45.2"
					( objectStatus "b" )
				)
			)
			( gate "R46"
				( objectStatus "@baseboard_fab2_lib.baseboard_fab2(sch_1):page236_i120" )
				( pin "R46.1"
					( objectStatus "a" )
				)
				( pin "R46.2"
					( objectStatus "b" )
				)
			)
			( gate "R8A10"
				( objectStatus "@baseboard_fab2_lib.baseboard_fab2(sch_1):page237_i3" )
				( pin "R8A10.1"
					( objectStatus "a" )
				)
				( pin "R8A10.2"
					( objectStatus "b" )
				)
			)
			( gate "C8A11"
				( objectStatus "@baseboard_fab2_lib.baseboard_fab2(sch_1):page237_i5" )
				( pin "C8A11.1"
					( objectStatus "a" )
				)
				( pin "C8A11.2"
					( objectStatus "b" )
				)
			)
			( gate "C2L45"
				( objectStatus "@baseboard_fab2_lib.baseboard_fab2(sch_1):page237_i12" )
				( pin "C2L45.1"
					( objectStatus "a" )
				)
				( pin "C2L45.2"
					( objectStatus "b" )
				)
			)
			( gate "C8A14"
				( objectStatus "@baseboard_fab2_lib.baseboard_fab2(sch_1):page237_i13" )
				( pin "C8A14.1"
					( objectStatus "a" )
				)
				( pin "C8A14.2"
					( objectStatus "b" )
				)
			)
			( gate "R8A12"
				( objectStatus "@baseboard_fab2_lib.baseboard_fab2(sch_1):page237_i15" )
				( pin "R8A12.1"
					( objectStatus "a" )
				)
				( pin "R8A12.2"
					( objectStatus "b" )
				)
			)
			( gate "C8A6"
				( objectStatus "@baseboard_fab2_lib.baseboard_fab2(sch_1):page237_i29" )
				( pin "C8A6.1"
					( objectStatus "a" )
				)
				( pin "C8A6.2"
					( objectStatus "b" )
				)
			)
			( gate "C8A4"
				( objectStatus "@baseboard_fab2_lib.baseboard_fab2(sch_1):page237_i31" )
				( pin "C8A4.1"
					( objectStatus "a" )
				)
				( pin "C8A4.2"
					( objectStatus "b" )
				)
			)
			( gate "C8A10"
				( objectStatus "@baseboard_fab2_lib.baseboard_fab2(sch_1):page237_i55" )
				( pin "C8A10.1"
					( objectStatus "a" )
				)
				( pin "C8A10.2"
					( objectStatus "b" )
				)
			)
			( gate "C8A12"
				( objectStatus "@baseboard_fab2_lib.baseboard_fab2(sch_1):page237_i77" )
				( pin "C8A12.1"
					( objectStatus "a" )
				)
				( pin "C8A12.2"
					( objectStatus "b" )
				)
			)
			( gate "C2L32"
				( objectStatus "@baseboard_fab2_lib.baseboard_fab2(sch_1):page237_i79" )
				( pin "C2L32.1"
					( objectStatus "a" )
				)
				( pin "C2L32.2"
					( objectStatus "b" )
				)
			)
			( gate "R2L19"
				( objectStatus "@baseboard_fab2_lib.baseboard_fab2(sch_1):page237_i80" )
				( pin "R2L19.1"
					( objectStatus "a" )
				)
				( pin "R2L19.2"
					( objectStatus "b" )
				)
			)
			( gate "R2L20"
				( objectStatus "@baseboard_fab2_lib.baseboard_fab2(sch_1):page237_i81" )
				( pin "R2L20.1"
					( objectStatus "a" )
				)
				( pin "R2L20.2"
					( objectStatus "b" )
				)
			)
			( gate "EU8A2"
				( objectStatus "@baseboard_fab2_lib.baseboard_fab2(sch_1):page237_i86" )
				( pin "EU8A2.4"
					( objectStatus "adj_nc" )
				)
				( pin "EU8A2.6"
					( objectStatus "en" )
				)
				( pin "EU8A2.11"
					( objectStatus "gnd" )
				)
				( pin "EU8A2.5"
					( objectStatus "pgood" )
				)
				( pin "EU8A2.10"
					( objectStatus "vdd" )
				)
				( pin "EU8A2.7"
					( objectStatus "vin(0)" )
				)
				( pin "EU8A2.8"
					( objectStatus "vin(1)" )
				)
				( pin "EU8A2.9"
					( objectStatus "vin(2)" )
				)
				( pin "EU8A2.1"
					( objectStatus "vout(0)" )
				)
				( pin "EU8A2.2"
					( objectStatus "vout(1)" )
				)
				( pin "EU8A2.3"
					( objectStatus "vout(2)" )
				)
			)
			( gate "R8A11"
				( objectStatus "@baseboard_fab2_lib.baseboard_fab2(sch_1):page237_i90" )
				( pin "R8A11.1"
					( objectStatus "a" )
				)
				( pin "R8A11.2"
					( objectStatus "b" )
				)
			)
			( gate "C9F9"
				( objectStatus "@baseboard_fab2_lib.baseboard_fab2(sch_1):page238_i5" )
				( pin "C9F9.1"
					( objectStatus "a" )
				)
				( pin "C9F9.2"
					( objectStatus "b" )
				)
			)
			( gate "C9F3"
				( objectStatus "@baseboard_fab2_lib.baseboard_fab2(sch_1):page238_i7" )
				( pin "C9F3.1"
					( objectStatus "a" )
				)
				( pin "C9F3.2"
					( objectStatus "b" )
				)
			)
			( gate "R9F8"
				( objectStatus "@baseboard_fab2_lib.baseboard_fab2(sch_1):page238_i14" )
				( pin "R9F8.1"
					( objectStatus "a" )
				)
				( pin "R9F8.2"
					( objectStatus "b" )
				)
			)
			( gate "R9F6"
				( objectStatus "@baseboard_fab2_lib.baseboard_fab2(sch_1):page238_i17" )
				( pin "R9F6.1"
					( objectStatus "a" )
				)
				( pin "R9F6.2"
					( objectStatus "b" )
				)
			)
			( gate "C9F8"
				( objectStatus "@baseboard_fab2_lib.baseboard_fab2(sch_1):page238_i19" )
				( pin "C9F8.1"
					( objectStatus "a" )
				)
				( pin "C9F8.2"
					( objectStatus "b" )
				)
			)
			( gate "R9F13"
				( objectStatus "@baseboard_fab2_lib.baseboard_fab2(sch_1):page238_i21" )
				( pin "R9F13.1"
					( objectStatus "a" )
				)
				( pin "R9F13.2"
					( objectStatus "b" )
				)
			)
			( gate "C9E10"
				( objectStatus "@baseboard_fab2_lib.baseboard_fab2(sch_1):page238_i23" )
				( pin "C9E10.1"
					( objectStatus "a" )
				)
				( pin "C9E10.2"
					( objectStatus "b" )
				)
			)
			( gate "C9F4"
				( objectStatus "@baseboard_fab2_lib.baseboard_fab2(sch_1):page238_i30" )
				( pin "C9F4.1"
					( objectStatus "a" )
				)
				( pin "C9F4.2"
					( objectStatus "b" )
				)
			)
			( gate "C9E11"
				( objectStatus "@baseboard_fab2_lib.baseboard_fab2(sch_1):page238_i39" )
				( pin "C9E11.1"
					( objectStatus "a" )
				)
				( pin "C9E11.2"
					( objectStatus "b" )
				)
			)
			( gate "EU9F1"
				( objectStatus "@baseboard_fab2_lib.baseboard_fab2(sch_1):page238_i40" )
				( pin "EU9F1.4"
					( objectStatus "adj_nc" )
				)
				( pin "EU9F1.6"
					( objectStatus "en" )
				)
				( pin "EU9F1.11"
					( objectStatus "gnd" )
				)
				( pin "EU9F1.5"
					( objectStatus "pgood" )
				)
				( pin "EU9F1.10"
					( objectStatus "vdd" )
				)
				( pin "EU9F1.7"
					( objectStatus "vin(0)" )
				)
				( pin "EU9F1.8"
					( objectStatus "vin(1)" )
				)
				( pin "EU9F1.9"
					( objectStatus "vin(2)" )
				)
				( pin "EU9F1.1"
					( objectStatus "vout(0)" )
				)
				( pin "EU9F1.2"
					( objectStatus "vout(1)" )
				)
				( pin "EU9F1.3"
					( objectStatus "vout(2)" )
				)
			)
			( gate "R9F11"
				( objectStatus "@baseboard_fab2_lib.baseboard_fab2(sch_1):page238_i41" )
				( pin "R9F11.1"
					( objectStatus "a" )
				)
				( pin "R9F11.2"
					( objectStatus "b" )
				)
			)
			( gate "C9F10"
				( objectStatus "@baseboard_fab2_lib.baseboard_fab2(sch_1):page239_i4" )
				( pin "C9F10.1"
					( objectStatus "a" )
				)
				( pin "C9F10.2"
					( objectStatus "b" )
				)
			)
			( gate "R9F12"
				( objectStatus "@baseboard_fab2_lib.baseboard_fab2(sch_1):page239_i6" )
				( pin "R9F12.1"
					( objectStatus "a" )
				)
				( pin "R9F12.2"
					( objectStatus "b" )
				)
			)
			( gate "C9F13"
				( objectStatus "@baseboard_fab2_lib.baseboard_fab2(sch_1):page239_i7" )
				( pin "C9F13.1"
					( objectStatus "a" )
				)
				( pin "C9F13.2"
					( objectStatus "b" )
				)
			)
			( gate "C1T15"
				( objectStatus "@baseboard_fab2_lib.baseboard_fab2(sch_1):page239_i12" )
				( pin "C1T15.1"
					( objectStatus "a" )
				)
				( pin "C1T15.2"
					( objectStatus "b" )
				)
			)
			( gate "R9F31"
				( objectStatus "@baseboard_fab2_lib.baseboard_fab2(sch_1):page239_i14" )
				( pin "R9F31.1"
					( objectStatus "a" )
				)
				( pin "R9F31.2"
					( objectStatus "b" )
				)
			)
			( gate "R9F32"
				( objectStatus "@baseboard_fab2_lib.baseboard_fab2(sch_1):page239_i15" )
				( pin "R9F32.1"
					( objectStatus "a" )
				)
				( pin "R9F32.2"
					( objectStatus "b" )
				)
			)
			( gate "C1T7"
				( objectStatus "@baseboard_fab2_lib.baseboard_fab2(sch_1):page239_i22" )
				( pin "C1T7.1"
					( objectStatus "a" )
				)
				( pin "C1T7.2"
					( objectStatus "b" )
				)
			)
			( gate "C9F6"
				( objectStatus "@baseboard_fab2_lib.baseboard_fab2(sch_1):page239_i30" )
				( pin "C9F6.1"
					( objectStatus "a" )
				)
				( pin "C9F6.2"
					( objectStatus "b" )
				)
			)
			( gate "EU9F2"
				( objectStatus "@baseboard_fab2_lib.baseboard_fab2(sch_1):page239_i70" )
				( pin "EU9F2.4"
					( objectStatus "adj_nc" )
				)
				( pin "EU9F2.6"
					( objectStatus "en" )
				)
				( pin "EU9F2.11"
					( objectStatus "gnd" )
				)
				( pin "EU9F2.5"
					( objectStatus "pgood" )
				)
				( pin "EU9F2.10"
					( objectStatus "vdd" )
				)
				( pin "EU9F2.7"
					( objectStatus "vin(0)" )
				)
				( pin "EU9F2.8"
					( objectStatus "vin(1)" )
				)
				( pin "EU9F2.9"
					( objectStatus "vin(2)" )
				)
				( pin "EU9F2.1"
					( objectStatus "vout(0)" )
				)
				( pin "EU9F2.2"
					( objectStatus "vout(1)" )
				)
				( pin "EU9F2.3"
					( objectStatus "vout(2)" )
				)
			)
			( gate "C9F5"
				( objectStatus "@baseboard_fab2_lib.baseboard_fab2(sch_1):page239_i71" )
				( pin "C9F5.1"
					( objectStatus "a" )
				)
				( pin "C9F5.2"
					( objectStatus "b" )
				)
			)
			( gate "R1T9"
				( objectStatus "@baseboard_fab2_lib.baseboard_fab2(sch_1):page239_i72" )
				( pin "R1T9.1"
					( objectStatus "a" )
				)
				( pin "R1T9.2"
					( objectStatus "b" )
				)
			)
			( gate "R8F9"
				( objectStatus "@baseboard_fab2_lib.baseboard_fab2(sch_1):page240_i106" )
				( pin "R8F9.1"
					( objectStatus "a" )
				)
				( pin "R8F9.2"
					( objectStatus "b" )
				)
			)
			( gate "C2R11"
				( objectStatus "@baseboard_fab2_lib.baseboard_fab2(sch_1):page240_i109" )
				( pin "C2R11.1"
					( objectStatus "a" )
				)
				( pin "C2R11.2"
					( objectStatus "b" )
				)
			)
			( gate "R8F1"
				( objectStatus "@baseboard_fab2_lib.baseboard_fab2(sch_1):page240_i111" )
				( pin "R8F1.1"
					( objectStatus "a" )
				)
				( pin "R8F1.2"
					( objectStatus "b" )
				)
			)
			( gate "C8E17"
				( objectStatus "@baseboard_fab2_lib.baseboard_fab2(sch_1):page240_i113" )
				( pin "C8E17.1"
					( objectStatus "a" )
				)
				( pin "C8E17.2"
					( objectStatus "b" )
				)
			)
			( gate "C8F2"
				( objectStatus "@baseboard_fab2_lib.baseboard_fab2(sch_1):page240_i116" )
				( pin "C8F2.1"
					( objectStatus "a" )
				)
				( pin "C8F2.2"
					( objectStatus "b" )
				)
			)
			( gate "R8F5"
				( objectStatus "@baseboard_fab2_lib.baseboard_fab2(sch_1):page240_i117" )
				( pin "R8F5.1"
					( objectStatus "a" )
				)
				( pin "R8F5.2"
					( objectStatus "b" )
				)
			)
			( gate "EU8F1"
				( objectStatus "@baseboard_fab2_lib.baseboard_fab2(sch_1):page240_i125" )
				( pin "EU8F1.4"
					( objectStatus "boot" )
				)
				( pin "EU8F1.10"
					( objectStatus "cs" )
				)
				( pin "EU8F1.8"
					( objectStatus "en" )
				)
				( pin "EU8F1.11"
					( objectStatus "g0" )
				)
				( pin "EU8F1.12"
					( objectStatus "gnd(0)" )
				)
				( pin "EU8F1.13"
					( objectStatus "gnd(1)" )
				)
				( pin "EU8F1.1"
					( objectStatus "lgate" )
				)
				( pin "EU8F1.9"
					( objectStatus "pgood" )
				)
				( pin "EU8F1.2"
					( objectStatus "phase" )
				)
				( pin "EU8F1.7"
					( objectStatus "rgnd" )
				)
				( pin "EU8F1.3"
					( objectStatus "ugate" )
				)
				( pin "EU8F1.5"
					( objectStatus "vcc" )
				)
				( pin "EU8F1.6"
					( objectStatus "vout" )
				)
			)
			( gate "R8E35"
				( objectStatus "@baseboard_fab2_lib.baseboard_fab2(sch_1):page240_i127" )
				( pin "R8E35.1"
					( objectStatus "a" )
				)
				( pin "R8E35.2"
					( objectStatus "b" )
				)
			)
			( gate "C8E12"
				( objectStatus "@baseboard_fab2_lib.baseboard_fab2(sch_1):page240_i129" )
				( pin "C8E12.1"
					( objectStatus "a" )
				)
				( pin "C8E12.2"
					( objectStatus "b" )
				)
			)
			( gate "FB9E1"
				( objectStatus "@baseboard_fab2_lib.baseboard_fab2(sch_1):page240_i132" )
				( pin "FB9E1.1"
					( objectStatus "a" )
				)
				( pin "FB9E1.2"
					( objectStatus "b" )
				)
			)
			( gate "C9F1"
				( objectStatus "@baseboard_fab2_lib.baseboard_fab2(sch_1):page240_i134" )
				( pin "C9F1.1"
					( objectStatus "a" )
				)
				( pin "C9F1.2"
					( objectStatus "b" )
				)
			)
			( gate "C8E11"
				( objectStatus "@baseboard_fab2_lib.baseboard_fab2(sch_1):page240_i135" )
				( pin "C8E11.1"
					( objectStatus "a" )
				)
				( pin "C8E11.2"
					( objectStatus "b" )
				)
			)
			( gate "C8E10"
				( objectStatus "@baseboard_fab2_lib.baseboard_fab2(sch_1):page240_i137" )
				( pin "C8E10.1"
					( objectStatus "a" )
				)
				( pin "C8E10.2"
					( objectStatus "b" )
				)
			)
			( gate "C8E14"
				( objectStatus "@baseboard_fab2_lib.baseboard_fab2(sch_1):page240_i139" )
				( pin "C8E14.1"
					( objectStatus "a" )
				)
				( pin "C8E14.2"
					( objectStatus "b" )
				)
			)
			( gate "R8E38"
				( objectStatus "@baseboard_fab2_lib.baseboard_fab2(sch_1):page240_i140" )
				( pin "R8E38.1"
					( objectStatus "a" )
				)
				( pin "R8E38.2"
					( objectStatus "b" )
				)
			)
			( gate "R8E34"
				( objectStatus "@baseboard_fab2_lib.baseboard_fab2(sch_1):page240_i142" )
				( pin "R8E34.1"
					( objectStatus "a" )
				)
				( pin "R8E34.2"
					( objectStatus "b" )
				)
			)
			( gate "R8E31"
				( objectStatus "@baseboard_fab2_lib.baseboard_fab2(sch_1):page240_i143" )
				( pin "R8E31.1"
					( objectStatus "a" )
				)
				( pin "R8E31.2"
					( objectStatus "b" )
				)
			)
			( gate "R8E25"
				( objectStatus "@baseboard_fab2_lib.baseboard_fab2(sch_1):page240_i144" )
				( pin "R8E25.1"
					( objectStatus "a" )
				)
				( pin "R8E25.2"
					( objectStatus "b" )
				)
			)
			( gate "R8F11"
				( objectStatus "@baseboard_fab2_lib.baseboard_fab2(sch_1):page240_i146" )
				( pin "R8F11.1"
					( objectStatus "a" )
				)
				( pin "R8F11.2"
					( objectStatus "b" )
				)
			)
			( gate "R8F3"
				( objectStatus "@baseboard_fab2_lib.baseboard_fab2(sch_1):page240_i148" )
				( pin "R8F3.1"
					( objectStatus "a" )
				)
				( pin "R8F3.2"
					( objectStatus "b" )
				)
			)
			( gate "R2T4"
				( objectStatus "@baseboard_fab2_lib.baseboard_fab2(sch_1):page240_i152" )
				( pin "R2T4.1"
					( objectStatus "a" )
				)
				( pin "R2T4.2"
					( objectStatus "b" )
				)
			)
			( gate "C8F14"
				( objectStatus "@baseboard_fab2_lib.baseboard_fab2(sch_1):page240_i154" )
				( pin "C8F14.1"
					( objectStatus "a" )
				)
				( pin "C8F14.2"
					( objectStatus "b" )
				)
			)
			( gate "C8F8"
				( objectStatus "@baseboard_fab2_lib.baseboard_fab2(sch_1):page240_i155" )
				( pin "C8F8.1"
					( objectStatus "a" )
				)
				( pin "C8F8.2"
					( objectStatus "b" )
				)
			)
			( gate "C2T7"
				( objectStatus "@baseboard_fab2_lib.baseboard_fab2(sch_1):page240_i158" )
				( pin "C2T7.1"
					( objectStatus "a" )
				)
				( pin "C2T7.2"
					( objectStatus "b" )
				)
			)
			( gate "C2T6"
				( objectStatus "@baseboard_fab2_lib.baseboard_fab2(sch_1):page240_i160" )
				( pin "C2T6.1"
					( objectStatus "a" )
				)
				( pin "C2T6.2"
					( objectStatus "b" )
				)
			)
			( gate "C8F3"
				( objectStatus "@baseboard_fab2_lib.baseboard_fab2(sch_1):page240_i163" )
				( pin "C8F3.1"
					( objectStatus "a" )
				)
				( pin "C8F3.2"
					( objectStatus "b" )
				)
			)
			( gate "EU8E1"
				( objectStatus "@baseboard_fab2_lib.baseboard_fab2(sch_1):page240_i170" )
				( pin "EU8E1.4"
					( objectStatus "bg" )
				)
				( pin "EU8E1.3"
					( objectStatus "pgnd" )
				)
				( pin "EU8E1.1"
					( objectStatus "tg" )
				)
				( pin "EU8E1.2"
					( objectStatus "vin" )
				)
				( pin "EU8E1.5"
					( objectStatus "vsw" )
				)
			)
			( gate "R8F10"
				( objectStatus "@baseboard_fab2_lib.baseboard_fab2(sch_1):page240_i171" )
				( pin "R8F10.1"
					( objectStatus "a" )
				)
				( pin "R8F10.2"
					( objectStatus "b" )
				)
			)
			( gate "L8F1"
				( objectStatus "@baseboard_fab2_lib.baseboard_fab2(sch_1):page240_i173" )
				( pin "L8F1.1"
					( objectStatus "ina" )
				)
				( pin "L8F1.2"
					( objectStatus "inb" )
				)
			)
			( gate "C2T9"
				( objectStatus "@baseboard_fab2_lib.baseboard_fab2(sch_1):page240_i174" )
				( pin "C2T9.1"
					( objectStatus "a" )
				)
				( pin "C2T9.2"
					( objectStatus "b" )
				)
			)
			( gate "R8F2"
				( objectStatus "@baseboard_fab2_lib.baseboard_fab2(sch_1):page240_i176" )
				( pin "R8F2.1"
					( objectStatus "a" )
				)
				( pin "R8F2.2"
					( objectStatus "b" )
				)
			)
			( gate "R8E40"
				( objectStatus "@baseboard_fab2_lib.baseboard_fab2(sch_1):page240_i177" )
				( pin "R8E40.1"
					( objectStatus "a" )
				)
				( pin "R8E40.2"
					( objectStatus "b" )
				)
			)
			( gate "C8E9"
				( objectStatus "@baseboard_fab2_lib.baseboard_fab2(sch_1):page241_i2" )
				( pin "C8E9.1"
					( objectStatus "a" )
				)
				( pin "C8E9.2"
					( objectStatus "b" )
				)
			)
			( gate "C8E7"
				( objectStatus "@baseboard_fab2_lib.baseboard_fab2(sch_1):page241_i3" )
				( pin "C8E7.1"
					( objectStatus "a" )
				)
				( pin "C8E7.2"
					( objectStatus "b" )
				)
			)
			( gate "C8E4"
				( objectStatus "@baseboard_fab2_lib.baseboard_fab2(sch_1):page241_i8" )
				( pin "C8E4.1"
					( objectStatus "a" )
				)
				( pin "C8E4.2"
					( objectStatus "b" )
				)
			)
			( gate "R8E18"
				( objectStatus "@baseboard_fab2_lib.baseboard_fab2(sch_1):page241_i9" )
				( pin "R8E18.1"
					( objectStatus "a" )
				)
				( pin "R8E18.2"
					( objectStatus "b" )
				)
			)
			( gate "R7E12"
				( objectStatus "@baseboard_fab2_lib.baseboard_fab2(sch_1):page241_i11" )
				( pin "R7E12.1"
					( objectStatus "a" )
				)
				( pin "R7E12.2"
					( objectStatus "b" )
				)
			)
			( gate "C8E6"
				( objectStatus "@baseboard_fab2_lib.baseboard_fab2(sch_1):page241_i12" )
				( pin "C8E6.1"
					( objectStatus "a" )
				)
				( pin "C8E6.2"
					( objectStatus "b" )
				)
			)
			( gate "C7E10"
				( objectStatus "@baseboard_fab2_lib.baseboard_fab2(sch_1):page241_i14" )
				( pin "C7E10.1"
					( objectStatus "a" )
				)
				( pin "C7E10.2"
					( objectStatus "b" )
				)
			)
			( gate "R7E14"
				( objectStatus "@baseboard_fab2_lib.baseboard_fab2(sch_1):page241_i18" )
				( pin "R7E14.1"
					( objectStatus "a" )
				)
				( pin "R7E14.2"
					( objectStatus "b" )
				)
			)
			( gate "C7E14"
				( objectStatus "@baseboard_fab2_lib.baseboard_fab2(sch_1):page241_i30" )
				( pin "C7E14.1"
					( objectStatus "a" )
				)
				( pin "C7E14.2"
					( objectStatus "b" )
				)
			)
			( gate "R7E17"
				( objectStatus "@baseboard_fab2_lib.baseboard_fab2(sch_1):page241_i37" )
				( pin "R7E17.1"
					( objectStatus "a" )
				)
				( pin "R7E17.2"
					( objectStatus "b" )
				)
			)
			( gate "C7E11"
				( objectStatus "@baseboard_fab2_lib.baseboard_fab2(sch_1):page241_i39" )
				( pin "C7E11.1"
					( objectStatus "a" )
				)
				( pin "C7E11.2"
					( objectStatus "b" )
				)
			)
			( gate "C8E13"
				( objectStatus "@baseboard_fab2_lib.baseboard_fab2(sch_1):page241_i41" )
				( pin "C8E13.1"
					( objectStatus "a" )
				)
				( pin "C8E13.2"
					( objectStatus "b" )
				)
			)
			( gate "C7E13"
				( objectStatus "@baseboard_fab2_lib.baseboard_fab2(sch_1):page241_i45" )
				( pin "C7E13.1"
					( objectStatus "a" )
				)
				( pin "C7E13.2"
					( objectStatus "b" )
				)
			)
			( gate "C7E12"
				( objectStatus "@baseboard_fab2_lib.baseboard_fab2(sch_1):page241_i47" )
				( pin "C7E12.1"
					( objectStatus "a" )
				)
				( pin "C7E12.2"
					( objectStatus "b" )
				)
			)
			( gate "R7F1"
				( objectStatus "@baseboard_fab2_lib.baseboard_fab2(sch_1):page241_i50" )
				( pin "R7F1.1"
					( objectStatus "a" )
				)
				( pin "R7F1.2"
					( objectStatus "b" )
				)
			)
			( gate "R7E16"
				( objectStatus "@baseboard_fab2_lib.baseboard_fab2(sch_1):page241_i51" )
				( pin "R7E16.1"
					( objectStatus "a" )
				)
				( pin "R7E16.2"
					( objectStatus "b" )
				)
			)
			( gate "C8E16"
				( objectStatus "@baseboard_fab2_lib.baseboard_fab2(sch_1):page241_i53" )
				( pin "C8E16.1"
					( objectStatus "a" )
				)
				( pin "C8E16.2"
					( objectStatus "b" )
				)
			)
			( gate "R8E39"
				( objectStatus "@baseboard_fab2_lib.baseboard_fab2(sch_1):page241_i54" )
				( pin "R8E39.1"
					( objectStatus "a" )
				)
				( pin "R8E39.2"
					( objectStatus "b" )
				)
			)
			( gate "C8F1"
				( objectStatus "@baseboard_fab2_lib.baseboard_fab2(sch_1):page241_i57" )
				( pin "C8F1.1"
					( objectStatus "a" )
				)
				( pin "C8F1.2"
					( objectStatus "b" )
				)
			)
			( gate "R7E13"
				( objectStatus "@baseboard_fab2_lib.baseboard_fab2(sch_1):page241_i58" )
				( pin "R7E13.1"
					( objectStatus "a" )
				)
				( pin "R7E13.2"
					( objectStatus "b" )
				)
			)
			( gate "C8E15"
				( objectStatus "@baseboard_fab2_lib.baseboard_fab2(sch_1):page241_i63" )
				( pin "C8E15.1"
					( objectStatus "a" )
				)
				( pin "C8E15.2"
					( objectStatus "b" )
				)
			)
			( gate "R8E37"
				( objectStatus "@baseboard_fab2_lib.baseboard_fab2(sch_1):page241_i78" )
				( pin "R8E37.1"
					( objectStatus "a" )
				)
				( pin "R8E37.2"
					( objectStatus "b" )
				)
			)
			( gate "FB7E1"
				( objectStatus "@baseboard_fab2_lib.baseboard_fab2(sch_1):page241_i82" )
				( pin "FB7E1.1"
					( objectStatus "a" )
				)
				( pin "FB7E1.2"
					( objectStatus "b" )
				)
			)
			( gate "EU7E2"
				( objectStatus "@baseboard_fab2_lib.baseboard_fab2(sch_1):page241_i83" )
				( pin "EU7E2.13"
					( objectStatus "boot" )
				)
				( pin "EU7E2.8"
					( objectStatus "comp" )
				)
				( pin "EU7E2.10"
					( objectStatus "en" )
				)
				( pin "EU7E2.2"
					( objectStatus "gnd(0)" )
				)
				( pin "EU7E2.3"
					( objectStatus "gnd(1)" )
				)
				( pin "EU7E2.11"
					( objectStatus "ph(0)" )
				)
				( pin "EU7E2.12"
					( objectStatus "ph(1)" )
				)
				( pin "EU7E2.4"
					( objectStatus "pvin(0)" )
				)
				( pin "EU7E2.5"
					( objectStatus "pvin(1)" )
				)
				( pin "EU7E2.14"
					( objectStatus "pwrgd" )
				)
				( pin "EU7E2.1"
					( objectStatus "rt_clk" )
				)
				( pin "EU7E2.9"
					( objectStatus "ss_tr" )
				)
				( pin "EU7E2.15"
					( objectStatus "thpad" )
				)
				( pin "EU7E2.6"
					( objectStatus "vin" )
				)
				( pin "EU7E2.7"
					( objectStatus "vsense" )
				)
			)
			( gate "R7E15"
				( objectStatus "@baseboard_fab2_lib.baseboard_fab2(sch_1):page241_i89" )
				( pin "R7E15.1"
					( objectStatus "a" )
				)
				( pin "R7E15.2"
					( objectStatus "b" )
				)
			)
			( gate "L8E1"
				( objectStatus "@baseboard_fab2_lib.baseboard_fab2(sch_1):page241_i90" )
				( pin "L8E1.1"
					( objectStatus "ina" )
				)
				( pin "L8E1.2"
					( objectStatus "inb" )
				)
			)
			( gate "R8E33"
				( objectStatus "@baseboard_fab2_lib.baseboard_fab2(sch_1):page241_i91" )
				( pin "R8E33.1"
					( objectStatus "a" )
				)
				( pin "R8E33.2"
					( objectStatus "b" )
				)
			)
			( gate "J5"
				( objectStatus "@baseboard_fab2_lib.baseboard_fab2(sch_1):page199_i124" )
				( pin "J5.1"
					( objectStatus "io1" )
				)
				( pin "J5.2"
					( objectStatus "io2" )
				)
				( pin "J5.3"
					( objectStatus "io3" )
				)
			)
			( gate "R176"
				( objectStatus "@baseboard_fab2_lib.baseboard_fab2(sch_1):page169_i164" )
				( pin "R176.1"
					( objectStatus "a" )
				)
				( pin "R176.2"
					( objectStatus "b" )
				)
			)
			( gate "R175"
				( objectStatus "@baseboard_fab2_lib.baseboard_fab2(sch_1):page191_i193" )
				( pin "R175.1"
					( objectStatus "a" )
				)
				( pin "R175.2"
					( objectStatus "b" )
				)
			)
			( pin "U1L1.12"
				( objectStatus "@baseboard_fab2_lib.baseboard_fab2(sch_1):page112_i108(0):a(0)" )
			)
			( pin "U1L1.9"
				( objectStatus "@baseboard_fab2_lib.baseboard_fab2(sch_1):page112_i108(1):a(1)" )
			)
			( pin "U1L1.5"
				( objectStatus "@baseboard_fab2_lib.baseboard_fab2(sch_1):page112_i108(2):a(2)" )
			)
			( pin "U1L1.2"
				( objectStatus "@baseboard_fab2_lib.baseboard_fab2(sch_1):page112_i108(3):a(3)" )
			)
			( pin "U1L1.11"
				( objectStatus "@baseboard_fab2_lib.baseboard_fab2(sch_1):page112_i108(0):b(0)" )
			)
			( pin "U1L1.8"
				( objectStatus "@baseboard_fab2_lib.baseboard_fab2(sch_1):page112_i108(1):b(1)" )
			)
			( pin "U1L1.6"
				( objectStatus "@baseboard_fab2_lib.baseboard_fab2(sch_1):page112_i108(2):b(2)" )
			)
			( pin "U1L1.3"
				( objectStatus "@baseboard_fab2_lib.baseboard_fab2(sch_1):page112_i108(3):b(3)" )
			)
			( pin "U1L1.13"
				( objectStatus "@baseboard_fab2_lib.baseboard_fab2(sch_1):page112_i108(0):oe(0)" )
			)
			( pin "U1L1.10"
				( objectStatus "@baseboard_fab2_lib.baseboard_fab2(sch_1):page112_i108(1):oe(1)" )
			)
			( pin "U1L1.4"
				( objectStatus "@baseboard_fab2_lib.baseboard_fab2(sch_1):page112_i108(2):oe(2)" )
			)
			( pin "U1L1.1"
				( objectStatus "@baseboard_fab2_lib.baseboard_fab2(sch_1):page112_i108(3):oe(3)" )
			)
			( pin "U1L5.12"
				( objectStatus "@baseboard_fab2_lib.baseboard_fab2(sch_1):page112_i109(0):a(0)" )
			)
			( pin "U1L5.9"
				( objectStatus "@baseboard_fab2_lib.baseboard_fab2(sch_1):page112_i109(1):a(1)" )
			)
			( pin "U1L5.5"
				( objectStatus "@baseboard_fab2_lib.baseboard_fab2(sch_1):page112_i109(2):a(2)" )
			)
			( pin "U1L5.2"
				( objectStatus "@baseboard_fab2_lib.baseboard_fab2(sch_1):page112_i109(3):a(3)" )
			)
			( pin "U1L5.11"
				( objectStatus "@baseboard_fab2_lib.baseboard_fab2(sch_1):page112_i109(0):b(0)" )
			)
			( pin "U1L5.8"
				( objectStatus "@baseboard_fab2_lib.baseboard_fab2(sch_1):page112_i109(1):b(1)" )
			)
			( pin "U1L5.6"
				( objectStatus "@baseboard_fab2_lib.baseboard_fab2(sch_1):page112_i109(2):b(2)" )
			)
			( pin "U1L5.3"
				( objectStatus "@baseboard_fab2_lib.baseboard_fab2(sch_1):page112_i109(3):b(3)" )
			)
			( pin "U1L5.13"
				( objectStatus "@baseboard_fab2_lib.baseboard_fab2(sch_1):page112_i109(0):oe(0)" )
			)
			( pin "U1L5.10"
				( objectStatus "@baseboard_fab2_lib.baseboard_fab2(sch_1):page112_i109(1):oe(1)" )
			)
			( pin "U1L5.4"
				( objectStatus "@baseboard_fab2_lib.baseboard_fab2(sch_1):page112_i109(2):oe(2)" )
			)
			( pin "U1L5.1"
				( objectStatus "@baseboard_fab2_lib.baseboard_fab2(sch_1):page112_i109(3):oe(3)" )
			)
			( bus "M_A_BA"
				( memberType ( signal ) )
				( member ( signalRef "M_A_BA<0>") )
				( member ( signalRef "M_A_BA<1>") )
				( objectStatus "@baseboard_fab2_lib.baseboard_fab2(sch_1):m_a_ba" )
			)
			( bus "M_A_BG"
				( memberType ( signal ) )
				( member ( signalRef "M_A_BG<0>") )
				( member ( signalRef "M_A_BG<1>") )
				( objectStatus "@baseboard_fab2_lib.baseboard_fab2(sch_1):m_a_bg" )
			)
			( bus "M_A_C"
				( memberType ( signal ) )
				( member ( signalRef "M_A_C<2>") )
				( objectStatus "@baseboard_fab2_lib.baseboard_fab2(sch_1):m_a_c" )
			)
			( bus "M_A_CKE"
				( memberType ( signal ) )
				( member ( signalRef "M_A_CKE<0>") )
				( member ( signalRef "M_A_CKE<1>") )
				( member ( signalRef "M_A_CKE<2>") )
				( member ( signalRef "M_A_CKE<3>") )
				( objectStatus "@baseboard_fab2_lib.baseboard_fab2(sch_1):m_a_cke" )
			)
			( bus "M_A_CLK_DN"
				( memberType ( signal ) )
				( member ( signalRef "M_A_CLK_DN<0>") )
				( member ( signalRef "M_A_CLK_DN<1>") )
				( member ( signalRef "M_A_CLK_DN<2>") )
				( member ( signalRef "M_A_CLK_DN<3>") )
				( objectStatus "@baseboard_fab2_lib.baseboard_fab2(sch_1):m_a_clk_dn" )
			)
			( bus "M_A_CLK_DP"
				( memberType ( signal ) )
				( member ( signalRef "M_A_CLK_DP<0>") )
				( member ( signalRef "M_A_CLK_DP<1>") )
				( member ( signalRef "M_A_CLK_DP<2>") )
				( member ( signalRef "M_A_CLK_DP<3>") )
				( objectStatus "@baseboard_fab2_lib.baseboard_fab2(sch_1):m_a_clk_dp" )
			)
			( bus "M_A_CS_N"
				( memberType ( signal ) )
				( member ( signalRef "M_A_CS_N<0>") )
				( member ( signalRef "M_A_CS_N<1>") )
				( member ( signalRef "M_A_CS_N<2>") )
				( member ( signalRef "M_A_CS_N<3>") )
				( member ( signalRef "M_A_CS_N<4>") )
				( member ( signalRef "M_A_CS_N<5>") )
				( member ( signalRef "M_A_CS_N<6>") )
				( member ( signalRef "M_A_CS_N<7>") )
				( objectStatus "@baseboard_fab2_lib.baseboard_fab2(sch_1):m_a_cs_n" )
			)
			( bus "M_A_DQ"
				( memberType ( signal ) )
				( member ( signalRef "M_A_DQ<0>") )
				( member ( signalRef "M_A_DQ<1>") )
				( member ( signalRef "M_A_DQ<2>") )
				( member ( signalRef "M_A_DQ<3>") )
				( member ( signalRef "M_A_DQ<4>") )
				( member ( signalRef "M_A_DQ<5>") )
				( member ( signalRef "M_A_DQ<6>") )
				( member ( signalRef "M_A_DQ<7>") )
				( member ( signalRef "M_A_DQ<8>") )
				( member ( signalRef "M_A_DQ<9>") )
				( member ( signalRef "M_A_DQ<10>") )
				( member ( signalRef "M_A_DQ<11>") )
				( member ( signalRef "M_A_DQ<12>") )
				( member ( signalRef "M_A_DQ<13>") )
				( member ( signalRef "M_A_DQ<14>") )
				( member ( signalRef "M_A_DQ<15>") )
				( member ( signalRef "M_A_DQ<16>") )
				( member ( signalRef "M_A_DQ<17>") )
				( member ( signalRef "M_A_DQ<18>") )
				( member ( signalRef "M_A_DQ<19>") )
				( member ( signalRef "M_A_DQ<20>") )
				( member ( signalRef "M_A_DQ<21>") )
				( member ( signalRef "M_A_DQ<22>") )
				( member ( signalRef "M_A_DQ<23>") )
				( member ( signalRef "M_A_DQ<24>") )
				( member ( signalRef "M_A_DQ<25>") )
				( member ( signalRef "M_A_DQ<26>") )
				( member ( signalRef "M_A_DQ<27>") )
				( member ( signalRef "M_A_DQ<28>") )
				( member ( signalRef "M_A_DQ<29>") )
				( member ( signalRef "M_A_DQ<30>") )
				( member ( signalRef "M_A_DQ<31>") )
				( member ( signalRef "M_A_DQ<32>") )
				( member ( signalRef "M_A_DQ<33>") )
				( member ( signalRef "M_A_DQ<34>") )
				( member ( signalRef "M_A_DQ<35>") )
				( member ( signalRef "M_A_DQ<36>") )
				( member ( signalRef "M_A_DQ<37>") )
				( member ( signalRef "M_A_DQ<38>") )
				( member ( signalRef "M_A_DQ<39>") )
				( member ( signalRef "M_A_DQ<40>") )
				( member ( signalRef "M_A_DQ<41>") )
				( member ( signalRef "M_A_DQ<42>") )
				( member ( signalRef "M_A_DQ<43>") )
				( member ( signalRef "M_A_DQ<44>") )
				( member ( signalRef "M_A_DQ<45>") )
				( member ( signalRef "M_A_DQ<46>") )
				( member ( signalRef "M_A_DQ<47>") )
				( member ( signalRef "M_A_DQ<48>") )
				( member ( signalRef "M_A_DQ<49>") )
				( member ( signalRef "M_A_DQ<50>") )
				( member ( signalRef "M_A_DQ<51>") )
				( member ( signalRef "M_A_DQ<52>") )
				( member ( signalRef "M_A_DQ<53>") )
				( member ( signalRef "M_A_DQ<54>") )
				( member ( signalRef "M_A_DQ<55>") )
				( member ( signalRef "M_A_DQ<56>") )
				( member ( signalRef "M_A_DQ<57>") )
				( member ( signalRef "M_A_DQ<58>") )
				( member ( signalRef "M_A_DQ<59>") )
				( member ( signalRef "M_A_DQ<60>") )
				( member ( signalRef "M_A_DQ<61>") )
				( member ( signalRef "M_A_DQ<62>") )
				( member ( signalRef "M_A_DQ<63>") )
				( objectStatus "@baseboard_fab2_lib.baseboard_fab2(sch_1):m_a_dq" )
			)
			( bus "M_A_DQS_DN"
				( memberType ( signal ) )
				( member ( signalRef "M_A_DQS_DN<0>") )
				( member ( signalRef "M_A_DQS_DN<1>") )
				( member ( signalRef "M_A_DQS_DN<2>") )
				( member ( signalRef "M_A_DQS_DN<3>") )
				( member ( signalRef "M_A_DQS_DN<4>") )
				( member ( signalRef "M_A_DQS_DN<5>") )
				( member ( signalRef "M_A_DQS_DN<6>") )
				( member ( signalRef "M_A_DQS_DN<7>") )
				( member ( signalRef "M_A_DQS_DN<8>") )
				( member ( signalRef "M_A_DQS_DN<9>") )
				( member ( signalRef "M_A_DQS_DN<10>") )
				( member ( signalRef "M_A_DQS_DN<11>") )
				( member ( signalRef "M_A_DQS_DN<12>") )
				( member ( signalRef "M_A_DQS_DN<13>") )
				( member ( signalRef "M_A_DQS_DN<14>") )
				( member ( signalRef "M_A_DQS_DN<15>") )
				( member ( signalRef "M_A_DQS_DN<16>") )
				( member ( signalRef "M_A_DQS_DN<17>") )
				( objectStatus "@baseboard_fab2_lib.baseboard_fab2(sch_1):m_a_dqs_dn" )
			)
			( bus "M_A_DQS_DP"
				( memberType ( signal ) )
				( member ( signalRef "M_A_DQS_DP<0>") )
				( member ( signalRef "M_A_DQS_DP<1>") )
				( member ( signalRef "M_A_DQS_DP<2>") )
				( member ( signalRef "M_A_DQS_DP<3>") )
				( member ( signalRef "M_A_DQS_DP<4>") )
				( member ( signalRef "M_A_DQS_DP<5>") )
				( member ( signalRef "M_A_DQS_DP<6>") )
				( member ( signalRef "M_A_DQS_DP<7>") )
				( member ( signalRef "M_A_DQS_DP<8>") )
				( member ( signalRef "M_A_DQS_DP<9>") )
				( member ( signalRef "M_A_DQS_DP<10>") )
				( member ( signalRef "M_A_DQS_DP<11>") )
				( member ( signalRef "M_A_DQS_DP<12>") )
				( member ( signalRef "M_A_DQS_DP<13>") )
				( member ( signalRef "M_A_DQS_DP<14>") )
				( member ( signalRef "M_A_DQS_DP<15>") )
				( member ( signalRef "M_A_DQS_DP<16>") )
				( member ( signalRef "M_A_DQS_DP<17>") )
				( objectStatus "@baseboard_fab2_lib.baseboard_fab2(sch_1):m_a_dqs_dp" )
			)
			( bus "M_A_ECC"
				( memberType ( signal ) )
				( member ( signalRef "M_A_ECC<0>") )
				( member ( signalRef "M_A_ECC<1>") )
				( member ( signalRef "M_A_ECC<2>") )
				( member ( signalRef "M_A_ECC<3>") )
				( member ( signalRef "M_A_ECC<4>") )
				( member ( signalRef "M_A_ECC<5>") )
				( member ( signalRef "M_A_ECC<6>") )
				( member ( signalRef "M_A_ECC<7>") )
				( objectStatus "@baseboard_fab2_lib.baseboard_fab2(sch_1):m_a_ecc" )
			)
			( bus "M_A_MA"
				( memberType ( signal ) )
				( member ( signalRef "M_A_MA<0>") )
				( member ( signalRef "M_A_MA<1>") )
				( member ( signalRef "M_A_MA<2>") )
				( member ( signalRef "M_A_MA<3>") )
				( member ( signalRef "M_A_MA<4>") )
				( member ( signalRef "M_A_MA<5>") )
				( member ( signalRef "M_A_MA<6>") )
				( member ( signalRef "M_A_MA<7>") )
				( member ( signalRef "M_A_MA<8>") )
				( member ( signalRef "M_A_MA<9>") )
				( member ( signalRef "M_A_MA<10>") )
				( member ( signalRef "M_A_MA<11>") )
				( member ( signalRef "M_A_MA<12>") )
				( member ( signalRef "M_A_MA<13>") )
				( member ( signalRef "M_A_MA<14>") )
				( member ( signalRef "M_A_MA<15>") )
				( member ( signalRef "M_A_MA<16>") )
				( member ( signalRef "M_A_MA<17>") )
				( objectStatus "@baseboard_fab2_lib.baseboard_fab2(sch_1):m_a_ma" )
			)
			( bus "M_A_ODT"
				( memberType ( signal ) )
				( member ( signalRef "M_A_ODT<0>") )
				( member ( signalRef "M_A_ODT<1>") )
				( member ( signalRef "M_A_ODT<2>") )
				( member ( signalRef "M_A_ODT<3>") )
				( objectStatus "@baseboard_fab2_lib.baseboard_fab2(sch_1):m_a_odt" )
			)
			( bus "M_B_BA"
				( memberType ( signal ) )
				( member ( signalRef "M_B_BA<0>") )
				( member ( signalRef "M_B_BA<1>") )
				( objectStatus "@baseboard_fab2_lib.baseboard_fab2(sch_1):m_b_ba" )
			)
			( bus "M_B_BG"
				( memberType ( signal ) )
				( member ( signalRef "M_B_BG<0>") )
				( member ( signalRef "M_B_BG<1>") )
				( objectStatus "@baseboard_fab2_lib.baseboard_fab2(sch_1):m_b_bg" )
			)
			( bus "M_B_C"
				( memberType ( signal ) )
				( member ( signalRef "M_B_C<2>") )
				( objectStatus "@baseboard_fab2_lib.baseboard_fab2(sch_1):m_b_c" )
			)
			( bus "M_B_CKE"
				( memberType ( signal ) )
				( member ( signalRef "M_B_CKE<0>") )
				( member ( signalRef "M_B_CKE<1>") )
				( member ( signalRef "M_B_CKE<2>") )
				( member ( signalRef "M_B_CKE<3>") )
				( objectStatus "@baseboard_fab2_lib.baseboard_fab2(sch_1):m_b_cke" )
			)
			( bus "M_B_CLK_DN"
				( memberType ( signal ) )
				( member ( signalRef "M_B_CLK_DN<0>") )
				( member ( signalRef "M_B_CLK_DN<1>") )
				( member ( signalRef "M_B_CLK_DN<2>") )
				( member ( signalRef "M_B_CLK_DN<3>") )
				( objectStatus "@baseboard_fab2_lib.baseboard_fab2(sch_1):m_b_clk_dn" )
			)
			( bus "M_B_CLK_DP"
				( memberType ( signal ) )
				( member ( signalRef "M_B_CLK_DP<0>") )
				( member ( signalRef "M_B_CLK_DP<1>") )
				( member ( signalRef "M_B_CLK_DP<2>") )
				( member ( signalRef "M_B_CLK_DP<3>") )
				( objectStatus "@baseboard_fab2_lib.baseboard_fab2(sch_1):m_b_clk_dp" )
			)
			( bus "M_B_CS_N"
				( memberType ( signal ) )
				( member ( signalRef "M_B_CS_N<0>") )
				( member ( signalRef "M_B_CS_N<1>") )
				( member ( signalRef "M_B_CS_N<2>") )
				( member ( signalRef "M_B_CS_N<3>") )
				( member ( signalRef "M_B_CS_N<4>") )
				( member ( signalRef "M_B_CS_N<5>") )
				( member ( signalRef "M_B_CS_N<6>") )
				( member ( signalRef "M_B_CS_N<7>") )
				( objectStatus "@baseboard_fab2_lib.baseboard_fab2(sch_1):m_b_cs_n" )
			)
			( bus "M_B_DQ"
				( memberType ( signal ) )
				( member ( signalRef "M_B_DQ<0>") )
				( member ( signalRef "M_B_DQ<1>") )
				( member ( signalRef "M_B_DQ<2>") )
				( member ( signalRef "M_B_DQ<3>") )
				( member ( signalRef "M_B_DQ<4>") )
				( member ( signalRef "M_B_DQ<5>") )
				( member ( signalRef "M_B_DQ<6>") )
				( member ( signalRef "M_B_DQ<7>") )
				( member ( signalRef "M_B_DQ<8>") )
				( member ( signalRef "M_B_DQ<9>") )
				( member ( signalRef "M_B_DQ<10>") )
				( member ( signalRef "M_B_DQ<11>") )
				( member ( signalRef "M_B_DQ<12>") )
				( member ( signalRef "M_B_DQ<13>") )
				( member ( signalRef "M_B_DQ<14>") )
				( member ( signalRef "M_B_DQ<15>") )
				( member ( signalRef "M_B_DQ<16>") )
				( member ( signalRef "M_B_DQ<17>") )
				( member ( signalRef "M_B_DQ<18>") )
				( member ( signalRef "M_B_DQ<19>") )
				( member ( signalRef "M_B_DQ<20>") )
				( member ( signalRef "M_B_DQ<21>") )
				( member ( signalRef "M_B_DQ<22>") )
				( member ( signalRef "M_B_DQ<23>") )
				( member ( signalRef "M_B_DQ<24>") )
				( member ( signalRef "M_B_DQ<25>") )
				( member ( signalRef "M_B_DQ<26>") )
				( member ( signalRef "M_B_DQ<27>") )
				( member ( signalRef "M_B_DQ<28>") )
				( member ( signalRef "M_B_DQ<29>") )
				( member ( signalRef "M_B_DQ<30>") )
				( member ( signalRef "M_B_DQ<31>") )
				( member ( signalRef "M_B_DQ<32>") )
				( member ( signalRef "M_B_DQ<33>") )
				( member ( signalRef "M_B_DQ<34>") )
				( member ( signalRef "M_B_DQ<35>") )
				( member ( signalRef "M_B_DQ<36>") )
				( member ( signalRef "M_B_DQ<37>") )
				( member ( signalRef "M_B_DQ<38>") )
				( member ( signalRef "M_B_DQ<39>") )
				( member ( signalRef "M_B_DQ<40>") )
				( member ( signalRef "M_B_DQ<41>") )
				( member ( signalRef "M_B_DQ<42>") )
				( member ( signalRef "M_B_DQ<43>") )
				( member ( signalRef "M_B_DQ<44>") )
				( member ( signalRef "M_B_DQ<45>") )
				( member ( signalRef "M_B_DQ<46>") )
				( member ( signalRef "M_B_DQ<47>") )
				( member ( signalRef "M_B_DQ<48>") )
				( member ( signalRef "M_B_DQ<49>") )
				( member ( signalRef "M_B_DQ<50>") )
				( member ( signalRef "M_B_DQ<51>") )
				( member ( signalRef "M_B_DQ<52>") )
				( member ( signalRef "M_B_DQ<53>") )
				( member ( signalRef "M_B_DQ<54>") )
				( member ( signalRef "M_B_DQ<55>") )
				( member ( signalRef "M_B_DQ<56>") )
				( member ( signalRef "M_B_DQ<57>") )
				( member ( signalRef "M_B_DQ<58>") )
				( member ( signalRef "M_B_DQ<59>") )
				( member ( signalRef "M_B_DQ<60>") )
				( member ( signalRef "M_B_DQ<61>") )
				( member ( signalRef "M_B_DQ<62>") )
				( member ( signalRef "M_B_DQ<63>") )
				( objectStatus "@baseboard_fab2_lib.baseboard_fab2(sch_1):m_b_dq" )
			)
			( bus "M_B_DQS_DN"
				( memberType ( signal ) )
				( member ( signalRef "M_B_DQS_DN<0>") )
				( member ( signalRef "M_B_DQS_DN<1>") )
				( member ( signalRef "M_B_DQS_DN<2>") )
				( member ( signalRef "M_B_DQS_DN<3>") )
				( member ( signalRef "M_B_DQS_DN<4>") )
				( member ( signalRef "M_B_DQS_DN<5>") )
				( member ( signalRef "M_B_DQS_DN<6>") )
				( member ( signalRef "M_B_DQS_DN<7>") )
				( member ( signalRef "M_B_DQS_DN<8>") )
				( member ( signalRef "M_B_DQS_DN<9>") )
				( member ( signalRef "M_B_DQS_DN<10>") )
				( member ( signalRef "M_B_DQS_DN<11>") )
				( member ( signalRef "M_B_DQS_DN<12>") )
				( member ( signalRef "M_B_DQS_DN<13>") )
				( member ( signalRef "M_B_DQS_DN<14>") )
				( member ( signalRef "M_B_DQS_DN<15>") )
				( member ( signalRef "M_B_DQS_DN<16>") )
				( member ( signalRef "M_B_DQS_DN<17>") )
				( objectStatus "@baseboard_fab2_lib.baseboard_fab2(sch_1):m_b_dqs_dn" )
			)
			( bus "M_B_DQS_DP"
				( memberType ( signal ) )
				( member ( signalRef "M_B_DQS_DP<0>") )
				( member ( signalRef "M_B_DQS_DP<1>") )
				( member ( signalRef "M_B_DQS_DP<2>") )
				( member ( signalRef "M_B_DQS_DP<3>") )
				( member ( signalRef "M_B_DQS_DP<4>") )
				( member ( signalRef "M_B_DQS_DP<5>") )
				( member ( signalRef "M_B_DQS_DP<6>") )
				( member ( signalRef "M_B_DQS_DP<7>") )
				( member ( signalRef "M_B_DQS_DP<8>") )
				( member ( signalRef "M_B_DQS_DP<9>") )
				( member ( signalRef "M_B_DQS_DP<10>") )
				( member ( signalRef "M_B_DQS_DP<11>") )
				( member ( signalRef "M_B_DQS_DP<12>") )
				( member ( signalRef "M_B_DQS_DP<13>") )
				( member ( signalRef "M_B_DQS_DP<14>") )
				( member ( signalRef "M_B_DQS_DP<15>") )
				( member ( signalRef "M_B_DQS_DP<16>") )
				( member ( signalRef "M_B_DQS_DP<17>") )
				( objectStatus "@baseboard_fab2_lib.baseboard_fab2(sch_1):m_b_dqs_dp" )
			)
			( bus "M_B_ECC"
				( memberType ( signal ) )
				( member ( signalRef "M_B_ECC<0>") )
				( member ( signalRef "M_B_ECC<1>") )
				( member ( signalRef "M_B_ECC<2>") )
				( member ( signalRef "M_B_ECC<3>") )
				( member ( signalRef "M_B_ECC<4>") )
				( member ( signalRef "M_B_ECC<5>") )
				( member ( signalRef "M_B_ECC<6>") )
				( member ( signalRef "M_B_ECC<7>") )
				( objectStatus "@baseboard_fab2_lib.baseboard_fab2(sch_1):m_b_ecc" )
			)
			( bus "M_B_MA"
				( memberType ( signal ) )
				( member ( signalRef "M_B_MA<0>") )
				( member ( signalRef "M_B_MA<1>") )
				( member ( signalRef "M_B_MA<2>") )
				( member ( signalRef "M_B_MA<3>") )
				( member ( signalRef "M_B_MA<4>") )
				( member ( signalRef "M_B_MA<5>") )
				( member ( signalRef "M_B_MA<6>") )
				( member ( signalRef "M_B_MA<7>") )
				( member ( signalRef "M_B_MA<8>") )
				( member ( signalRef "M_B_MA<9>") )
				( member ( signalRef "M_B_MA<10>") )
				( member ( signalRef "M_B_MA<11>") )
				( member ( signalRef "M_B_MA<12>") )
				( member ( signalRef "M_B_MA<13>") )
				( member ( signalRef "M_B_MA<14>") )
				( member ( signalRef "M_B_MA<15>") )
				( member ( signalRef "M_B_MA<16>") )
				( member ( signalRef "M_B_MA<17>") )
				( objectStatus "@baseboard_fab2_lib.baseboard_fab2(sch_1):m_b_ma" )
			)
			( bus "M_B_ODT"
				( memberType ( signal ) )
				( member ( signalRef "M_B_ODT<0>") )
				( member ( signalRef "M_B_ODT<1>") )
				( member ( signalRef "M_B_ODT<2>") )
				( member ( signalRef "M_B_ODT<3>") )
				( objectStatus "@baseboard_fab2_lib.baseboard_fab2(sch_1):m_b_odt" )
			)
			( bus "M_C_BA"
				( memberType ( signal ) )
				( member ( signalRef "M_C_BA<0>") )
				( member ( signalRef "M_C_BA<1>") )
				( objectStatus "@baseboard_fab2_lib.baseboard_fab2(sch_1):m_c_ba" )
			)
			( bus "M_C_BG"
				( memberType ( signal ) )
				( member ( signalRef "M_C_BG<0>") )
				( member ( signalRef "M_C_BG<1>") )
				( objectStatus "@baseboard_fab2_lib.baseboard_fab2(sch_1):m_c_bg" )
			)
			( bus "M_C_C"
				( memberType ( signal ) )
				( member ( signalRef "M_C_C<2>") )
				( objectStatus "@baseboard_fab2_lib.baseboard_fab2(sch_1):m_c_c" )
			)
			( bus "M_C_CKE"
				( memberType ( signal ) )
				( member ( signalRef "M_C_CKE<0>") )
				( member ( signalRef "M_C_CKE<1>") )
				( member ( signalRef "M_C_CKE<2>") )
				( member ( signalRef "M_C_CKE<3>") )
				( objectStatus "@baseboard_fab2_lib.baseboard_fab2(sch_1):m_c_cke" )
			)
			( bus "M_C_CLK_DN"
				( memberType ( signal ) )
				( member ( signalRef "M_C_CLK_DN<0>") )
				( member ( signalRef "M_C_CLK_DN<1>") )
				( member ( signalRef "M_C_CLK_DN<2>") )
				( member ( signalRef "M_C_CLK_DN<3>") )
				( objectStatus "@baseboard_fab2_lib.baseboard_fab2(sch_1):m_c_clk_dn" )
			)
			( bus "M_C_CLK_DP"
				( memberType ( signal ) )
				( member ( signalRef "M_C_CLK_DP<0>") )
				( member ( signalRef "M_C_CLK_DP<1>") )
				( member ( signalRef "M_C_CLK_DP<2>") )
				( member ( signalRef "M_C_CLK_DP<3>") )
				( objectStatus "@baseboard_fab2_lib.baseboard_fab2(sch_1):m_c_clk_dp" )
			)
			( bus "M_C_CS_N"
				( memberType ( signal ) )
				( member ( signalRef "M_C_CS_N<0>") )
				( member ( signalRef "M_C_CS_N<1>") )
				( member ( signalRef "M_C_CS_N<2>") )
				( member ( signalRef "M_C_CS_N<3>") )
				( member ( signalRef "M_C_CS_N<4>") )
				( member ( signalRef "M_C_CS_N<5>") )
				( member ( signalRef "M_C_CS_N<6>") )
				( member ( signalRef "M_C_CS_N<7>") )
				( objectStatus "@baseboard_fab2_lib.baseboard_fab2(sch_1):m_c_cs_n" )
			)
			( bus "M_C_DQ"
				( memberType ( signal ) )
				( member ( signalRef "M_C_DQ<0>") )
				( member ( signalRef "M_C_DQ<1>") )
				( member ( signalRef "M_C_DQ<2>") )
				( member ( signalRef "M_C_DQ<3>") )
				( member ( signalRef "M_C_DQ<4>") )
				( member ( signalRef "M_C_DQ<5>") )
				( member ( signalRef "M_C_DQ<6>") )
				( member ( signalRef "M_C_DQ<7>") )
				( member ( signalRef "M_C_DQ<8>") )
				( member ( signalRef "M_C_DQ<9>") )
				( member ( signalRef "M_C_DQ<10>") )
				( member ( signalRef "M_C_DQ<11>") )
				( member ( signalRef "M_C_DQ<12>") )
				( member ( signalRef "M_C_DQ<13>") )
				( member ( signalRef "M_C_DQ<14>") )
				( member ( signalRef "M_C_DQ<15>") )
				( member ( signalRef "M_C_DQ<16>") )
				( member ( signalRef "M_C_DQ<17>") )
				( member ( signalRef "M_C_DQ<18>") )
				( member ( signalRef "M_C_DQ<19>") )
				( member ( signalRef "M_C_DQ<20>") )
				( member ( signalRef "M_C_DQ<21>") )
				( member ( signalRef "M_C_DQ<22>") )
				( member ( signalRef "M_C_DQ<23>") )
				( member ( signalRef "M_C_DQ<24>") )
				( member ( signalRef "M_C_DQ<25>") )
				( member ( signalRef "M_C_DQ<26>") )
				( member ( signalRef "M_C_DQ<27>") )
				( member ( signalRef "M_C_DQ<28>") )
				( member ( signalRef "M_C_DQ<29>") )
				( member ( signalRef "M_C_DQ<30>") )
				( member ( signalRef "M_C_DQ<31>") )
				( member ( signalRef "M_C_DQ<32>") )
				( member ( signalRef "M_C_DQ<33>") )
				( member ( signalRef "M_C_DQ<34>") )
				( member ( signalRef "M_C_DQ<35>") )
				( member ( signalRef "M_C_DQ<36>") )
				( member ( signalRef "M_C_DQ<37>") )
				( member ( signalRef "M_C_DQ<38>") )
				( member ( signalRef "M_C_DQ<39>") )
				( member ( signalRef "M_C_DQ<40>") )
				( member ( signalRef "M_C_DQ<41>") )
				( member ( signalRef "M_C_DQ<42>") )
				( member ( signalRef "M_C_DQ<43>") )
				( member ( signalRef "M_C_DQ<44>") )
				( member ( signalRef "M_C_DQ<45>") )
				( member ( signalRef "M_C_DQ<46>") )
				( member ( signalRef "M_C_DQ<47>") )
				( member ( signalRef "M_C_DQ<48>") )
				( member ( signalRef "M_C_DQ<49>") )
				( member ( signalRef "M_C_DQ<50>") )
				( member ( signalRef "M_C_DQ<51>") )
				( member ( signalRef "M_C_DQ<52>") )
				( member ( signalRef "M_C_DQ<53>") )
				( member ( signalRef "M_C_DQ<54>") )
				( member ( signalRef "M_C_DQ<55>") )
				( member ( signalRef "M_C_DQ<56>") )
				( member ( signalRef "M_C_DQ<57>") )
				( member ( signalRef "M_C_DQ<58>") )
				( member ( signalRef "M_C_DQ<59>") )
				( member ( signalRef "M_C_DQ<60>") )
				( member ( signalRef "M_C_DQ<61>") )
				( member ( signalRef "M_C_DQ<62>") )
				( member ( signalRef "M_C_DQ<63>") )
				( objectStatus "@baseboard_fab2_lib.baseboard_fab2(sch_1):m_c_dq" )
			)
			( bus "M_C_DQS_DN"
				( memberType ( signal ) )
				( member ( signalRef "M_C_DQS_DN<0>") )
				( member ( signalRef "M_C_DQS_DN<1>") )
				( member ( signalRef "M_C_DQS_DN<2>") )
				( member ( signalRef "M_C_DQS_DN<3>") )
				( member ( signalRef "M_C_DQS_DN<4>") )
				( member ( signalRef "M_C_DQS_DN<5>") )
				( member ( signalRef "M_C_DQS_DN<6>") )
				( member ( signalRef "M_C_DQS_DN<7>") )
				( member ( signalRef "M_C_DQS_DN<8>") )
				( member ( signalRef "M_C_DQS_DN<9>") )
				( member ( signalRef "M_C_DQS_DN<10>") )
				( member ( signalRef "M_C_DQS_DN<11>") )
				( member ( signalRef "M_C_DQS_DN<12>") )
				( member ( signalRef "M_C_DQS_DN<13>") )
				( member ( signalRef "M_C_DQS_DN<14>") )
				( member ( signalRef "M_C_DQS_DN<15>") )
				( member ( signalRef "M_C_DQS_DN<16>") )
				( member ( signalRef "M_C_DQS_DN<17>") )
				( objectStatus "@baseboard_fab2_lib.baseboard_fab2(sch_1):m_c_dqs_dn" )
			)
			( bus "M_C_DQS_DP"
				( memberType ( signal ) )
				( member ( signalRef "M_C_DQS_DP<0>") )
				( member ( signalRef "M_C_DQS_DP<1>") )
				( member ( signalRef "M_C_DQS_DP<2>") )
				( member ( signalRef "M_C_DQS_DP<3>") )
				( member ( signalRef "M_C_DQS_DP<4>") )
				( member ( signalRef "M_C_DQS_DP<5>") )
				( member ( signalRef "M_C_DQS_DP<6>") )
				( member ( signalRef "M_C_DQS_DP<7>") )
				( member ( signalRef "M_C_DQS_DP<8>") )
				( member ( signalRef "M_C_DQS_DP<9>") )
				( member ( signalRef "M_C_DQS_DP<10>") )
				( member ( signalRef "M_C_DQS_DP<11>") )
				( member ( signalRef "M_C_DQS_DP<12>") )
				( member ( signalRef "M_C_DQS_DP<13>") )
				( member ( signalRef "M_C_DQS_DP<14>") )
				( member ( signalRef "M_C_DQS_DP<15>") )
				( member ( signalRef "M_C_DQS_DP<16>") )
				( member ( signalRef "M_C_DQS_DP<17>") )
				( objectStatus "@baseboard_fab2_lib.baseboard_fab2(sch_1):m_c_dqs_dp" )
			)
			( bus "M_C_ECC"
				( memberType ( signal ) )
				( member ( signalRef "M_C_ECC<0>") )
				( member ( signalRef "M_C_ECC<1>") )
				( member ( signalRef "M_C_ECC<2>") )
				( member ( signalRef "M_C_ECC<3>") )
				( member ( signalRef "M_C_ECC<4>") )
				( member ( signalRef "M_C_ECC<5>") )
				( member ( signalRef "M_C_ECC<6>") )
				( member ( signalRef "M_C_ECC<7>") )
				( objectStatus "@baseboard_fab2_lib.baseboard_fab2(sch_1):m_c_ecc" )
			)
			( bus "M_C_MA"
				( memberType ( signal ) )
				( member ( signalRef "M_C_MA<0>") )
				( member ( signalRef "M_C_MA<1>") )
				( member ( signalRef "M_C_MA<2>") )
				( member ( signalRef "M_C_MA<3>") )
				( member ( signalRef "M_C_MA<4>") )
				( member ( signalRef "M_C_MA<5>") )
				( member ( signalRef "M_C_MA<6>") )
				( member ( signalRef "M_C_MA<7>") )
				( member ( signalRef "M_C_MA<8>") )
				( member ( signalRef "M_C_MA<9>") )
				( member ( signalRef "M_C_MA<10>") )
				( member ( signalRef "M_C_MA<11>") )
				( member ( signalRef "M_C_MA<12>") )
				( member ( signalRef "M_C_MA<13>") )
				( member ( signalRef "M_C_MA<14>") )
				( member ( signalRef "M_C_MA<15>") )
				( member ( signalRef "M_C_MA<16>") )
				( member ( signalRef "M_C_MA<17>") )
				( objectStatus "@baseboard_fab2_lib.baseboard_fab2(sch_1):m_c_ma" )
			)
			( bus "M_C_ODT"
				( memberType ( signal ) )
				( member ( signalRef "M_C_ODT<0>") )
				( member ( signalRef "M_C_ODT<1>") )
				( member ( signalRef "M_C_ODT<2>") )
				( member ( signalRef "M_C_ODT<3>") )
				( objectStatus "@baseboard_fab2_lib.baseboard_fab2(sch_1):m_c_odt" )
			)
			( bus "M_D_BA"
				( memberType ( signal ) )
				( member ( signalRef "M_D_BA<0>") )
				( member ( signalRef "M_D_BA<1>") )
				( objectStatus "@baseboard_fab2_lib.baseboard_fab2(sch_1):m_d_ba" )
			)
			( bus "M_D_BG"
				( memberType ( signal ) )
				( member ( signalRef "M_D_BG<0>") )
				( member ( signalRef "M_D_BG<1>") )
				( objectStatus "@baseboard_fab2_lib.baseboard_fab2(sch_1):m_d_bg" )
			)
			( bus "M_D_C"
				( memberType ( signal ) )
				( member ( signalRef "M_D_C<2>") )
				( objectStatus "@baseboard_fab2_lib.baseboard_fab2(sch_1):m_d_c" )
			)
			( bus "M_D_CKE"
				( memberType ( signal ) )
				( member ( signalRef "M_D_CKE<0>") )
				( member ( signalRef "M_D_CKE<1>") )
				( member ( signalRef "M_D_CKE<2>") )
				( member ( signalRef "M_D_CKE<3>") )
				( objectStatus "@baseboard_fab2_lib.baseboard_fab2(sch_1):m_d_cke" )
			)
			( bus "M_D_CLK_DN"
				( memberType ( signal ) )
				( member ( signalRef "M_D_CLK_DN<0>") )
				( member ( signalRef "M_D_CLK_DN<1>") )
				( member ( signalRef "M_D_CLK_DN<2>") )
				( member ( signalRef "M_D_CLK_DN<3>") )
				( objectStatus "@baseboard_fab2_lib.baseboard_fab2(sch_1):m_d_clk_dn" )
			)
			( bus "M_D_CLK_DP"
				( memberType ( signal ) )
				( member ( signalRef "M_D_CLK_DP<0>") )
				( member ( signalRef "M_D_CLK_DP<1>") )
				( member ( signalRef "M_D_CLK_DP<2>") )
				( member ( signalRef "M_D_CLK_DP<3>") )
				( objectStatus "@baseboard_fab2_lib.baseboard_fab2(sch_1):m_d_clk_dp" )
			)
			( bus "M_D_CS_N"
				( memberType ( signal ) )
				( member ( signalRef "M_D_CS_N<0>") )
				( member ( signalRef "M_D_CS_N<1>") )
				( member ( signalRef "M_D_CS_N<2>") )
				( member ( signalRef "M_D_CS_N<3>") )
				( member ( signalRef "M_D_CS_N<4>") )
				( member ( signalRef "M_D_CS_N<5>") )
				( member ( signalRef "M_D_CS_N<6>") )
				( member ( signalRef "M_D_CS_N<7>") )
				( objectStatus "@baseboard_fab2_lib.baseboard_fab2(sch_1):m_d_cs_n" )
			)
			( bus "M_D_DQ"
				( memberType ( signal ) )
				( member ( signalRef "M_D_DQ<0>") )
				( member ( signalRef "M_D_DQ<1>") )
				( member ( signalRef "M_D_DQ<2>") )
				( member ( signalRef "M_D_DQ<3>") )
				( member ( signalRef "M_D_DQ<4>") )
				( member ( signalRef "M_D_DQ<5>") )
				( member ( signalRef "M_D_DQ<6>") )
				( member ( signalRef "M_D_DQ<7>") )
				( member ( signalRef "M_D_DQ<8>") )
				( member ( signalRef "M_D_DQ<9>") )
				( member ( signalRef "M_D_DQ<10>") )
				( member ( signalRef "M_D_DQ<11>") )
				( member ( signalRef "M_D_DQ<12>") )
				( member ( signalRef "M_D_DQ<13>") )
				( member ( signalRef "M_D_DQ<14>") )
				( member ( signalRef "M_D_DQ<15>") )
				( member ( signalRef "M_D_DQ<16>") )
				( member ( signalRef "M_D_DQ<17>") )
				( member ( signalRef "M_D_DQ<18>") )
				( member ( signalRef "M_D_DQ<19>") )
				( member ( signalRef "M_D_DQ<20>") )
				( member ( signalRef "M_D_DQ<21>") )
				( member ( signalRef "M_D_DQ<22>") )
				( member ( signalRef "M_D_DQ<23>") )
				( member ( signalRef "M_D_DQ<24>") )
				( member ( signalRef "M_D_DQ<25>") )
				( member ( signalRef "M_D_DQ<26>") )
				( member ( signalRef "M_D_DQ<27>") )
				( member ( signalRef "M_D_DQ<28>") )
				( member ( signalRef "M_D_DQ<29>") )
				( member ( signalRef "M_D_DQ<30>") )
				( member ( signalRef "M_D_DQ<31>") )
				( member ( signalRef "M_D_DQ<32>") )
				( member ( signalRef "M_D_DQ<33>") )
				( member ( signalRef "M_D_DQ<34>") )
				( member ( signalRef "M_D_DQ<35>") )
				( member ( signalRef "M_D_DQ<36>") )
				( member ( signalRef "M_D_DQ<37>") )
				( member ( signalRef "M_D_DQ<38>") )
				( member ( signalRef "M_D_DQ<39>") )
				( member ( signalRef "M_D_DQ<40>") )
				( member ( signalRef "M_D_DQ<41>") )
				( member ( signalRef "M_D_DQ<42>") )
				( member ( signalRef "M_D_DQ<43>") )
				( member ( signalRef "M_D_DQ<44>") )
				( member ( signalRef "M_D_DQ<45>") )
				( member ( signalRef "M_D_DQ<46>") )
				( member ( signalRef "M_D_DQ<47>") )
				( member ( signalRef "M_D_DQ<48>") )
				( member ( signalRef "M_D_DQ<49>") )
				( member ( signalRef "M_D_DQ<50>") )
				( member ( signalRef "M_D_DQ<51>") )
				( member ( signalRef "M_D_DQ<52>") )
				( member ( signalRef "M_D_DQ<53>") )
				( member ( signalRef "M_D_DQ<54>") )
				( member ( signalRef "M_D_DQ<55>") )
				( member ( signalRef "M_D_DQ<56>") )
				( member ( signalRef "M_D_DQ<57>") )
				( member ( signalRef "M_D_DQ<58>") )
				( member ( signalRef "M_D_DQ<59>") )
				( member ( signalRef "M_D_DQ<60>") )
				( member ( signalRef "M_D_DQ<61>") )
				( member ( signalRef "M_D_DQ<62>") )
				( member ( signalRef "M_D_DQ<63>") )
				( objectStatus "@baseboard_fab2_lib.baseboard_fab2(sch_1):m_d_dq" )
			)
			( bus "M_D_DQS_DN"
				( memberType ( signal ) )
				( member ( signalRef "M_D_DQS_DN<0>") )
				( member ( signalRef "M_D_DQS_DN<1>") )
				( member ( signalRef "M_D_DQS_DN<2>") )
				( member ( signalRef "M_D_DQS_DN<3>") )
				( member ( signalRef "M_D_DQS_DN<4>") )
				( member ( signalRef "M_D_DQS_DN<5>") )
				( member ( signalRef "M_D_DQS_DN<6>") )
				( member ( signalRef "M_D_DQS_DN<7>") )
				( member ( signalRef "M_D_DQS_DN<8>") )
				( member ( signalRef "M_D_DQS_DN<9>") )
				( member ( signalRef "M_D_DQS_DN<10>") )
				( member ( signalRef "M_D_DQS_DN<11>") )
				( member ( signalRef "M_D_DQS_DN<12>") )
				( member ( signalRef "M_D_DQS_DN<13>") )
				( member ( signalRef "M_D_DQS_DN<14>") )
				( member ( signalRef "M_D_DQS_DN<15>") )
				( member ( signalRef "M_D_DQS_DN<16>") )
				( member ( signalRef "M_D_DQS_DN<17>") )
				( objectStatus "@baseboard_fab2_lib.baseboard_fab2(sch_1):m_d_dqs_dn" )
			)
			( bus "M_D_DQS_DP"
				( memberType ( signal ) )
				( member ( signalRef "M_D_DQS_DP<0>") )
				( member ( signalRef "M_D_DQS_DP<1>") )
				( member ( signalRef "M_D_DQS_DP<2>") )
				( member ( signalRef "M_D_DQS_DP<3>") )
				( member ( signalRef "M_D_DQS_DP<4>") )
				( member ( signalRef "M_D_DQS_DP<5>") )
				( member ( signalRef "M_D_DQS_DP<6>") )
				( member ( signalRef "M_D_DQS_DP<7>") )
				( member ( signalRef "M_D_DQS_DP<8>") )
				( member ( signalRef "M_D_DQS_DP<9>") )
				( member ( signalRef "M_D_DQS_DP<10>") )
				( member ( signalRef "M_D_DQS_DP<11>") )
				( member ( signalRef "M_D_DQS_DP<12>") )
				( member ( signalRef "M_D_DQS_DP<13>") )
				( member ( signalRef "M_D_DQS_DP<14>") )
				( member ( signalRef "M_D_DQS_DP<15>") )
				( member ( signalRef "M_D_DQS_DP<16>") )
				( member ( signalRef "M_D_DQS_DP<17>") )
				( objectStatus "@baseboard_fab2_lib.baseboard_fab2(sch_1):m_d_dqs_dp" )
			)
			( bus "M_D_ECC"
				( memberType ( signal ) )
				( member ( signalRef "M_D_ECC<0>") )
				( member ( signalRef "M_D_ECC<1>") )
				( member ( signalRef "M_D_ECC<2>") )
				( member ( signalRef "M_D_ECC<3>") )
				( member ( signalRef "M_D_ECC<4>") )
				( member ( signalRef "M_D_ECC<5>") )
				( member ( signalRef "M_D_ECC<6>") )
				( member ( signalRef "M_D_ECC<7>") )
				( objectStatus "@baseboard_fab2_lib.baseboard_fab2(sch_1):m_d_ecc" )
			)
			( bus "M_D_MA"
				( memberType ( signal ) )
				( member ( signalRef "M_D_MA<0>") )
				( member ( signalRef "M_D_MA<1>") )
				( member ( signalRef "M_D_MA<2>") )
				( member ( signalRef "M_D_MA<3>") )
				( member ( signalRef "M_D_MA<4>") )
				( member ( signalRef "M_D_MA<5>") )
				( member ( signalRef "M_D_MA<6>") )
				( member ( signalRef "M_D_MA<7>") )
				( member ( signalRef "M_D_MA<8>") )
				( member ( signalRef "M_D_MA<9>") )
				( member ( signalRef "M_D_MA<10>") )
				( member ( signalRef "M_D_MA<11>") )
				( member ( signalRef "M_D_MA<12>") )
				( member ( signalRef "M_D_MA<13>") )
				( member ( signalRef "M_D_MA<14>") )
				( member ( signalRef "M_D_MA<15>") )
				( member ( signalRef "M_D_MA<16>") )
				( member ( signalRef "M_D_MA<17>") )
				( objectStatus "@baseboard_fab2_lib.baseboard_fab2(sch_1):m_d_ma" )
			)
			( bus "M_D_ODT"
				( memberType ( signal ) )
				( member ( signalRef "M_D_ODT<0>") )
				( member ( signalRef "M_D_ODT<1>") )
				( member ( signalRef "M_D_ODT<2>") )
				( member ( signalRef "M_D_ODT<3>") )
				( objectStatus "@baseboard_fab2_lib.baseboard_fab2(sch_1):m_d_odt" )
			)
			( bus "M_E_BA"
				( memberType ( signal ) )
				( member ( signalRef "M_E_BA<0>") )
				( member ( signalRef "M_E_BA<1>") )
				( objectStatus "@baseboard_fab2_lib.baseboard_fab2(sch_1):m_e_ba" )
			)
			( bus "M_E_BG"
				( memberType ( signal ) )
				( member ( signalRef "M_E_BG<0>") )
				( member ( signalRef "M_E_BG<1>") )
				( objectStatus "@baseboard_fab2_lib.baseboard_fab2(sch_1):m_e_bg" )
			)
			( bus "M_E_C"
				( memberType ( signal ) )
				( member ( signalRef "M_E_C<2>") )
				( objectStatus "@baseboard_fab2_lib.baseboard_fab2(sch_1):m_e_c" )
			)
			( bus "M_E_CKE"
				( memberType ( signal ) )
				( member ( signalRef "M_E_CKE<0>") )
				( member ( signalRef "M_E_CKE<1>") )
				( member ( signalRef "M_E_CKE<2>") )
				( member ( signalRef "M_E_CKE<3>") )
				( objectStatus "@baseboard_fab2_lib.baseboard_fab2(sch_1):m_e_cke" )
			)
			( bus "M_E_CLK_DN"
				( memberType ( signal ) )
				( member ( signalRef "M_E_CLK_DN<0>") )
				( member ( signalRef "M_E_CLK_DN<1>") )
				( member ( signalRef "M_E_CLK_DN<2>") )
				( member ( signalRef "M_E_CLK_DN<3>") )
				( objectStatus "@baseboard_fab2_lib.baseboard_fab2(sch_1):m_e_clk_dn" )
			)
			( bus "M_E_CLK_DP"
				( memberType ( signal ) )
				( member ( signalRef "M_E_CLK_DP<0>") )
				( member ( signalRef "M_E_CLK_DP<1>") )
				( member ( signalRef "M_E_CLK_DP<2>") )
				( member ( signalRef "M_E_CLK_DP<3>") )
				( objectStatus "@baseboard_fab2_lib.baseboard_fab2(sch_1):m_e_clk_dp" )
			)
			( bus "M_E_CS_N"
				( memberType ( signal ) )
				( member ( signalRef "M_E_CS_N<0>") )
				( member ( signalRef "M_E_CS_N<1>") )
				( member ( signalRef "M_E_CS_N<2>") )
				( member ( signalRef "M_E_CS_N<3>") )
				( member ( signalRef "M_E_CS_N<4>") )
				( member ( signalRef "M_E_CS_N<5>") )
				( member ( signalRef "M_E_CS_N<6>") )
				( member ( signalRef "M_E_CS_N<7>") )
				( objectStatus "@baseboard_fab2_lib.baseboard_fab2(sch_1):m_e_cs_n" )
			)
			( bus "M_E_DQ"
				( memberType ( signal ) )
				( member ( signalRef "M_E_DQ<0>") )
				( member ( signalRef "M_E_DQ<1>") )
				( member ( signalRef "M_E_DQ<2>") )
				( member ( signalRef "M_E_DQ<3>") )
				( member ( signalRef "M_E_DQ<4>") )
				( member ( signalRef "M_E_DQ<5>") )
				( member ( signalRef "M_E_DQ<6>") )
				( member ( signalRef "M_E_DQ<7>") )
				( member ( signalRef "M_E_DQ<8>") )
				( member ( signalRef "M_E_DQ<9>") )
				( member ( signalRef "M_E_DQ<10>") )
				( member ( signalRef "M_E_DQ<11>") )
				( member ( signalRef "M_E_DQ<12>") )
				( member ( signalRef "M_E_DQ<13>") )
				( member ( signalRef "M_E_DQ<14>") )
				( member ( signalRef "M_E_DQ<15>") )
				( member ( signalRef "M_E_DQ<16>") )
				( member ( signalRef "M_E_DQ<17>") )
				( member ( signalRef "M_E_DQ<18>") )
				( member ( signalRef "M_E_DQ<19>") )
				( member ( signalRef "M_E_DQ<20>") )
				( member ( signalRef "M_E_DQ<21>") )
				( member ( signalRef "M_E_DQ<22>") )
				( member ( signalRef "M_E_DQ<23>") )
				( member ( signalRef "M_E_DQ<24>") )
				( member ( signalRef "M_E_DQ<25>") )
				( member ( signalRef "M_E_DQ<26>") )
				( member ( signalRef "M_E_DQ<27>") )
				( member ( signalRef "M_E_DQ<28>") )
				( member ( signalRef "M_E_DQ<29>") )
				( member ( signalRef "M_E_DQ<30>") )
				( member ( signalRef "M_E_DQ<31>") )
				( member ( signalRef "M_E_DQ<32>") )
				( member ( signalRef "M_E_DQ<33>") )
				( member ( signalRef "M_E_DQ<34>") )
				( member ( signalRef "M_E_DQ<35>") )
				( member ( signalRef "M_E_DQ<36>") )
				( member ( signalRef "M_E_DQ<37>") )
				( member ( signalRef "M_E_DQ<38>") )
				( member ( signalRef "M_E_DQ<39>") )
				( member ( signalRef "M_E_DQ<40>") )
				( member ( signalRef "M_E_DQ<41>") )
				( member ( signalRef "M_E_DQ<42>") )
				( member ( signalRef "M_E_DQ<43>") )
				( member ( signalRef "M_E_DQ<44>") )
				( member ( signalRef "M_E_DQ<45>") )
				( member ( signalRef "M_E_DQ<46>") )
				( member ( signalRef "M_E_DQ<47>") )
				( member ( signalRef "M_E_DQ<48>") )
				( member ( signalRef "M_E_DQ<49>") )
				( member ( signalRef "M_E_DQ<50>") )
				( member ( signalRef "M_E_DQ<51>") )
				( member ( signalRef "M_E_DQ<52>") )
				( member ( signalRef "M_E_DQ<53>") )
				( member ( signalRef "M_E_DQ<54>") )
				( member ( signalRef "M_E_DQ<55>") )
				( member ( signalRef "M_E_DQ<56>") )
				( member ( signalRef "M_E_DQ<57>") )
				( member ( signalRef "M_E_DQ<58>") )
				( member ( signalRef "M_E_DQ<59>") )
				( member ( signalRef "M_E_DQ<60>") )
				( member ( signalRef "M_E_DQ<61>") )
				( member ( signalRef "M_E_DQ<62>") )
				( member ( signalRef "M_E_DQ<63>") )
				( objectStatus "@baseboard_fab2_lib.baseboard_fab2(sch_1):m_e_dq" )
			)
			( bus "M_E_DQS_DN"
				( memberType ( signal ) )
				( member ( signalRef "M_E_DQS_DN<0>") )
				( member ( signalRef "M_E_DQS_DN<1>") )
				( member ( signalRef "M_E_DQS_DN<2>") )
				( member ( signalRef "M_E_DQS_DN<3>") )
				( member ( signalRef "M_E_DQS_DN<4>") )
				( member ( signalRef "M_E_DQS_DN<5>") )
				( member ( signalRef "M_E_DQS_DN<6>") )
				( member ( signalRef "M_E_DQS_DN<7>") )
				( member ( signalRef "M_E_DQS_DN<8>") )
				( member ( signalRef "M_E_DQS_DN<9>") )
				( member ( signalRef "M_E_DQS_DN<10>") )
				( member ( signalRef "M_E_DQS_DN<11>") )
				( member ( signalRef "M_E_DQS_DN<12>") )
				( member ( signalRef "M_E_DQS_DN<13>") )
				( member ( signalRef "M_E_DQS_DN<14>") )
				( member ( signalRef "M_E_DQS_DN<15>") )
				( member ( signalRef "M_E_DQS_DN<16>") )
				( member ( signalRef "M_E_DQS_DN<17>") )
				( objectStatus "@baseboard_fab2_lib.baseboard_fab2(sch_1):m_e_dqs_dn" )
			)
			( bus "M_E_DQS_DP"
				( memberType ( signal ) )
				( member ( signalRef "M_E_DQS_DP<0>") )
				( member ( signalRef "M_E_DQS_DP<1>") )
				( member ( signalRef "M_E_DQS_DP<2>") )
				( member ( signalRef "M_E_DQS_DP<3>") )
				( member ( signalRef "M_E_DQS_DP<4>") )
				( member ( signalRef "M_E_DQS_DP<5>") )
				( member ( signalRef "M_E_DQS_DP<6>") )
				( member ( signalRef "M_E_DQS_DP<7>") )
				( member ( signalRef "M_E_DQS_DP<8>") )
				( member ( signalRef "M_E_DQS_DP<9>") )
				( member ( signalRef "M_E_DQS_DP<10>") )
				( member ( signalRef "M_E_DQS_DP<11>") )
				( member ( signalRef "M_E_DQS_DP<12>") )
				( member ( signalRef "M_E_DQS_DP<13>") )
				( member ( signalRef "M_E_DQS_DP<14>") )
				( member ( signalRef "M_E_DQS_DP<15>") )
				( member ( signalRef "M_E_DQS_DP<16>") )
				( member ( signalRef "M_E_DQS_DP<17>") )
				( objectStatus "@baseboard_fab2_lib.baseboard_fab2(sch_1):m_e_dqs_dp" )
			)
			( bus "M_E_ECC"
				( memberType ( signal ) )
				( member ( signalRef "M_E_ECC<0>") )
				( member ( signalRef "M_E_ECC<1>") )
				( member ( signalRef "M_E_ECC<2>") )
				( member ( signalRef "M_E_ECC<3>") )
				( member ( signalRef "M_E_ECC<4>") )
				( member ( signalRef "M_E_ECC<5>") )
				( member ( signalRef "M_E_ECC<6>") )
				( member ( signalRef "M_E_ECC<7>") )
				( objectStatus "@baseboard_fab2_lib.baseboard_fab2(sch_1):m_e_ecc" )
			)
			( bus "M_E_MA"
				( memberType ( signal ) )
				( member ( signalRef "M_E_MA<0>") )
				( member ( signalRef "M_E_MA<1>") )
				( member ( signalRef "M_E_MA<2>") )
				( member ( signalRef "M_E_MA<3>") )
				( member ( signalRef "M_E_MA<4>") )
				( member ( signalRef "M_E_MA<5>") )
				( member ( signalRef "M_E_MA<6>") )
				( member ( signalRef "M_E_MA<7>") )
				( member ( signalRef "M_E_MA<8>") )
				( member ( signalRef "M_E_MA<9>") )
				( member ( signalRef "M_E_MA<10>") )
				( member ( signalRef "M_E_MA<11>") )
				( member ( signalRef "M_E_MA<12>") )
				( member ( signalRef "M_E_MA<13>") )
				( member ( signalRef "M_E_MA<14>") )
				( member ( signalRef "M_E_MA<15>") )
				( member ( signalRef "M_E_MA<16>") )
				( member ( signalRef "M_E_MA<17>") )
				( objectStatus "@baseboard_fab2_lib.baseboard_fab2(sch_1):m_e_ma" )
			)
			( bus "M_E_ODT"
				( memberType ( signal ) )
				( member ( signalRef "M_E_ODT<0>") )
				( member ( signalRef "M_E_ODT<1>") )
				( member ( signalRef "M_E_ODT<2>") )
				( member ( signalRef "M_E_ODT<3>") )
				( objectStatus "@baseboard_fab2_lib.baseboard_fab2(sch_1):m_e_odt" )
			)
			( bus "M_F_BA"
				( memberType ( signal ) )
				( member ( signalRef "M_F_BA<0>") )
				( member ( signalRef "M_F_BA<1>") )
				( objectStatus "@baseboard_fab2_lib.baseboard_fab2(sch_1):m_f_ba" )
			)
			( bus "M_F_BG"
				( memberType ( signal ) )
				( member ( signalRef "M_F_BG<0>") )
				( member ( signalRef "M_F_BG<1>") )
				( objectStatus "@baseboard_fab2_lib.baseboard_fab2(sch_1):m_f_bg" )
			)
			( bus "M_F_C"
				( memberType ( signal ) )
				( member ( signalRef "M_F_C<2>") )
				( objectStatus "@baseboard_fab2_lib.baseboard_fab2(sch_1):m_f_c" )
			)
			( bus "M_F_CKE"
				( memberType ( signal ) )
				( member ( signalRef "M_F_CKE<0>") )
				( member ( signalRef "M_F_CKE<1>") )
				( member ( signalRef "M_F_CKE<2>") )
				( member ( signalRef "M_F_CKE<3>") )
				( objectStatus "@baseboard_fab2_lib.baseboard_fab2(sch_1):m_f_cke" )
			)
			( bus "M_F_CLK_DN"
				( memberType ( signal ) )
				( member ( signalRef "M_F_CLK_DN<0>") )
				( member ( signalRef "M_F_CLK_DN<1>") )
				( member ( signalRef "M_F_CLK_DN<2>") )
				( member ( signalRef "M_F_CLK_DN<3>") )
				( objectStatus "@baseboard_fab2_lib.baseboard_fab2(sch_1):m_f_clk_dn" )
			)
			( bus "M_F_CLK_DP"
				( memberType ( signal ) )
				( member ( signalRef "M_F_CLK_DP<0>") )
				( member ( signalRef "M_F_CLK_DP<1>") )
				( member ( signalRef "M_F_CLK_DP<2>") )
				( member ( signalRef "M_F_CLK_DP<3>") )
				( objectStatus "@baseboard_fab2_lib.baseboard_fab2(sch_1):m_f_clk_dp" )
			)
			( bus "M_F_CS_N"
				( memberType ( signal ) )
				( member ( signalRef "M_F_CS_N<0>") )
				( member ( signalRef "M_F_CS_N<1>") )
				( member ( signalRef "M_F_CS_N<2>") )
				( member ( signalRef "M_F_CS_N<3>") )
				( member ( signalRef "M_F_CS_N<4>") )
				( member ( signalRef "M_F_CS_N<5>") )
				( member ( signalRef "M_F_CS_N<6>") )
				( member ( signalRef "M_F_CS_N<7>") )
				( objectStatus "@baseboard_fab2_lib.baseboard_fab2(sch_1):m_f_cs_n" )
			)
			( bus "M_F_DQ"
				( memberType ( signal ) )
				( member ( signalRef "M_F_DQ<0>") )
				( member ( signalRef "M_F_DQ<1>") )
				( member ( signalRef "M_F_DQ<2>") )
				( member ( signalRef "M_F_DQ<3>") )
				( member ( signalRef "M_F_DQ<4>") )
				( member ( signalRef "M_F_DQ<5>") )
				( member ( signalRef "M_F_DQ<6>") )
				( member ( signalRef "M_F_DQ<7>") )
				( member ( signalRef "M_F_DQ<8>") )
				( member ( signalRef "M_F_DQ<9>") )
				( member ( signalRef "M_F_DQ<10>") )
				( member ( signalRef "M_F_DQ<11>") )
				( member ( signalRef "M_F_DQ<12>") )
				( member ( signalRef "M_F_DQ<13>") )
				( member ( signalRef "M_F_DQ<14>") )
				( member ( signalRef "M_F_DQ<15>") )
				( member ( signalRef "M_F_DQ<16>") )
				( member ( signalRef "M_F_DQ<17>") )
				( member ( signalRef "M_F_DQ<18>") )
				( member ( signalRef "M_F_DQ<19>") )
				( member ( signalRef "M_F_DQ<20>") )
				( member ( signalRef "M_F_DQ<21>") )
				( member ( signalRef "M_F_DQ<22>") )
				( member ( signalRef "M_F_DQ<23>") )
				( member ( signalRef "M_F_DQ<24>") )
				( member ( signalRef "M_F_DQ<25>") )
				( member ( signalRef "M_F_DQ<26>") )
				( member ( signalRef "M_F_DQ<27>") )
				( member ( signalRef "M_F_DQ<28>") )
				( member ( signalRef "M_F_DQ<29>") )
				( member ( signalRef "M_F_DQ<30>") )
				( member ( signalRef "M_F_DQ<31>") )
				( member ( signalRef "M_F_DQ<32>") )
				( member ( signalRef "M_F_DQ<33>") )
				( member ( signalRef "M_F_DQ<34>") )
				( member ( signalRef "M_F_DQ<35>") )
				( member ( signalRef "M_F_DQ<36>") )
				( member ( signalRef "M_F_DQ<37>") )
				( member ( signalRef "M_F_DQ<38>") )
				( member ( signalRef "M_F_DQ<39>") )
				( member ( signalRef "M_F_DQ<40>") )
				( member ( signalRef "M_F_DQ<41>") )
				( member ( signalRef "M_F_DQ<42>") )
				( member ( signalRef "M_F_DQ<43>") )
				( member ( signalRef "M_F_DQ<44>") )
				( member ( signalRef "M_F_DQ<45>") )
				( member ( signalRef "M_F_DQ<46>") )
				( member ( signalRef "M_F_DQ<47>") )
				( member ( signalRef "M_F_DQ<48>") )
				( member ( signalRef "M_F_DQ<49>") )
				( member ( signalRef "M_F_DQ<50>") )
				( member ( signalRef "M_F_DQ<51>") )
				( member ( signalRef "M_F_DQ<52>") )
				( member ( signalRef "M_F_DQ<53>") )
				( member ( signalRef "M_F_DQ<54>") )
				( member ( signalRef "M_F_DQ<55>") )
				( member ( signalRef "M_F_DQ<56>") )
				( member ( signalRef "M_F_DQ<57>") )
				( member ( signalRef "M_F_DQ<58>") )
				( member ( signalRef "M_F_DQ<59>") )
				( member ( signalRef "M_F_DQ<60>") )
				( member ( signalRef "M_F_DQ<61>") )
				( member ( signalRef "M_F_DQ<62>") )
				( member ( signalRef "M_F_DQ<63>") )
				( objectStatus "@baseboard_fab2_lib.baseboard_fab2(sch_1):m_f_dq" )
			)
			( bus "M_F_DQS_DN"
				( memberType ( signal ) )
				( member ( signalRef "M_F_DQS_DN<0>") )
				( member ( signalRef "M_F_DQS_DN<1>") )
				( member ( signalRef "M_F_DQS_DN<2>") )
				( member ( signalRef "M_F_DQS_DN<3>") )
				( member ( signalRef "M_F_DQS_DN<4>") )
				( member ( signalRef "M_F_DQS_DN<5>") )
				( member ( signalRef "M_F_DQS_DN<6>") )
				( member ( signalRef "M_F_DQS_DN<7>") )
				( member ( signalRef "M_F_DQS_DN<8>") )
				( member ( signalRef "M_F_DQS_DN<9>") )
				( member ( signalRef "M_F_DQS_DN<10>") )
				( member ( signalRef "M_F_DQS_DN<11>") )
				( member ( signalRef "M_F_DQS_DN<12>") )
				( member ( signalRef "M_F_DQS_DN<13>") )
				( member ( signalRef "M_F_DQS_DN<14>") )
				( member ( signalRef "M_F_DQS_DN<15>") )
				( member ( signalRef "M_F_DQS_DN<16>") )
				( member ( signalRef "M_F_DQS_DN<17>") )
				( objectStatus "@baseboard_fab2_lib.baseboard_fab2(sch_1):m_f_dqs_dn" )
			)
			( bus "M_F_DQS_DP"
				( memberType ( signal ) )
				( member ( signalRef "M_F_DQS_DP<0>") )
				( member ( signalRef "M_F_DQS_DP<1>") )
				( member ( signalRef "M_F_DQS_DP<2>") )
				( member ( signalRef "M_F_DQS_DP<3>") )
				( member ( signalRef "M_F_DQS_DP<4>") )
				( member ( signalRef "M_F_DQS_DP<5>") )
				( member ( signalRef "M_F_DQS_DP<6>") )
				( member ( signalRef "M_F_DQS_DP<7>") )
				( member ( signalRef "M_F_DQS_DP<8>") )
				( member ( signalRef "M_F_DQS_DP<9>") )
				( member ( signalRef "M_F_DQS_DP<10>") )
				( member ( signalRef "M_F_DQS_DP<11>") )
				( member ( signalRef "M_F_DQS_DP<12>") )
				( member ( signalRef "M_F_DQS_DP<13>") )
				( member ( signalRef "M_F_DQS_DP<14>") )
				( member ( signalRef "M_F_DQS_DP<15>") )
				( member ( signalRef "M_F_DQS_DP<16>") )
				( member ( signalRef "M_F_DQS_DP<17>") )
				( objectStatus "@baseboard_fab2_lib.baseboard_fab2(sch_1):m_f_dqs_dp" )
			)
			( bus "M_F_ECC"
				( memberType ( signal ) )
				( member ( signalRef "M_F_ECC<0>") )
				( member ( signalRef "M_F_ECC<1>") )
				( member ( signalRef "M_F_ECC<2>") )
				( member ( signalRef "M_F_ECC<3>") )
				( member ( signalRef "M_F_ECC<4>") )
				( member ( signalRef "M_F_ECC<5>") )
				( member ( signalRef "M_F_ECC<6>") )
				( member ( signalRef "M_F_ECC<7>") )
				( objectStatus "@baseboard_fab2_lib.baseboard_fab2(sch_1):m_f_ecc" )
			)
			( bus "M_F_MA"
				( memberType ( signal ) )
				( member ( signalRef "M_F_MA<0>") )
				( member ( signalRef "M_F_MA<1>") )
				( member ( signalRef "M_F_MA<2>") )
				( member ( signalRef "M_F_MA<3>") )
				( member ( signalRef "M_F_MA<4>") )
				( member ( signalRef "M_F_MA<5>") )
				( member ( signalRef "M_F_MA<6>") )
				( member ( signalRef "M_F_MA<7>") )
				( member ( signalRef "M_F_MA<8>") )
				( member ( signalRef "M_F_MA<9>") )
				( member ( signalRef "M_F_MA<10>") )
				( member ( signalRef "M_F_MA<11>") )
				( member ( signalRef "M_F_MA<12>") )
				( member ( signalRef "M_F_MA<13>") )
				( member ( signalRef "M_F_MA<14>") )
				( member ( signalRef "M_F_MA<15>") )
				( member ( signalRef "M_F_MA<16>") )
				( member ( signalRef "M_F_MA<17>") )
				( objectStatus "@baseboard_fab2_lib.baseboard_fab2(sch_1):m_f_ma" )
			)
			( bus "M_F_ODT"
				( memberType ( signal ) )
				( member ( signalRef "M_F_ODT<0>") )
				( member ( signalRef "M_F_ODT<1>") )
				( member ( signalRef "M_F_ODT<2>") )
				( member ( signalRef "M_F_ODT<3>") )
				( objectStatus "@baseboard_fab2_lib.baseboard_fab2(sch_1):m_f_odt" )
			)
			( bus "DMI_CPU0_PCH_RX_C_DN"
				( memberType ( signal ) )
				( member ( signalRef "DMI_CPU0_PCH_RX_C_DN<0>") )
				( member ( signalRef "DMI_CPU0_PCH_RX_C_DN<1>") )
				( member ( signalRef "DMI_CPU0_PCH_RX_C_DN<2>") )
				( member ( signalRef "DMI_CPU0_PCH_RX_C_DN<3>") )
				( objectStatus "@baseboard_fab2_lib.baseboard_fab2(sch_1):dmi_cpu0_pch_rx_c_dn" )
			)
			( bus "DMI_CPU0_PCH_RX_C_DP"
				( memberType ( signal ) )
				( member ( signalRef "DMI_CPU0_PCH_RX_C_DP<0>") )
				( member ( signalRef "DMI_CPU0_PCH_RX_C_DP<1>") )
				( member ( signalRef "DMI_CPU0_PCH_RX_C_DP<2>") )
				( member ( signalRef "DMI_CPU0_PCH_RX_C_DP<3>") )
				( objectStatus "@baseboard_fab2_lib.baseboard_fab2(sch_1):dmi_cpu0_pch_rx_c_dp" )
			)
			( bus "DMI_CPU0_PCH_TX_DN"
				( memberType ( signal ) )
				( member ( signalRef "DMI_CPU0_PCH_TX_DN<0>") )
				( member ( signalRef "DMI_CPU0_PCH_TX_DN<1>") )
				( member ( signalRef "DMI_CPU0_PCH_TX_DN<2>") )
				( member ( signalRef "DMI_CPU0_PCH_TX_DN<3>") )
				( objectStatus "@baseboard_fab2_lib.baseboard_fab2(sch_1):dmi_cpu0_pch_tx_dn" )
			)
			( bus "DMI_CPU0_PCH_TX_DP"
				( memberType ( signal ) )
				( member ( signalRef "DMI_CPU0_PCH_TX_DP<0>") )
				( member ( signalRef "DMI_CPU0_PCH_TX_DP<1>") )
				( member ( signalRef "DMI_CPU0_PCH_TX_DP<2>") )
				( member ( signalRef "DMI_CPU0_PCH_TX_DP<3>") )
				( objectStatus "@baseboard_fab2_lib.baseboard_fab2(sch_1):dmi_cpu0_pch_tx_dp" )
			)
			( bus "P3E_CPU0_PE1_PCH_RXN"
				( memberType ( signal ) )
				( member ( signalRef "P3E_CPU0_PE1_PCH_RXN<8>") )
				( member ( signalRef "P3E_CPU0_PE1_PCH_RXN<9>") )
				( member ( signalRef "P3E_CPU0_PE1_PCH_RXN<10>") )
				( member ( signalRef "P3E_CPU0_PE1_PCH_RXN<11>") )
				( member ( signalRef "P3E_CPU0_PE1_PCH_RXN<12>") )
				( member ( signalRef "P3E_CPU0_PE1_PCH_RXN<13>") )
				( member ( signalRef "P3E_CPU0_PE1_PCH_RXN<14>") )
				( member ( signalRef "P3E_CPU0_PE1_PCH_RXN<15>") )
				( member ( signalRef "P3E_CPU0_PE1_PCH_RXN<0>") )
				( member ( signalRef "P3E_CPU0_PE1_PCH_RXN<1>") )
				( member ( signalRef "P3E_CPU0_PE1_PCH_RXN<2>") )
				( member ( signalRef "P3E_CPU0_PE1_PCH_RXN<3>") )
				( member ( signalRef "P3E_CPU0_PE1_PCH_RXN<4>") )
				( member ( signalRef "P3E_CPU0_PE1_PCH_RXN<5>") )
				( member ( signalRef "P3E_CPU0_PE1_PCH_RXN<6>") )
				( member ( signalRef "P3E_CPU0_PE1_PCH_RXN<7>") )
				( objectStatus "@baseboard_fab2_lib.baseboard_fab2(sch_1):p3e_cpu0_pe1_pch_rxn" )
			)
			( bus "P3E_CPU0_PE1_PCH_RXP"
				( memberType ( signal ) )
				( member ( signalRef "P3E_CPU0_PE1_PCH_RXP<8>") )
				( member ( signalRef "P3E_CPU0_PE1_PCH_RXP<9>") )
				( member ( signalRef "P3E_CPU0_PE1_PCH_RXP<10>") )
				( member ( signalRef "P3E_CPU0_PE1_PCH_RXP<11>") )
				( member ( signalRef "P3E_CPU0_PE1_PCH_RXP<12>") )
				( member ( signalRef "P3E_CPU0_PE1_PCH_RXP<13>") )
				( member ( signalRef "P3E_CPU0_PE1_PCH_RXP<14>") )
				( member ( signalRef "P3E_CPU0_PE1_PCH_RXP<15>") )
				( member ( signalRef "P3E_CPU0_PE1_PCH_RXP<0>") )
				( member ( signalRef "P3E_CPU0_PE1_PCH_RXP<1>") )
				( member ( signalRef "P3E_CPU0_PE1_PCH_RXP<2>") )
				( member ( signalRef "P3E_CPU0_PE1_PCH_RXP<3>") )
				( member ( signalRef "P3E_CPU0_PE1_PCH_RXP<4>") )
				( member ( signalRef "P3E_CPU0_PE1_PCH_RXP<5>") )
				( member ( signalRef "P3E_CPU0_PE1_PCH_RXP<6>") )
				( member ( signalRef "P3E_CPU0_PE1_PCH_RXP<7>") )
				( objectStatus "@baseboard_fab2_lib.baseboard_fab2(sch_1):p3e_cpu0_pe1_pch_rxp" )
			)
			( bus "P3E_CPU0_PE1_PCH_TXN"
				( memberType ( signal ) )
				( member ( signalRef "P3E_CPU0_PE1_PCH_TXN<8>") )
				( member ( signalRef "P3E_CPU0_PE1_PCH_TXN<9>") )
				( member ( signalRef "P3E_CPU0_PE1_PCH_TXN<10>") )
				( member ( signalRef "P3E_CPU0_PE1_PCH_TXN<11>") )
				( member ( signalRef "P3E_CPU0_PE1_PCH_TXN<12>") )
				( member ( signalRef "P3E_CPU0_PE1_PCH_TXN<13>") )
				( member ( signalRef "P3E_CPU0_PE1_PCH_TXN<14>") )
				( member ( signalRef "P3E_CPU0_PE1_PCH_TXN<15>") )
				( member ( signalRef "P3E_CPU0_PE1_PCH_TXN<0>") )
				( member ( signalRef "P3E_CPU0_PE1_PCH_TXN<1>") )
				( member ( signalRef "P3E_CPU0_PE1_PCH_TXN<2>") )
				( member ( signalRef "P3E_CPU0_PE1_PCH_TXN<3>") )
				( member ( signalRef "P3E_CPU0_PE1_PCH_TXN<4>") )
				( member ( signalRef "P3E_CPU0_PE1_PCH_TXN<5>") )
				( member ( signalRef "P3E_CPU0_PE1_PCH_TXN<6>") )
				( member ( signalRef "P3E_CPU0_PE1_PCH_TXN<7>") )
				( objectStatus "@baseboard_fab2_lib.baseboard_fab2(sch_1):p3e_cpu0_pe1_pch_txn" )
			)
			( bus "P3E_CPU0_PE1_PCH_TXP"
				( memberType ( signal ) )
				( member ( signalRef "P3E_CPU0_PE1_PCH_TXP<8>") )
				( member ( signalRef "P3E_CPU0_PE1_PCH_TXP<9>") )
				( member ( signalRef "P3E_CPU0_PE1_PCH_TXP<10>") )
				( member ( signalRef "P3E_CPU0_PE1_PCH_TXP<11>") )
				( member ( signalRef "P3E_CPU0_PE1_PCH_TXP<12>") )
				( member ( signalRef "P3E_CPU0_PE1_PCH_TXP<13>") )
				( member ( signalRef "P3E_CPU0_PE1_PCH_TXP<14>") )
				( member ( signalRef "P3E_CPU0_PE1_PCH_TXP<15>") )
				( member ( signalRef "P3E_CPU0_PE1_PCH_TXP<0>") )
				( member ( signalRef "P3E_CPU0_PE1_PCH_TXP<1>") )
				( member ( signalRef "P3E_CPU0_PE1_PCH_TXP<2>") )
				( member ( signalRef "P3E_CPU0_PE1_PCH_TXP<3>") )
				( member ( signalRef "P3E_CPU0_PE1_PCH_TXP<4>") )
				( member ( signalRef "P3E_CPU0_PE1_PCH_TXP<5>") )
				( member ( signalRef "P3E_CPU0_PE1_PCH_TXP<6>") )
				( member ( signalRef "P3E_CPU0_PE1_PCH_TXP<7>") )
				( objectStatus "@baseboard_fab2_lib.baseboard_fab2(sch_1):p3e_cpu0_pe1_pch_txp" )
			)
			( bus "P3E_CPU0_PE1_SS_RXN"
				( memberType ( signal ) )
				( member ( signalRef "P3E_CPU0_PE1_SS_RXN<0>") )
				( member ( signalRef "P3E_CPU0_PE1_SS_RXN<1>") )
				( member ( signalRef "P3E_CPU0_PE1_SS_RXN<2>") )
				( member ( signalRef "P3E_CPU0_PE1_SS_RXN<3>") )
				( member ( signalRef "P3E_CPU0_PE1_SS_RXN<4>") )
				( member ( signalRef "P3E_CPU0_PE1_SS_RXN<5>") )
				( member ( signalRef "P3E_CPU0_PE1_SS_RXN<6>") )
				( member ( signalRef "P3E_CPU0_PE1_SS_RXN<7>") )
				( objectStatus "@baseboard_fab2_lib.baseboard_fab2(sch_1):p3e_cpu0_pe1_ss_rxn" )
			)
			( bus "P3E_CPU0_PE1_SS_RXP"
				( memberType ( signal ) )
				( member ( signalRef "P3E_CPU0_PE1_SS_RXP<0>") )
				( member ( signalRef "P3E_CPU0_PE1_SS_RXP<1>") )
				( member ( signalRef "P3E_CPU0_PE1_SS_RXP<2>") )
				( member ( signalRef "P3E_CPU0_PE1_SS_RXP<3>") )
				( member ( signalRef "P3E_CPU0_PE1_SS_RXP<4>") )
				( member ( signalRef "P3E_CPU0_PE1_SS_RXP<5>") )
				( member ( signalRef "P3E_CPU0_PE1_SS_RXP<6>") )
				( member ( signalRef "P3E_CPU0_PE1_SS_RXP<7>") )
				( objectStatus "@baseboard_fab2_lib.baseboard_fab2(sch_1):p3e_cpu0_pe1_ss_rxp" )
			)
			( bus "P3E_CPU0_PE1_SS_TXN"
				( memberType ( signal ) )
				( member ( signalRef "P3E_CPU0_PE1_SS_TXN<0>") )
				( member ( signalRef "P3E_CPU0_PE1_SS_TXN<1>") )
				( member ( signalRef "P3E_CPU0_PE1_SS_TXN<2>") )
				( member ( signalRef "P3E_CPU0_PE1_SS_TXN<3>") )
				( member ( signalRef "P3E_CPU0_PE1_SS_TXN<4>") )
				( member ( signalRef "P3E_CPU0_PE1_SS_TXN<5>") )
				( member ( signalRef "P3E_CPU0_PE1_SS_TXN<6>") )
				( member ( signalRef "P3E_CPU0_PE1_SS_TXN<7>") )
				( objectStatus "@baseboard_fab2_lib.baseboard_fab2(sch_1):p3e_cpu0_pe1_ss_txn" )
			)
			( bus "P3E_CPU0_PE1_SS_TXP"
				( memberType ( signal ) )
				( member ( signalRef "P3E_CPU0_PE1_SS_TXP<0>") )
				( member ( signalRef "P3E_CPU0_PE1_SS_TXP<1>") )
				( member ( signalRef "P3E_CPU0_PE1_SS_TXP<2>") )
				( member ( signalRef "P3E_CPU0_PE1_SS_TXP<3>") )
				( member ( signalRef "P3E_CPU0_PE1_SS_TXP<4>") )
				( member ( signalRef "P3E_CPU0_PE1_SS_TXP<5>") )
				( member ( signalRef "P3E_CPU0_PE1_SS_TXP<6>") )
				( member ( signalRef "P3E_CPU0_PE1_SS_TXP<7>") )
				( objectStatus "@baseboard_fab2_lib.baseboard_fab2(sch_1):p3e_cpu0_pe1_ss_txp" )
			)
			( bus "P3E_CPU0_PE2_SS_RXN"
				( memberType ( signal ) )
				( member ( signalRef "P3E_CPU0_PE2_SS_RXN<0>") )
				( member ( signalRef "P3E_CPU0_PE2_SS_RXN<1>") )
				( member ( signalRef "P3E_CPU0_PE2_SS_RXN<2>") )
				( member ( signalRef "P3E_CPU0_PE2_SS_RXN<3>") )
				( member ( signalRef "P3E_CPU0_PE2_SS_RXN<4>") )
				( member ( signalRef "P3E_CPU0_PE2_SS_RXN<5>") )
				( member ( signalRef "P3E_CPU0_PE2_SS_RXN<6>") )
				( member ( signalRef "P3E_CPU0_PE2_SS_RXN<7>") )
				( member ( signalRef "P3E_CPU0_PE2_SS_RXN<8>") )
				( member ( signalRef "P3E_CPU0_PE2_SS_RXN<9>") )
				( member ( signalRef "P3E_CPU0_PE2_SS_RXN<10>") )
				( member ( signalRef "P3E_CPU0_PE2_SS_RXN<11>") )
				( member ( signalRef "P3E_CPU0_PE2_SS_RXN<12>") )
				( member ( signalRef "P3E_CPU0_PE2_SS_RXN<13>") )
				( member ( signalRef "P3E_CPU0_PE2_SS_RXN<14>") )
				( member ( signalRef "P3E_CPU0_PE2_SS_RXN<15>") )
				( objectStatus "@baseboard_fab2_lib.baseboard_fab2(sch_1):p3e_cpu0_pe2_ss_rxn" )
			)
			( bus "P3E_CPU0_PE2_SS_RXP"
				( memberType ( signal ) )
				( member ( signalRef "P3E_CPU0_PE2_SS_RXP<0>") )
				( member ( signalRef "P3E_CPU0_PE2_SS_RXP<1>") )
				( member ( signalRef "P3E_CPU0_PE2_SS_RXP<2>") )
				( member ( signalRef "P3E_CPU0_PE2_SS_RXP<3>") )
				( member ( signalRef "P3E_CPU0_PE2_SS_RXP<4>") )
				( member ( signalRef "P3E_CPU0_PE2_SS_RXP<5>") )
				( member ( signalRef "P3E_CPU0_PE2_SS_RXP<6>") )
				( member ( signalRef "P3E_CPU0_PE2_SS_RXP<7>") )
				( member ( signalRef "P3E_CPU0_PE2_SS_RXP<8>") )
				( member ( signalRef "P3E_CPU0_PE2_SS_RXP<9>") )
				( member ( signalRef "P3E_CPU0_PE2_SS_RXP<10>") )
				( member ( signalRef "P3E_CPU0_PE2_SS_RXP<11>") )
				( member ( signalRef "P3E_CPU0_PE2_SS_RXP<12>") )
				( member ( signalRef "P3E_CPU0_PE2_SS_RXP<13>") )
				( member ( signalRef "P3E_CPU0_PE2_SS_RXP<14>") )
				( member ( signalRef "P3E_CPU0_PE2_SS_RXP<15>") )
				( objectStatus "@baseboard_fab2_lib.baseboard_fab2(sch_1):p3e_cpu0_pe2_ss_rxp" )
			)
			( bus "P3E_CPU0_PE2_SS_TXN"
				( memberType ( signal ) )
				( member ( signalRef "P3E_CPU0_PE2_SS_TXN<0>") )
				( member ( signalRef "P3E_CPU0_PE2_SS_TXN<1>") )
				( member ( signalRef "P3E_CPU0_PE2_SS_TXN<2>") )
				( member ( signalRef "P3E_CPU0_PE2_SS_TXN<3>") )
				( member ( signalRef "P3E_CPU0_PE2_SS_TXN<4>") )
				( member ( signalRef "P3E_CPU0_PE2_SS_TXN<5>") )
				( member ( signalRef "P3E_CPU0_PE2_SS_TXN<6>") )
				( member ( signalRef "P3E_CPU0_PE2_SS_TXN<7>") )
				( member ( signalRef "P3E_CPU0_PE2_SS_TXN<8>") )
				( member ( signalRef "P3E_CPU0_PE2_SS_TXN<9>") )
				( member ( signalRef "P3E_CPU0_PE2_SS_TXN<10>") )
				( member ( signalRef "P3E_CPU0_PE2_SS_TXN<11>") )
				( member ( signalRef "P3E_CPU0_PE2_SS_TXN<12>") )
				( member ( signalRef "P3E_CPU0_PE2_SS_TXN<13>") )
				( member ( signalRef "P3E_CPU0_PE2_SS_TXN<14>") )
				( member ( signalRef "P3E_CPU0_PE2_SS_TXN<15>") )
				( objectStatus "@baseboard_fab2_lib.baseboard_fab2(sch_1):p3e_cpu0_pe2_ss_txn" )
			)
			( bus "P3E_CPU0_PE2_SS_TXP"
				( memberType ( signal ) )
				( member ( signalRef "P3E_CPU0_PE2_SS_TXP<0>") )
				( member ( signalRef "P3E_CPU0_PE2_SS_TXP<1>") )
				( member ( signalRef "P3E_CPU0_PE2_SS_TXP<2>") )
				( member ( signalRef "P3E_CPU0_PE2_SS_TXP<3>") )
				( member ( signalRef "P3E_CPU0_PE2_SS_TXP<4>") )
				( member ( signalRef "P3E_CPU0_PE2_SS_TXP<5>") )
				( member ( signalRef "P3E_CPU0_PE2_SS_TXP<6>") )
				( member ( signalRef "P3E_CPU0_PE2_SS_TXP<7>") )
				( member ( signalRef "P3E_CPU0_PE2_SS_TXP<8>") )
				( member ( signalRef "P3E_CPU0_PE2_SS_TXP<9>") )
				( member ( signalRef "P3E_CPU0_PE2_SS_TXP<10>") )
				( member ( signalRef "P3E_CPU0_PE2_SS_TXP<11>") )
				( member ( signalRef "P3E_CPU0_PE2_SS_TXP<12>") )
				( member ( signalRef "P3E_CPU0_PE2_SS_TXP<13>") )
				( member ( signalRef "P3E_CPU0_PE2_SS_TXP<14>") )
				( member ( signalRef "P3E_CPU0_PE2_SS_TXP<15>") )
				( objectStatus "@baseboard_fab2_lib.baseboard_fab2(sch_1):p3e_cpu0_pe2_ss_txp" )
			)
			( bus "P3E_CPU0_PE3_OCP_RXN"
				( memberType ( signal ) )
				( member ( signalRef "P3E_CPU0_PE3_OCP_RXN<0>") )
				( member ( signalRef "P3E_CPU0_PE3_OCP_RXN<1>") )
				( member ( signalRef "P3E_CPU0_PE3_OCP_RXN<2>") )
				( member ( signalRef "P3E_CPU0_PE3_OCP_RXN<3>") )
				( member ( signalRef "P3E_CPU0_PE3_OCP_RXN<4>") )
				( member ( signalRef "P3E_CPU0_PE3_OCP_RXN<5>") )
				( member ( signalRef "P3E_CPU0_PE3_OCP_RXN<6>") )
				( member ( signalRef "P3E_CPU0_PE3_OCP_RXN<7>") )
				( member ( signalRef "P3E_CPU0_PE3_OCP_RXN<8>") )
				( member ( signalRef "P3E_CPU0_PE3_OCP_RXN<9>") )
				( member ( signalRef "P3E_CPU0_PE3_OCP_RXN<10>") )
				( member ( signalRef "P3E_CPU0_PE3_OCP_RXN<11>") )
				( member ( signalRef "P3E_CPU0_PE3_OCP_RXN<12>") )
				( member ( signalRef "P3E_CPU0_PE3_OCP_RXN<13>") )
				( member ( signalRef "P3E_CPU0_PE3_OCP_RXN<14>") )
				( member ( signalRef "P3E_CPU0_PE3_OCP_RXN<15>") )
				( objectStatus "@baseboard_fab2_lib.baseboard_fab2(sch_1):p3e_cpu0_pe3_ocp_rxn" )
			)
			( bus "P3E_CPU0_PE3_OCP_RXP"
				( memberType ( signal ) )
				( member ( signalRef "P3E_CPU0_PE3_OCP_RXP<0>") )
				( member ( signalRef "P3E_CPU0_PE3_OCP_RXP<1>") )
				( member ( signalRef "P3E_CPU0_PE3_OCP_RXP<2>") )
				( member ( signalRef "P3E_CPU0_PE3_OCP_RXP<3>") )
				( member ( signalRef "P3E_CPU0_PE3_OCP_RXP<4>") )
				( member ( signalRef "P3E_CPU0_PE3_OCP_RXP<5>") )
				( member ( signalRef "P3E_CPU0_PE3_OCP_RXP<6>") )
				( member ( signalRef "P3E_CPU0_PE3_OCP_RXP<7>") )
				( member ( signalRef "P3E_CPU0_PE3_OCP_RXP<8>") )
				( member ( signalRef "P3E_CPU0_PE3_OCP_RXP<9>") )
				( member ( signalRef "P3E_CPU0_PE3_OCP_RXP<10>") )
				( member ( signalRef "P3E_CPU0_PE3_OCP_RXP<11>") )
				( member ( signalRef "P3E_CPU0_PE3_OCP_RXP<12>") )
				( member ( signalRef "P3E_CPU0_PE3_OCP_RXP<13>") )
				( member ( signalRef "P3E_CPU0_PE3_OCP_RXP<14>") )
				( member ( signalRef "P3E_CPU0_PE3_OCP_RXP<15>") )
				( objectStatus "@baseboard_fab2_lib.baseboard_fab2(sch_1):p3e_cpu0_pe3_ocp_rxp" )
			)
			( bus "P3E_CPU0_PE3_OCP_TXN"
				( memberType ( signal ) )
				( member ( signalRef "P3E_CPU0_PE3_OCP_TXN<0>") )
				( member ( signalRef "P3E_CPU0_PE3_OCP_TXN<1>") )
				( member ( signalRef "P3E_CPU0_PE3_OCP_TXN<2>") )
				( member ( signalRef "P3E_CPU0_PE3_OCP_TXN<3>") )
				( member ( signalRef "P3E_CPU0_PE3_OCP_TXN<4>") )
				( member ( signalRef "P3E_CPU0_PE3_OCP_TXN<5>") )
				( member ( signalRef "P3E_CPU0_PE3_OCP_TXN<6>") )
				( member ( signalRef "P3E_CPU0_PE3_OCP_TXN<7>") )
				( member ( signalRef "P3E_CPU0_PE3_OCP_TXN<8>") )
				( member ( signalRef "P3E_CPU0_PE3_OCP_TXN<9>") )
				( member ( signalRef "P3E_CPU0_PE3_OCP_TXN<10>") )
				( member ( signalRef "P3E_CPU0_PE3_OCP_TXN<11>") )
				( member ( signalRef "P3E_CPU0_PE3_OCP_TXN<12>") )
				( member ( signalRef "P3E_CPU0_PE3_OCP_TXN<13>") )
				( member ( signalRef "P3E_CPU0_PE3_OCP_TXN<14>") )
				( member ( signalRef "P3E_CPU0_PE3_OCP_TXN<15>") )
				( objectStatus "@baseboard_fab2_lib.baseboard_fab2(sch_1):p3e_cpu0_pe3_ocp_txn" )
			)
			( bus "P3E_CPU0_PE3_OCP_TXP"
				( memberType ( signal ) )
				( member ( signalRef "P3E_CPU0_PE3_OCP_TXP<0>") )
				( member ( signalRef "P3E_CPU0_PE3_OCP_TXP<1>") )
				( member ( signalRef "P3E_CPU0_PE3_OCP_TXP<2>") )
				( member ( signalRef "P3E_CPU0_PE3_OCP_TXP<3>") )
				( member ( signalRef "P3E_CPU0_PE3_OCP_TXP<4>") )
				( member ( signalRef "P3E_CPU0_PE3_OCP_TXP<5>") )
				( member ( signalRef "P3E_CPU0_PE3_OCP_TXP<6>") )
				( member ( signalRef "P3E_CPU0_PE3_OCP_TXP<7>") )
				( member ( signalRef "P3E_CPU0_PE3_OCP_TXP<8>") )
				( member ( signalRef "P3E_CPU0_PE3_OCP_TXP<9>") )
				( member ( signalRef "P3E_CPU0_PE3_OCP_TXP<10>") )
				( member ( signalRef "P3E_CPU0_PE3_OCP_TXP<11>") )
				( member ( signalRef "P3E_CPU0_PE3_OCP_TXP<12>") )
				( member ( signalRef "P3E_CPU0_PE3_OCP_TXP<13>") )
				( member ( signalRef "P3E_CPU0_PE3_OCP_TXP<14>") )
				( member ( signalRef "P3E_CPU0_PE3_OCP_TXP<15>") )
				( objectStatus "@baseboard_fab2_lib.baseboard_fab2(sch_1):p3e_cpu0_pe3_ocp_txp" )
			)
			( bus "UPI_CPU0_CPU1_P0P0_DN"
				( memberType ( signal ) )
				( member ( signalRef "UPI_CPU0_CPU1_P0P0_DN<0>") )
				( member ( signalRef "UPI_CPU0_CPU1_P0P0_DN<1>") )
				( member ( signalRef "UPI_CPU0_CPU1_P0P0_DN<2>") )
				( member ( signalRef "UPI_CPU0_CPU1_P0P0_DN<3>") )
				( member ( signalRef "UPI_CPU0_CPU1_P0P0_DN<4>") )
				( member ( signalRef "UPI_CPU0_CPU1_P0P0_DN<5>") )
				( member ( signalRef "UPI_CPU0_CPU1_P0P0_DN<6>") )
				( member ( signalRef "UPI_CPU0_CPU1_P0P0_DN<7>") )
				( member ( signalRef "UPI_CPU0_CPU1_P0P0_DN<8>") )
				( member ( signalRef "UPI_CPU0_CPU1_P0P0_DN<9>") )
				( member ( signalRef "UPI_CPU0_CPU1_P0P0_DN<10>") )
				( member ( signalRef "UPI_CPU0_CPU1_P0P0_DN<11>") )
				( member ( signalRef "UPI_CPU0_CPU1_P0P0_DN<12>") )
				( member ( signalRef "UPI_CPU0_CPU1_P0P0_DN<13>") )
				( member ( signalRef "UPI_CPU0_CPU1_P0P0_DN<14>") )
				( member ( signalRef "UPI_CPU0_CPU1_P0P0_DN<15>") )
				( member ( signalRef "UPI_CPU0_CPU1_P0P0_DN<16>") )
				( member ( signalRef "UPI_CPU0_CPU1_P0P0_DN<17>") )
				( member ( signalRef "UPI_CPU0_CPU1_P0P0_DN<18>") )
				( member ( signalRef "UPI_CPU0_CPU1_P0P0_DN<19>") )
				( objectStatus "@baseboard_fab2_lib.baseboard_fab2(sch_1):upi_cpu0_cpu1_p0p0_dn" )
			)
			( bus "UPI_CPU0_CPU1_P0P0_DP"
				( memberType ( signal ) )
				( member ( signalRef "UPI_CPU0_CPU1_P0P0_DP<0>") )
				( member ( signalRef "UPI_CPU0_CPU1_P0P0_DP<1>") )
				( member ( signalRef "UPI_CPU0_CPU1_P0P0_DP<2>") )
				( member ( signalRef "UPI_CPU0_CPU1_P0P0_DP<3>") )
				( member ( signalRef "UPI_CPU0_CPU1_P0P0_DP<4>") )
				( member ( signalRef "UPI_CPU0_CPU1_P0P0_DP<5>") )
				( member ( signalRef "UPI_CPU0_CPU1_P0P0_DP<6>") )
				( member ( signalRef "UPI_CPU0_CPU1_P0P0_DP<7>") )
				( member ( signalRef "UPI_CPU0_CPU1_P0P0_DP<8>") )
				( member ( signalRef "UPI_CPU0_CPU1_P0P0_DP<9>") )
				( member ( signalRef "UPI_CPU0_CPU1_P0P0_DP<10>") )
				( member ( signalRef "UPI_CPU0_CPU1_P0P0_DP<11>") )
				( member ( signalRef "UPI_CPU0_CPU1_P0P0_DP<12>") )
				( member ( signalRef "UPI_CPU0_CPU1_P0P0_DP<13>") )
				( member ( signalRef "UPI_CPU0_CPU1_P0P0_DP<14>") )
				( member ( signalRef "UPI_CPU0_CPU1_P0P0_DP<15>") )
				( member ( signalRef "UPI_CPU0_CPU1_P0P0_DP<16>") )
				( member ( signalRef "UPI_CPU0_CPU1_P0P0_DP<17>") )
				( member ( signalRef "UPI_CPU0_CPU1_P0P0_DP<18>") )
				( member ( signalRef "UPI_CPU0_CPU1_P0P0_DP<19>") )
				( objectStatus "@baseboard_fab2_lib.baseboard_fab2(sch_1):upi_cpu0_cpu1_p0p0_dp" )
			)
			( bus "UPI_CPU1_CPU0_P0P0_DN"
				( memberType ( signal ) )
				( member ( signalRef "UPI_CPU1_CPU0_P0P0_DN<0>") )
				( member ( signalRef "UPI_CPU1_CPU0_P0P0_DN<1>") )
				( member ( signalRef "UPI_CPU1_CPU0_P0P0_DN<2>") )
				( member ( signalRef "UPI_CPU1_CPU0_P0P0_DN<3>") )
				( member ( signalRef "UPI_CPU1_CPU0_P0P0_DN<4>") )
				( member ( signalRef "UPI_CPU1_CPU0_P0P0_DN<5>") )
				( member ( signalRef "UPI_CPU1_CPU0_P0P0_DN<6>") )
				( member ( signalRef "UPI_CPU1_CPU0_P0P0_DN<7>") )
				( member ( signalRef "UPI_CPU1_CPU0_P0P0_DN<8>") )
				( member ( signalRef "UPI_CPU1_CPU0_P0P0_DN<9>") )
				( member ( signalRef "UPI_CPU1_CPU0_P0P0_DN<10>") )
				( member ( signalRef "UPI_CPU1_CPU0_P0P0_DN<11>") )
				( member ( signalRef "UPI_CPU1_CPU0_P0P0_DN<12>") )
				( member ( signalRef "UPI_CPU1_CPU0_P0P0_DN<13>") )
				( member ( signalRef "UPI_CPU1_CPU0_P0P0_DN<14>") )
				( member ( signalRef "UPI_CPU1_CPU0_P0P0_DN<15>") )
				( member ( signalRef "UPI_CPU1_CPU0_P0P0_DN<16>") )
				( member ( signalRef "UPI_CPU1_CPU0_P0P0_DN<17>") )
				( member ( signalRef "UPI_CPU1_CPU0_P0P0_DN<18>") )
				( member ( signalRef "UPI_CPU1_CPU0_P0P0_DN<19>") )
				( objectStatus "@baseboard_fab2_lib.baseboard_fab2(sch_1):upi_cpu1_cpu0_p0p0_dn" )
			)
			( bus "UPI_CPU1_CPU0_P0P0_DP"
				( memberType ( signal ) )
				( member ( signalRef "UPI_CPU1_CPU0_P0P0_DP<0>") )
				( member ( signalRef "UPI_CPU1_CPU0_P0P0_DP<1>") )
				( member ( signalRef "UPI_CPU1_CPU0_P0P0_DP<2>") )
				( member ( signalRef "UPI_CPU1_CPU0_P0P0_DP<3>") )
				( member ( signalRef "UPI_CPU1_CPU0_P0P0_DP<4>") )
				( member ( signalRef "UPI_CPU1_CPU0_P0P0_DP<5>") )
				( member ( signalRef "UPI_CPU1_CPU0_P0P0_DP<6>") )
				( member ( signalRef "UPI_CPU1_CPU0_P0P0_DP<7>") )
				( member ( signalRef "UPI_CPU1_CPU0_P0P0_DP<8>") )
				( member ( signalRef "UPI_CPU1_CPU0_P0P0_DP<9>") )
				( member ( signalRef "UPI_CPU1_CPU0_P0P0_DP<10>") )
				( member ( signalRef "UPI_CPU1_CPU0_P0P0_DP<11>") )
				( member ( signalRef "UPI_CPU1_CPU0_P0P0_DP<12>") )
				( member ( signalRef "UPI_CPU1_CPU0_P0P0_DP<13>") )
				( member ( signalRef "UPI_CPU1_CPU0_P0P0_DP<14>") )
				( member ( signalRef "UPI_CPU1_CPU0_P0P0_DP<15>") )
				( member ( signalRef "UPI_CPU1_CPU0_P0P0_DP<16>") )
				( member ( signalRef "UPI_CPU1_CPU0_P0P0_DP<17>") )
				( member ( signalRef "UPI_CPU1_CPU0_P0P0_DP<18>") )
				( member ( signalRef "UPI_CPU1_CPU0_P0P0_DP<19>") )
				( objectStatus "@baseboard_fab2_lib.baseboard_fab2(sch_1):upi_cpu1_cpu0_p0p0_dp" )
			)
			( bus "UPI_CPU0_CPU1_P1P1_DN"
				( memberType ( signal ) )
				( member ( signalRef "UPI_CPU0_CPU1_P1P1_DN<0>") )
				( member ( signalRef "UPI_CPU0_CPU1_P1P1_DN<1>") )
				( member ( signalRef "UPI_CPU0_CPU1_P1P1_DN<2>") )
				( member ( signalRef "UPI_CPU0_CPU1_P1P1_DN<3>") )
				( member ( signalRef "UPI_CPU0_CPU1_P1P1_DN<4>") )
				( member ( signalRef "UPI_CPU0_CPU1_P1P1_DN<5>") )
				( member ( signalRef "UPI_CPU0_CPU1_P1P1_DN<6>") )
				( member ( signalRef "UPI_CPU0_CPU1_P1P1_DN<7>") )
				( member ( signalRef "UPI_CPU0_CPU1_P1P1_DN<8>") )
				( member ( signalRef "UPI_CPU0_CPU1_P1P1_DN<9>") )
				( member ( signalRef "UPI_CPU0_CPU1_P1P1_DN<10>") )
				( member ( signalRef "UPI_CPU0_CPU1_P1P1_DN<11>") )
				( member ( signalRef "UPI_CPU0_CPU1_P1P1_DN<12>") )
				( member ( signalRef "UPI_CPU0_CPU1_P1P1_DN<13>") )
				( member ( signalRef "UPI_CPU0_CPU1_P1P1_DN<14>") )
				( member ( signalRef "UPI_CPU0_CPU1_P1P1_DN<15>") )
				( member ( signalRef "UPI_CPU0_CPU1_P1P1_DN<16>") )
				( member ( signalRef "UPI_CPU0_CPU1_P1P1_DN<17>") )
				( member ( signalRef "UPI_CPU0_CPU1_P1P1_DN<18>") )
				( member ( signalRef "UPI_CPU0_CPU1_P1P1_DN<19>") )
				( objectStatus "@baseboard_fab2_lib.baseboard_fab2(sch_1):upi_cpu0_cpu1_p1p1_dn" )
			)
			( bus "UPI_CPU0_CPU1_P1P1_DP"
				( memberType ( signal ) )
				( member ( signalRef "UPI_CPU0_CPU1_P1P1_DP<0>") )
				( member ( signalRef "UPI_CPU0_CPU1_P1P1_DP<1>") )
				( member ( signalRef "UPI_CPU0_CPU1_P1P1_DP<2>") )
				( member ( signalRef "UPI_CPU0_CPU1_P1P1_DP<3>") )
				( member ( signalRef "UPI_CPU0_CPU1_P1P1_DP<4>") )
				( member ( signalRef "UPI_CPU0_CPU1_P1P1_DP<5>") )
				( member ( signalRef "UPI_CPU0_CPU1_P1P1_DP<6>") )
				( member ( signalRef "UPI_CPU0_CPU1_P1P1_DP<7>") )
				( member ( signalRef "UPI_CPU0_CPU1_P1P1_DP<8>") )
				( member ( signalRef "UPI_CPU0_CPU1_P1P1_DP<9>") )
				( member ( signalRef "UPI_CPU0_CPU1_P1P1_DP<10>") )
				( member ( signalRef "UPI_CPU0_CPU1_P1P1_DP<11>") )
				( member ( signalRef "UPI_CPU0_CPU1_P1P1_DP<12>") )
				( member ( signalRef "UPI_CPU0_CPU1_P1P1_DP<13>") )
				( member ( signalRef "UPI_CPU0_CPU1_P1P1_DP<14>") )
				( member ( signalRef "UPI_CPU0_CPU1_P1P1_DP<15>") )
				( member ( signalRef "UPI_CPU0_CPU1_P1P1_DP<16>") )
				( member ( signalRef "UPI_CPU0_CPU1_P1P1_DP<17>") )
				( member ( signalRef "UPI_CPU0_CPU1_P1P1_DP<18>") )
				( member ( signalRef "UPI_CPU0_CPU1_P1P1_DP<19>") )
				( objectStatus "@baseboard_fab2_lib.baseboard_fab2(sch_1):upi_cpu0_cpu1_p1p1_dp" )
			)
			( bus "UPI_CPU1_CPU0_P1P1_DN"
				( memberType ( signal ) )
				( member ( signalRef "UPI_CPU1_CPU0_P1P1_DN<0>") )
				( member ( signalRef "UPI_CPU1_CPU0_P1P1_DN<1>") )
				( member ( signalRef "UPI_CPU1_CPU0_P1P1_DN<2>") )
				( member ( signalRef "UPI_CPU1_CPU0_P1P1_DN<3>") )
				( member ( signalRef "UPI_CPU1_CPU0_P1P1_DN<4>") )
				( member ( signalRef "UPI_CPU1_CPU0_P1P1_DN<5>") )
				( member ( signalRef "UPI_CPU1_CPU0_P1P1_DN<6>") )
				( member ( signalRef "UPI_CPU1_CPU0_P1P1_DN<7>") )
				( member ( signalRef "UPI_CPU1_CPU0_P1P1_DN<8>") )
				( member ( signalRef "UPI_CPU1_CPU0_P1P1_DN<9>") )
				( member ( signalRef "UPI_CPU1_CPU0_P1P1_DN<10>") )
				( member ( signalRef "UPI_CPU1_CPU0_P1P1_DN<11>") )
				( member ( signalRef "UPI_CPU1_CPU0_P1P1_DN<12>") )
				( member ( signalRef "UPI_CPU1_CPU0_P1P1_DN<13>") )
				( member ( signalRef "UPI_CPU1_CPU0_P1P1_DN<14>") )
				( member ( signalRef "UPI_CPU1_CPU0_P1P1_DN<15>") )
				( member ( signalRef "UPI_CPU1_CPU0_P1P1_DN<16>") )
				( member ( signalRef "UPI_CPU1_CPU0_P1P1_DN<17>") )
				( member ( signalRef "UPI_CPU1_CPU0_P1P1_DN<18>") )
				( member ( signalRef "UPI_CPU1_CPU0_P1P1_DN<19>") )
				( objectStatus "@baseboard_fab2_lib.baseboard_fab2(sch_1):upi_cpu1_cpu0_p1p1_dn" )
			)
			( bus "UPI_CPU1_CPU0_P1P1_DP"
				( memberType ( signal ) )
				( member ( signalRef "UPI_CPU1_CPU0_P1P1_DP<0>") )
				( member ( signalRef "UPI_CPU1_CPU0_P1P1_DP<1>") )
				( member ( signalRef "UPI_CPU1_CPU0_P1P1_DP<2>") )
				( member ( signalRef "UPI_CPU1_CPU0_P1P1_DP<3>") )
				( member ( signalRef "UPI_CPU1_CPU0_P1P1_DP<4>") )
				( member ( signalRef "UPI_CPU1_CPU0_P1P1_DP<5>") )
				( member ( signalRef "UPI_CPU1_CPU0_P1P1_DP<6>") )
				( member ( signalRef "UPI_CPU1_CPU0_P1P1_DP<7>") )
				( member ( signalRef "UPI_CPU1_CPU0_P1P1_DP<8>") )
				( member ( signalRef "UPI_CPU1_CPU0_P1P1_DP<9>") )
				( member ( signalRef "UPI_CPU1_CPU0_P1P1_DP<10>") )
				( member ( signalRef "UPI_CPU1_CPU0_P1P1_DP<11>") )
				( member ( signalRef "UPI_CPU1_CPU0_P1P1_DP<12>") )
				( member ( signalRef "UPI_CPU1_CPU0_P1P1_DP<13>") )
				( member ( signalRef "UPI_CPU1_CPU0_P1P1_DP<14>") )
				( member ( signalRef "UPI_CPU1_CPU0_P1P1_DP<15>") )
				( member ( signalRef "UPI_CPU1_CPU0_P1P1_DP<16>") )
				( member ( signalRef "UPI_CPU1_CPU0_P1P1_DP<17>") )
				( member ( signalRef "UPI_CPU1_CPU0_P1P1_DP<18>") )
				( member ( signalRef "UPI_CPU1_CPU0_P1P1_DP<19>") )
				( objectStatus "@baseboard_fab2_lib.baseboard_fab2(sch_1):upi_cpu1_cpu0_p1p1_dp" )
			)
			( bus "M_G_BA"
				( memberType ( signal ) )
				( member ( signalRef "M_G_BA<0>") )
				( member ( signalRef "M_G_BA<1>") )
				( objectStatus "@baseboard_fab2_lib.baseboard_fab2(sch_1):m_g_ba" )
			)
			( bus "M_G_BG"
				( memberType ( signal ) )
				( member ( signalRef "M_G_BG<0>") )
				( member ( signalRef "M_G_BG<1>") )
				( objectStatus "@baseboard_fab2_lib.baseboard_fab2(sch_1):m_g_bg" )
			)
			( bus "M_G_C"
				( memberType ( signal ) )
				( member ( signalRef "M_G_C<2>") )
				( objectStatus "@baseboard_fab2_lib.baseboard_fab2(sch_1):m_g_c" )
			)
			( bus "M_G_CKE"
				( memberType ( signal ) )
				( member ( signalRef "M_G_CKE<0>") )
				( member ( signalRef "M_G_CKE<1>") )
				( member ( signalRef "M_G_CKE<2>") )
				( member ( signalRef "M_G_CKE<3>") )
				( objectStatus "@baseboard_fab2_lib.baseboard_fab2(sch_1):m_g_cke" )
			)
			( bus "M_G_CLK_DN"
				( memberType ( signal ) )
				( member ( signalRef "M_G_CLK_DN<0>") )
				( member ( signalRef "M_G_CLK_DN<1>") )
				( member ( signalRef "M_G_CLK_DN<2>") )
				( member ( signalRef "M_G_CLK_DN<3>") )
				( objectStatus "@baseboard_fab2_lib.baseboard_fab2(sch_1):m_g_clk_dn" )
			)
			( bus "M_G_CLK_DP"
				( memberType ( signal ) )
				( member ( signalRef "M_G_CLK_DP<0>") )
				( member ( signalRef "M_G_CLK_DP<1>") )
				( member ( signalRef "M_G_CLK_DP<2>") )
				( member ( signalRef "M_G_CLK_DP<3>") )
				( objectStatus "@baseboard_fab2_lib.baseboard_fab2(sch_1):m_g_clk_dp" )
			)
			( bus "M_G_CS_N"
				( memberType ( signal ) )
				( member ( signalRef "M_G_CS_N<0>") )
				( member ( signalRef "M_G_CS_N<1>") )
				( member ( signalRef "M_G_CS_N<2>") )
				( member ( signalRef "M_G_CS_N<3>") )
				( member ( signalRef "M_G_CS_N<4>") )
				( member ( signalRef "M_G_CS_N<5>") )
				( member ( signalRef "M_G_CS_N<6>") )
				( member ( signalRef "M_G_CS_N<7>") )
				( objectStatus "@baseboard_fab2_lib.baseboard_fab2(sch_1):m_g_cs_n" )
			)
			( bus "M_G_DQ"
				( memberType ( signal ) )
				( member ( signalRef "M_G_DQ<0>") )
				( member ( signalRef "M_G_DQ<1>") )
				( member ( signalRef "M_G_DQ<2>") )
				( member ( signalRef "M_G_DQ<3>") )
				( member ( signalRef "M_G_DQ<4>") )
				( member ( signalRef "M_G_DQ<5>") )
				( member ( signalRef "M_G_DQ<6>") )
				( member ( signalRef "M_G_DQ<7>") )
				( member ( signalRef "M_G_DQ<8>") )
				( member ( signalRef "M_G_DQ<9>") )
				( member ( signalRef "M_G_DQ<10>") )
				( member ( signalRef "M_G_DQ<11>") )
				( member ( signalRef "M_G_DQ<12>") )
				( member ( signalRef "M_G_DQ<13>") )
				( member ( signalRef "M_G_DQ<14>") )
				( member ( signalRef "M_G_DQ<15>") )
				( member ( signalRef "M_G_DQ<16>") )
				( member ( signalRef "M_G_DQ<17>") )
				( member ( signalRef "M_G_DQ<18>") )
				( member ( signalRef "M_G_DQ<19>") )
				( member ( signalRef "M_G_DQ<20>") )
				( member ( signalRef "M_G_DQ<21>") )
				( member ( signalRef "M_G_DQ<22>") )
				( member ( signalRef "M_G_DQ<23>") )
				( member ( signalRef "M_G_DQ<24>") )
				( member ( signalRef "M_G_DQ<25>") )
				( member ( signalRef "M_G_DQ<26>") )
				( member ( signalRef "M_G_DQ<27>") )
				( member ( signalRef "M_G_DQ<28>") )
				( member ( signalRef "M_G_DQ<29>") )
				( member ( signalRef "M_G_DQ<30>") )
				( member ( signalRef "M_G_DQ<31>") )
				( member ( signalRef "M_G_DQ<32>") )
				( member ( signalRef "M_G_DQ<33>") )
				( member ( signalRef "M_G_DQ<34>") )
				( member ( signalRef "M_G_DQ<35>") )
				( member ( signalRef "M_G_DQ<36>") )
				( member ( signalRef "M_G_DQ<37>") )
				( member ( signalRef "M_G_DQ<38>") )
				( member ( signalRef "M_G_DQ<39>") )
				( member ( signalRef "M_G_DQ<40>") )
				( member ( signalRef "M_G_DQ<41>") )
				( member ( signalRef "M_G_DQ<42>") )
				( member ( signalRef "M_G_DQ<43>") )
				( member ( signalRef "M_G_DQ<44>") )
				( member ( signalRef "M_G_DQ<45>") )
				( member ( signalRef "M_G_DQ<46>") )
				( member ( signalRef "M_G_DQ<47>") )
				( member ( signalRef "M_G_DQ<48>") )
				( member ( signalRef "M_G_DQ<49>") )
				( member ( signalRef "M_G_DQ<50>") )
				( member ( signalRef "M_G_DQ<51>") )
				( member ( signalRef "M_G_DQ<52>") )
				( member ( signalRef "M_G_DQ<53>") )
				( member ( signalRef "M_G_DQ<54>") )
				( member ( signalRef "M_G_DQ<55>") )
				( member ( signalRef "M_G_DQ<56>") )
				( member ( signalRef "M_G_DQ<57>") )
				( member ( signalRef "M_G_DQ<58>") )
				( member ( signalRef "M_G_DQ<59>") )
				( member ( signalRef "M_G_DQ<60>") )
				( member ( signalRef "M_G_DQ<61>") )
				( member ( signalRef "M_G_DQ<62>") )
				( member ( signalRef "M_G_DQ<63>") )
				( objectStatus "@baseboard_fab2_lib.baseboard_fab2(sch_1):m_g_dq" )
			)
			( bus "M_G_DQS_DN"
				( memberType ( signal ) )
				( member ( signalRef "M_G_DQS_DN<0>") )
				( member ( signalRef "M_G_DQS_DN<1>") )
				( member ( signalRef "M_G_DQS_DN<2>") )
				( member ( signalRef "M_G_DQS_DN<3>") )
				( member ( signalRef "M_G_DQS_DN<4>") )
				( member ( signalRef "M_G_DQS_DN<5>") )
				( member ( signalRef "M_G_DQS_DN<6>") )
				( member ( signalRef "M_G_DQS_DN<7>") )
				( member ( signalRef "M_G_DQS_DN<8>") )
				( member ( signalRef "M_G_DQS_DN<9>") )
				( member ( signalRef "M_G_DQS_DN<10>") )
				( member ( signalRef "M_G_DQS_DN<11>") )
				( member ( signalRef "M_G_DQS_DN<12>") )
				( member ( signalRef "M_G_DQS_DN<13>") )
				( member ( signalRef "M_G_DQS_DN<14>") )
				( member ( signalRef "M_G_DQS_DN<15>") )
				( member ( signalRef "M_G_DQS_DN<16>") )
				( member ( signalRef "M_G_DQS_DN<17>") )
				( objectStatus "@baseboard_fab2_lib.baseboard_fab2(sch_1):m_g_dqs_dn" )
			)
			( bus "M_G_DQS_DP"
				( memberType ( signal ) )
				( member ( signalRef "M_G_DQS_DP<0>") )
				( member ( signalRef "M_G_DQS_DP<1>") )
				( member ( signalRef "M_G_DQS_DP<2>") )
				( member ( signalRef "M_G_DQS_DP<3>") )
				( member ( signalRef "M_G_DQS_DP<4>") )
				( member ( signalRef "M_G_DQS_DP<5>") )
				( member ( signalRef "M_G_DQS_DP<6>") )
				( member ( signalRef "M_G_DQS_DP<7>") )
				( member ( signalRef "M_G_DQS_DP<8>") )
				( member ( signalRef "M_G_DQS_DP<9>") )
				( member ( signalRef "M_G_DQS_DP<10>") )
				( member ( signalRef "M_G_DQS_DP<11>") )
				( member ( signalRef "M_G_DQS_DP<12>") )
				( member ( signalRef "M_G_DQS_DP<13>") )
				( member ( signalRef "M_G_DQS_DP<14>") )
				( member ( signalRef "M_G_DQS_DP<15>") )
				( member ( signalRef "M_G_DQS_DP<16>") )
				( member ( signalRef "M_G_DQS_DP<17>") )
				( objectStatus "@baseboard_fab2_lib.baseboard_fab2(sch_1):m_g_dqs_dp" )
			)
			( bus "M_G_ECC"
				( memberType ( signal ) )
				( member ( signalRef "M_G_ECC<0>") )
				( member ( signalRef "M_G_ECC<1>") )
				( member ( signalRef "M_G_ECC<2>") )
				( member ( signalRef "M_G_ECC<3>") )
				( member ( signalRef "M_G_ECC<4>") )
				( member ( signalRef "M_G_ECC<5>") )
				( member ( signalRef "M_G_ECC<6>") )
				( member ( signalRef "M_G_ECC<7>") )
				( objectStatus "@baseboard_fab2_lib.baseboard_fab2(sch_1):m_g_ecc" )
			)
			( bus "M_G_MA"
				( memberType ( signal ) )
				( member ( signalRef "M_G_MA<0>") )
				( member ( signalRef "M_G_MA<1>") )
				( member ( signalRef "M_G_MA<2>") )
				( member ( signalRef "M_G_MA<3>") )
				( member ( signalRef "M_G_MA<4>") )
				( member ( signalRef "M_G_MA<5>") )
				( member ( signalRef "M_G_MA<6>") )
				( member ( signalRef "M_G_MA<7>") )
				( member ( signalRef "M_G_MA<8>") )
				( member ( signalRef "M_G_MA<9>") )
				( member ( signalRef "M_G_MA<10>") )
				( member ( signalRef "M_G_MA<11>") )
				( member ( signalRef "M_G_MA<12>") )
				( member ( signalRef "M_G_MA<13>") )
				( member ( signalRef "M_G_MA<14>") )
				( member ( signalRef "M_G_MA<15>") )
				( member ( signalRef "M_G_MA<16>") )
				( member ( signalRef "M_G_MA<17>") )
				( objectStatus "@baseboard_fab2_lib.baseboard_fab2(sch_1):m_g_ma" )
			)
			( bus "M_G_ODT"
				( memberType ( signal ) )
				( member ( signalRef "M_G_ODT<0>") )
				( member ( signalRef "M_G_ODT<1>") )
				( member ( signalRef "M_G_ODT<2>") )
				( member ( signalRef "M_G_ODT<3>") )
				( objectStatus "@baseboard_fab2_lib.baseboard_fab2(sch_1):m_g_odt" )
			)
			( bus "M_H_BA"
				( memberType ( signal ) )
				( member ( signalRef "M_H_BA<0>") )
				( member ( signalRef "M_H_BA<1>") )
				( objectStatus "@baseboard_fab2_lib.baseboard_fab2(sch_1):m_h_ba" )
			)
			( bus "M_H_BG"
				( memberType ( signal ) )
				( member ( signalRef "M_H_BG<0>") )
				( member ( signalRef "M_H_BG<1>") )
				( objectStatus "@baseboard_fab2_lib.baseboard_fab2(sch_1):m_h_bg" )
			)
			( bus "M_H_C"
				( memberType ( signal ) )
				( member ( signalRef "M_H_C<2>") )
				( objectStatus "@baseboard_fab2_lib.baseboard_fab2(sch_1):m_h_c" )
			)
			( bus "M_H_CKE"
				( memberType ( signal ) )
				( member ( signalRef "M_H_CKE<0>") )
				( member ( signalRef "M_H_CKE<1>") )
				( member ( signalRef "M_H_CKE<2>") )
				( member ( signalRef "M_H_CKE<3>") )
				( objectStatus "@baseboard_fab2_lib.baseboard_fab2(sch_1):m_h_cke" )
			)
			( bus "M_H_CLK_DN"
				( memberType ( signal ) )
				( member ( signalRef "M_H_CLK_DN<0>") )
				( member ( signalRef "M_H_CLK_DN<1>") )
				( member ( signalRef "M_H_CLK_DN<2>") )
				( member ( signalRef "M_H_CLK_DN<3>") )
				( objectStatus "@baseboard_fab2_lib.baseboard_fab2(sch_1):m_h_clk_dn" )
			)
			( bus "M_H_CLK_DP"
				( memberType ( signal ) )
				( member ( signalRef "M_H_CLK_DP<0>") )
				( member ( signalRef "M_H_CLK_DP<1>") )
				( member ( signalRef "M_H_CLK_DP<2>") )
				( member ( signalRef "M_H_CLK_DP<3>") )
				( objectStatus "@baseboard_fab2_lib.baseboard_fab2(sch_1):m_h_clk_dp" )
			)
			( bus "M_H_CS_N"
				( memberType ( signal ) )
				( member ( signalRef "M_H_CS_N<0>") )
				( member ( signalRef "M_H_CS_N<1>") )
				( member ( signalRef "M_H_CS_N<2>") )
				( member ( signalRef "M_H_CS_N<3>") )
				( member ( signalRef "M_H_CS_N<4>") )
				( member ( signalRef "M_H_CS_N<5>") )
				( member ( signalRef "M_H_CS_N<6>") )
				( member ( signalRef "M_H_CS_N<7>") )
				( objectStatus "@baseboard_fab2_lib.baseboard_fab2(sch_1):m_h_cs_n" )
			)
			( bus "M_H_DQ"
				( memberType ( signal ) )
				( member ( signalRef "M_H_DQ<0>") )
				( member ( signalRef "M_H_DQ<1>") )
				( member ( signalRef "M_H_DQ<2>") )
				( member ( signalRef "M_H_DQ<3>") )
				( member ( signalRef "M_H_DQ<4>") )
				( member ( signalRef "M_H_DQ<5>") )
				( member ( signalRef "M_H_DQ<6>") )
				( member ( signalRef "M_H_DQ<7>") )
				( member ( signalRef "M_H_DQ<8>") )
				( member ( signalRef "M_H_DQ<9>") )
				( member ( signalRef "M_H_DQ<10>") )
				( member ( signalRef "M_H_DQ<11>") )
				( member ( signalRef "M_H_DQ<12>") )
				( member ( signalRef "M_H_DQ<13>") )
				( member ( signalRef "M_H_DQ<14>") )
				( member ( signalRef "M_H_DQ<15>") )
				( member ( signalRef "M_H_DQ<16>") )
				( member ( signalRef "M_H_DQ<17>") )
				( member ( signalRef "M_H_DQ<18>") )
				( member ( signalRef "M_H_DQ<19>") )
				( member ( signalRef "M_H_DQ<20>") )
				( member ( signalRef "M_H_DQ<21>") )
				( member ( signalRef "M_H_DQ<22>") )
				( member ( signalRef "M_H_DQ<23>") )
				( member ( signalRef "M_H_DQ<24>") )
				( member ( signalRef "M_H_DQ<25>") )
				( member ( signalRef "M_H_DQ<26>") )
				( member ( signalRef "M_H_DQ<27>") )
				( member ( signalRef "M_H_DQ<28>") )
				( member ( signalRef "M_H_DQ<29>") )
				( member ( signalRef "M_H_DQ<30>") )
				( member ( signalRef "M_H_DQ<31>") )
				( member ( signalRef "M_H_DQ<32>") )
				( member ( signalRef "M_H_DQ<33>") )
				( member ( signalRef "M_H_DQ<34>") )
				( member ( signalRef "M_H_DQ<35>") )
				( member ( signalRef "M_H_DQ<36>") )
				( member ( signalRef "M_H_DQ<37>") )
				( member ( signalRef "M_H_DQ<38>") )
				( member ( signalRef "M_H_DQ<39>") )
				( member ( signalRef "M_H_DQ<40>") )
				( member ( signalRef "M_H_DQ<41>") )
				( member ( signalRef "M_H_DQ<42>") )
				( member ( signalRef "M_H_DQ<43>") )
				( member ( signalRef "M_H_DQ<44>") )
				( member ( signalRef "M_H_DQ<45>") )
				( member ( signalRef "M_H_DQ<46>") )
				( member ( signalRef "M_H_DQ<47>") )
				( member ( signalRef "M_H_DQ<48>") )
				( member ( signalRef "M_H_DQ<49>") )
				( member ( signalRef "M_H_DQ<50>") )
				( member ( signalRef "M_H_DQ<51>") )
				( member ( signalRef "M_H_DQ<52>") )
				( member ( signalRef "M_H_DQ<53>") )
				( member ( signalRef "M_H_DQ<54>") )
				( member ( signalRef "M_H_DQ<55>") )
				( member ( signalRef "M_H_DQ<56>") )
				( member ( signalRef "M_H_DQ<57>") )
				( member ( signalRef "M_H_DQ<58>") )
				( member ( signalRef "M_H_DQ<59>") )
				( member ( signalRef "M_H_DQ<60>") )
				( member ( signalRef "M_H_DQ<61>") )
				( member ( signalRef "M_H_DQ<62>") )
				( member ( signalRef "M_H_DQ<63>") )
				( objectStatus "@baseboard_fab2_lib.baseboard_fab2(sch_1):m_h_dq" )
			)
			( bus "M_H_DQS_DN"
				( memberType ( signal ) )
				( member ( signalRef "M_H_DQS_DN<0>") )
				( member ( signalRef "M_H_DQS_DN<1>") )
				( member ( signalRef "M_H_DQS_DN<2>") )
				( member ( signalRef "M_H_DQS_DN<3>") )
				( member ( signalRef "M_H_DQS_DN<4>") )
				( member ( signalRef "M_H_DQS_DN<5>") )
				( member ( signalRef "M_H_DQS_DN<6>") )
				( member ( signalRef "M_H_DQS_DN<7>") )
				( member ( signalRef "M_H_DQS_DN<8>") )
				( member ( signalRef "M_H_DQS_DN<9>") )
				( member ( signalRef "M_H_DQS_DN<10>") )
				( member ( signalRef "M_H_DQS_DN<11>") )
				( member ( signalRef "M_H_DQS_DN<12>") )
				( member ( signalRef "M_H_DQS_DN<13>") )
				( member ( signalRef "M_H_DQS_DN<14>") )
				( member ( signalRef "M_H_DQS_DN<15>") )
				( member ( signalRef "M_H_DQS_DN<16>") )
				( member ( signalRef "M_H_DQS_DN<17>") )
				( objectStatus "@baseboard_fab2_lib.baseboard_fab2(sch_1):m_h_dqs_dn" )
			)
			( bus "M_H_DQS_DP"
				( memberType ( signal ) )
				( member ( signalRef "M_H_DQS_DP<0>") )
				( member ( signalRef "M_H_DQS_DP<1>") )
				( member ( signalRef "M_H_DQS_DP<2>") )
				( member ( signalRef "M_H_DQS_DP<3>") )
				( member ( signalRef "M_H_DQS_DP<4>") )
				( member ( signalRef "M_H_DQS_DP<5>") )
				( member ( signalRef "M_H_DQS_DP<6>") )
				( member ( signalRef "M_H_DQS_DP<7>") )
				( member ( signalRef "M_H_DQS_DP<8>") )
				( member ( signalRef "M_H_DQS_DP<9>") )
				( member ( signalRef "M_H_DQS_DP<10>") )
				( member ( signalRef "M_H_DQS_DP<11>") )
				( member ( signalRef "M_H_DQS_DP<12>") )
				( member ( signalRef "M_H_DQS_DP<13>") )
				( member ( signalRef "M_H_DQS_DP<14>") )
				( member ( signalRef "M_H_DQS_DP<15>") )
				( member ( signalRef "M_H_DQS_DP<16>") )
				( member ( signalRef "M_H_DQS_DP<17>") )
				( objectStatus "@baseboard_fab2_lib.baseboard_fab2(sch_1):m_h_dqs_dp" )
			)
			( bus "M_H_ECC"
				( memberType ( signal ) )
				( member ( signalRef "M_H_ECC<0>") )
				( member ( signalRef "M_H_ECC<1>") )
				( member ( signalRef "M_H_ECC<2>") )
				( member ( signalRef "M_H_ECC<3>") )
				( member ( signalRef "M_H_ECC<4>") )
				( member ( signalRef "M_H_ECC<5>") )
				( member ( signalRef "M_H_ECC<6>") )
				( member ( signalRef "M_H_ECC<7>") )
				( objectStatus "@baseboard_fab2_lib.baseboard_fab2(sch_1):m_h_ecc" )
			)
			( bus "M_H_MA"
				( memberType ( signal ) )
				( member ( signalRef "M_H_MA<0>") )
				( member ( signalRef "M_H_MA<1>") )
				( member ( signalRef "M_H_MA<2>") )
				( member ( signalRef "M_H_MA<3>") )
				( member ( signalRef "M_H_MA<4>") )
				( member ( signalRef "M_H_MA<5>") )
				( member ( signalRef "M_H_MA<6>") )
				( member ( signalRef "M_H_MA<7>") )
				( member ( signalRef "M_H_MA<8>") )
				( member ( signalRef "M_H_MA<9>") )
				( member ( signalRef "M_H_MA<10>") )
				( member ( signalRef "M_H_MA<11>") )
				( member ( signalRef "M_H_MA<12>") )
				( member ( signalRef "M_H_MA<13>") )
				( member ( signalRef "M_H_MA<14>") )
				( member ( signalRef "M_H_MA<15>") )
				( member ( signalRef "M_H_MA<16>") )
				( member ( signalRef "M_H_MA<17>") )
				( objectStatus "@baseboard_fab2_lib.baseboard_fab2(sch_1):m_h_ma" )
			)
			( bus "M_H_ODT"
				( memberType ( signal ) )
				( member ( signalRef "M_H_ODT<0>") )
				( member ( signalRef "M_H_ODT<1>") )
				( member ( signalRef "M_H_ODT<2>") )
				( member ( signalRef "M_H_ODT<3>") )
				( objectStatus "@baseboard_fab2_lib.baseboard_fab2(sch_1):m_h_odt" )
			)
			( bus "M_J_BA"
				( memberType ( signal ) )
				( member ( signalRef "M_J_BA<0>") )
				( member ( signalRef "M_J_BA<1>") )
				( objectStatus "@baseboard_fab2_lib.baseboard_fab2(sch_1):m_j_ba" )
			)
			( bus "M_J_BG"
				( memberType ( signal ) )
				( member ( signalRef "M_J_BG<0>") )
				( member ( signalRef "M_J_BG<1>") )
				( objectStatus "@baseboard_fab2_lib.baseboard_fab2(sch_1):m_j_bg" )
			)
			( bus "M_J_C"
				( memberType ( signal ) )
				( member ( signalRef "M_J_C<2>") )
				( objectStatus "@baseboard_fab2_lib.baseboard_fab2(sch_1):m_j_c" )
			)
			( bus "M_J_CKE"
				( memberType ( signal ) )
				( member ( signalRef "M_J_CKE<0>") )
				( member ( signalRef "M_J_CKE<1>") )
				( member ( signalRef "M_J_CKE<2>") )
				( member ( signalRef "M_J_CKE<3>") )
				( objectStatus "@baseboard_fab2_lib.baseboard_fab2(sch_1):m_j_cke" )
			)
			( bus "M_J_CLK_DN"
				( memberType ( signal ) )
				( member ( signalRef "M_J_CLK_DN<0>") )
				( member ( signalRef "M_J_CLK_DN<1>") )
				( member ( signalRef "M_J_CLK_DN<2>") )
				( member ( signalRef "M_J_CLK_DN<3>") )
				( objectStatus "@baseboard_fab2_lib.baseboard_fab2(sch_1):m_j_clk_dn" )
			)
			( bus "M_J_CLK_DP"
				( memberType ( signal ) )
				( member ( signalRef "M_J_CLK_DP<0>") )
				( member ( signalRef "M_J_CLK_DP<1>") )
				( member ( signalRef "M_J_CLK_DP<2>") )
				( member ( signalRef "M_J_CLK_DP<3>") )
				( objectStatus "@baseboard_fab2_lib.baseboard_fab2(sch_1):m_j_clk_dp" )
			)
			( bus "M_J_CS_N"
				( memberType ( signal ) )
				( member ( signalRef "M_J_CS_N<0>") )
				( member ( signalRef "M_J_CS_N<1>") )
				( member ( signalRef "M_J_CS_N<2>") )
				( member ( signalRef "M_J_CS_N<3>") )
				( member ( signalRef "M_J_CS_N<4>") )
				( member ( signalRef "M_J_CS_N<5>") )
				( member ( signalRef "M_J_CS_N<6>") )
				( member ( signalRef "M_J_CS_N<7>") )
				( objectStatus "@baseboard_fab2_lib.baseboard_fab2(sch_1):m_j_cs_n" )
			)
			( bus "M_J_DQ"
				( memberType ( signal ) )
				( member ( signalRef "M_J_DQ<0>") )
				( member ( signalRef "M_J_DQ<1>") )
				( member ( signalRef "M_J_DQ<2>") )
				( member ( signalRef "M_J_DQ<3>") )
				( member ( signalRef "M_J_DQ<4>") )
				( member ( signalRef "M_J_DQ<5>") )
				( member ( signalRef "M_J_DQ<6>") )
				( member ( signalRef "M_J_DQ<7>") )
				( member ( signalRef "M_J_DQ<8>") )
				( member ( signalRef "M_J_DQ<9>") )
				( member ( signalRef "M_J_DQ<10>") )
				( member ( signalRef "M_J_DQ<11>") )
				( member ( signalRef "M_J_DQ<12>") )
				( member ( signalRef "M_J_DQ<13>") )
				( member ( signalRef "M_J_DQ<14>") )
				( member ( signalRef "M_J_DQ<15>") )
				( member ( signalRef "M_J_DQ<16>") )
				( member ( signalRef "M_J_DQ<17>") )
				( member ( signalRef "M_J_DQ<18>") )
				( member ( signalRef "M_J_DQ<19>") )
				( member ( signalRef "M_J_DQ<20>") )
				( member ( signalRef "M_J_DQ<21>") )
				( member ( signalRef "M_J_DQ<22>") )
				( member ( signalRef "M_J_DQ<23>") )
				( member ( signalRef "M_J_DQ<24>") )
				( member ( signalRef "M_J_DQ<25>") )
				( member ( signalRef "M_J_DQ<26>") )
				( member ( signalRef "M_J_DQ<27>") )
				( member ( signalRef "M_J_DQ<28>") )
				( member ( signalRef "M_J_DQ<29>") )
				( member ( signalRef "M_J_DQ<30>") )
				( member ( signalRef "M_J_DQ<31>") )
				( member ( signalRef "M_J_DQ<32>") )
				( member ( signalRef "M_J_DQ<33>") )
				( member ( signalRef "M_J_DQ<34>") )
				( member ( signalRef "M_J_DQ<35>") )
				( member ( signalRef "M_J_DQ<36>") )
				( member ( signalRef "M_J_DQ<37>") )
				( member ( signalRef "M_J_DQ<38>") )
				( member ( signalRef "M_J_DQ<39>") )
				( member ( signalRef "M_J_DQ<40>") )
				( member ( signalRef "M_J_DQ<41>") )
				( member ( signalRef "M_J_DQ<42>") )
				( member ( signalRef "M_J_DQ<43>") )
				( member ( signalRef "M_J_DQ<44>") )
				( member ( signalRef "M_J_DQ<45>") )
				( member ( signalRef "M_J_DQ<46>") )
				( member ( signalRef "M_J_DQ<47>") )
				( member ( signalRef "M_J_DQ<48>") )
				( member ( signalRef "M_J_DQ<49>") )
				( member ( signalRef "M_J_DQ<50>") )
				( member ( signalRef "M_J_DQ<51>") )
				( member ( signalRef "M_J_DQ<52>") )
				( member ( signalRef "M_J_DQ<53>") )
				( member ( signalRef "M_J_DQ<54>") )
				( member ( signalRef "M_J_DQ<55>") )
				( member ( signalRef "M_J_DQ<56>") )
				( member ( signalRef "M_J_DQ<57>") )
				( member ( signalRef "M_J_DQ<58>") )
				( member ( signalRef "M_J_DQ<59>") )
				( member ( signalRef "M_J_DQ<60>") )
				( member ( signalRef "M_J_DQ<61>") )
				( member ( signalRef "M_J_DQ<62>") )
				( member ( signalRef "M_J_DQ<63>") )
				( objectStatus "@baseboard_fab2_lib.baseboard_fab2(sch_1):m_j_dq" )
			)
			( bus "M_J_DQS_DN"
				( memberType ( signal ) )
				( member ( signalRef "M_J_DQS_DN<0>") )
				( member ( signalRef "M_J_DQS_DN<1>") )
				( member ( signalRef "M_J_DQS_DN<2>") )
				( member ( signalRef "M_J_DQS_DN<3>") )
				( member ( signalRef "M_J_DQS_DN<4>") )
				( member ( signalRef "M_J_DQS_DN<5>") )
				( member ( signalRef "M_J_DQS_DN<6>") )
				( member ( signalRef "M_J_DQS_DN<7>") )
				( member ( signalRef "M_J_DQS_DN<8>") )
				( member ( signalRef "M_J_DQS_DN<9>") )
				( member ( signalRef "M_J_DQS_DN<10>") )
				( member ( signalRef "M_J_DQS_DN<11>") )
				( member ( signalRef "M_J_DQS_DN<12>") )
				( member ( signalRef "M_J_DQS_DN<13>") )
				( member ( signalRef "M_J_DQS_DN<14>") )
				( member ( signalRef "M_J_DQS_DN<15>") )
				( member ( signalRef "M_J_DQS_DN<16>") )
				( member ( signalRef "M_J_DQS_DN<17>") )
				( objectStatus "@baseboard_fab2_lib.baseboard_fab2(sch_1):m_j_dqs_dn" )
			)
			( bus "M_J_DQS_DP"
				( memberType ( signal ) )
				( member ( signalRef "M_J_DQS_DP<0>") )
				( member ( signalRef "M_J_DQS_DP<1>") )
				( member ( signalRef "M_J_DQS_DP<2>") )
				( member ( signalRef "M_J_DQS_DP<3>") )
				( member ( signalRef "M_J_DQS_DP<4>") )
				( member ( signalRef "M_J_DQS_DP<5>") )
				( member ( signalRef "M_J_DQS_DP<6>") )
				( member ( signalRef "M_J_DQS_DP<7>") )
				( member ( signalRef "M_J_DQS_DP<8>") )
				( member ( signalRef "M_J_DQS_DP<9>") )
				( member ( signalRef "M_J_DQS_DP<10>") )
				( member ( signalRef "M_J_DQS_DP<11>") )
				( member ( signalRef "M_J_DQS_DP<12>") )
				( member ( signalRef "M_J_DQS_DP<13>") )
				( member ( signalRef "M_J_DQS_DP<14>") )
				( member ( signalRef "M_J_DQS_DP<15>") )
				( member ( signalRef "M_J_DQS_DP<16>") )
				( member ( signalRef "M_J_DQS_DP<17>") )
				( objectStatus "@baseboard_fab2_lib.baseboard_fab2(sch_1):m_j_dqs_dp" )
			)
			( bus "M_J_ECC"
				( memberType ( signal ) )
				( member ( signalRef "M_J_ECC<0>") )
				( member ( signalRef "M_J_ECC<1>") )
				( member ( signalRef "M_J_ECC<2>") )
				( member ( signalRef "M_J_ECC<3>") )
				( member ( signalRef "M_J_ECC<4>") )
				( member ( signalRef "M_J_ECC<5>") )
				( member ( signalRef "M_J_ECC<6>") )
				( member ( signalRef "M_J_ECC<7>") )
				( objectStatus "@baseboard_fab2_lib.baseboard_fab2(sch_1):m_j_ecc" )
			)
			( bus "M_J_MA"
				( memberType ( signal ) )
				( member ( signalRef "M_J_MA<0>") )
				( member ( signalRef "M_J_MA<1>") )
				( member ( signalRef "M_J_MA<2>") )
				( member ( signalRef "M_J_MA<3>") )
				( member ( signalRef "M_J_MA<4>") )
				( member ( signalRef "M_J_MA<5>") )
				( member ( signalRef "M_J_MA<6>") )
				( member ( signalRef "M_J_MA<7>") )
				( member ( signalRef "M_J_MA<8>") )
				( member ( signalRef "M_J_MA<9>") )
				( member ( signalRef "M_J_MA<10>") )
				( member ( signalRef "M_J_MA<11>") )
				( member ( signalRef "M_J_MA<12>") )
				( member ( signalRef "M_J_MA<13>") )
				( member ( signalRef "M_J_MA<14>") )
				( member ( signalRef "M_J_MA<15>") )
				( member ( signalRef "M_J_MA<16>") )
				( member ( signalRef "M_J_MA<17>") )
				( objectStatus "@baseboard_fab2_lib.baseboard_fab2(sch_1):m_j_ma" )
			)
			( bus "M_J_ODT"
				( memberType ( signal ) )
				( member ( signalRef "M_J_ODT<0>") )
				( member ( signalRef "M_J_ODT<1>") )
				( member ( signalRef "M_J_ODT<2>") )
				( member ( signalRef "M_J_ODT<3>") )
				( objectStatus "@baseboard_fab2_lib.baseboard_fab2(sch_1):m_j_odt" )
			)
			( bus "M_K_BA"
				( memberType ( signal ) )
				( member ( signalRef "M_K_BA<0>") )
				( member ( signalRef "M_K_BA<1>") )
				( objectStatus "@baseboard_fab2_lib.baseboard_fab2(sch_1):m_k_ba" )
			)
			( bus "M_K_BG"
				( memberType ( signal ) )
				( member ( signalRef "M_K_BG<0>") )
				( member ( signalRef "M_K_BG<1>") )
				( objectStatus "@baseboard_fab2_lib.baseboard_fab2(sch_1):m_k_bg" )
			)
			( bus "M_K_C"
				( memberType ( signal ) )
				( member ( signalRef "M_K_C<2>") )
				( objectStatus "@baseboard_fab2_lib.baseboard_fab2(sch_1):m_k_c" )
			)
			( bus "M_K_CKE"
				( memberType ( signal ) )
				( member ( signalRef "M_K_CKE<0>") )
				( member ( signalRef "M_K_CKE<1>") )
				( member ( signalRef "M_K_CKE<2>") )
				( member ( signalRef "M_K_CKE<3>") )
				( objectStatus "@baseboard_fab2_lib.baseboard_fab2(sch_1):m_k_cke" )
			)
			( bus "M_K_CLK_DN"
				( memberType ( signal ) )
				( member ( signalRef "M_K_CLK_DN<0>") )
				( member ( signalRef "M_K_CLK_DN<1>") )
				( member ( signalRef "M_K_CLK_DN<2>") )
				( member ( signalRef "M_K_CLK_DN<3>") )
				( objectStatus "@baseboard_fab2_lib.baseboard_fab2(sch_1):m_k_clk_dn" )
			)
			( bus "M_K_CLK_DP"
				( memberType ( signal ) )
				( member ( signalRef "M_K_CLK_DP<0>") )
				( member ( signalRef "M_K_CLK_DP<1>") )
				( member ( signalRef "M_K_CLK_DP<2>") )
				( member ( signalRef "M_K_CLK_DP<3>") )
				( objectStatus "@baseboard_fab2_lib.baseboard_fab2(sch_1):m_k_clk_dp" )
			)
			( bus "M_K_CS_N"
				( memberType ( signal ) )
				( member ( signalRef "M_K_CS_N<0>") )
				( member ( signalRef "M_K_CS_N<1>") )
				( member ( signalRef "M_K_CS_N<2>") )
				( member ( signalRef "M_K_CS_N<3>") )
				( member ( signalRef "M_K_CS_N<4>") )
				( member ( signalRef "M_K_CS_N<5>") )
				( member ( signalRef "M_K_CS_N<6>") )
				( member ( signalRef "M_K_CS_N<7>") )
				( objectStatus "@baseboard_fab2_lib.baseboard_fab2(sch_1):m_k_cs_n" )
			)
			( bus "M_K_DQ"
				( memberType ( signal ) )
				( member ( signalRef "M_K_DQ<0>") )
				( member ( signalRef "M_K_DQ<1>") )
				( member ( signalRef "M_K_DQ<2>") )
				( member ( signalRef "M_K_DQ<3>") )
				( member ( signalRef "M_K_DQ<4>") )
				( member ( signalRef "M_K_DQ<5>") )
				( member ( signalRef "M_K_DQ<6>") )
				( member ( signalRef "M_K_DQ<7>") )
				( member ( signalRef "M_K_DQ<8>") )
				( member ( signalRef "M_K_DQ<9>") )
				( member ( signalRef "M_K_DQ<10>") )
				( member ( signalRef "M_K_DQ<11>") )
				( member ( signalRef "M_K_DQ<12>") )
				( member ( signalRef "M_K_DQ<13>") )
				( member ( signalRef "M_K_DQ<14>") )
				( member ( signalRef "M_K_DQ<15>") )
				( member ( signalRef "M_K_DQ<16>") )
				( member ( signalRef "M_K_DQ<17>") )
				( member ( signalRef "M_K_DQ<18>") )
				( member ( signalRef "M_K_DQ<19>") )
				( member ( signalRef "M_K_DQ<20>") )
				( member ( signalRef "M_K_DQ<21>") )
				( member ( signalRef "M_K_DQ<22>") )
				( member ( signalRef "M_K_DQ<23>") )
				( member ( signalRef "M_K_DQ<24>") )
				( member ( signalRef "M_K_DQ<25>") )
				( member ( signalRef "M_K_DQ<26>") )
				( member ( signalRef "M_K_DQ<27>") )
				( member ( signalRef "M_K_DQ<28>") )
				( member ( signalRef "M_K_DQ<29>") )
				( member ( signalRef "M_K_DQ<30>") )
				( member ( signalRef "M_K_DQ<31>") )
				( member ( signalRef "M_K_DQ<32>") )
				( member ( signalRef "M_K_DQ<33>") )
				( member ( signalRef "M_K_DQ<34>") )
				( member ( signalRef "M_K_DQ<35>") )
				( member ( signalRef "M_K_DQ<36>") )
				( member ( signalRef "M_K_DQ<37>") )
				( member ( signalRef "M_K_DQ<38>") )
				( member ( signalRef "M_K_DQ<39>") )
				( member ( signalRef "M_K_DQ<40>") )
				( member ( signalRef "M_K_DQ<41>") )
				( member ( signalRef "M_K_DQ<42>") )
				( member ( signalRef "M_K_DQ<43>") )
				( member ( signalRef "M_K_DQ<44>") )
				( member ( signalRef "M_K_DQ<45>") )
				( member ( signalRef "M_K_DQ<46>") )
				( member ( signalRef "M_K_DQ<47>") )
				( member ( signalRef "M_K_DQ<48>") )
				( member ( signalRef "M_K_DQ<49>") )
				( member ( signalRef "M_K_DQ<50>") )
				( member ( signalRef "M_K_DQ<51>") )
				( member ( signalRef "M_K_DQ<52>") )
				( member ( signalRef "M_K_DQ<53>") )
				( member ( signalRef "M_K_DQ<54>") )
				( member ( signalRef "M_K_DQ<55>") )
				( member ( signalRef "M_K_DQ<56>") )
				( member ( signalRef "M_K_DQ<57>") )
				( member ( signalRef "M_K_DQ<58>") )
				( member ( signalRef "M_K_DQ<59>") )
				( member ( signalRef "M_K_DQ<60>") )
				( member ( signalRef "M_K_DQ<61>") )
				( member ( signalRef "M_K_DQ<62>") )
				( member ( signalRef "M_K_DQ<63>") )
				( objectStatus "@baseboard_fab2_lib.baseboard_fab2(sch_1):m_k_dq" )
			)
			( bus "M_K_DQS_DN"
				( memberType ( signal ) )
				( member ( signalRef "M_K_DQS_DN<0>") )
				( member ( signalRef "M_K_DQS_DN<1>") )
				( member ( signalRef "M_K_DQS_DN<2>") )
				( member ( signalRef "M_K_DQS_DN<3>") )
				( member ( signalRef "M_K_DQS_DN<4>") )
				( member ( signalRef "M_K_DQS_DN<5>") )
				( member ( signalRef "M_K_DQS_DN<6>") )
				( member ( signalRef "M_K_DQS_DN<7>") )
				( member ( signalRef "M_K_DQS_DN<8>") )
				( member ( signalRef "M_K_DQS_DN<9>") )
				( member ( signalRef "M_K_DQS_DN<10>") )
				( member ( signalRef "M_K_DQS_DN<11>") )
				( member ( signalRef "M_K_DQS_DN<12>") )
				( member ( signalRef "M_K_DQS_DN<13>") )
				( member ( signalRef "M_K_DQS_DN<14>") )
				( member ( signalRef "M_K_DQS_DN<15>") )
				( member ( signalRef "M_K_DQS_DN<16>") )
				( member ( signalRef "M_K_DQS_DN<17>") )
				( objectStatus "@baseboard_fab2_lib.baseboard_fab2(sch_1):m_k_dqs_dn" )
			)
			( bus "M_K_DQS_DP"
				( memberType ( signal ) )
				( member ( signalRef "M_K_DQS_DP<0>") )
				( member ( signalRef "M_K_DQS_DP<1>") )
				( member ( signalRef "M_K_DQS_DP<2>") )
				( member ( signalRef "M_K_DQS_DP<3>") )
				( member ( signalRef "M_K_DQS_DP<4>") )
				( member ( signalRef "M_K_DQS_DP<5>") )
				( member ( signalRef "M_K_DQS_DP<6>") )
				( member ( signalRef "M_K_DQS_DP<7>") )
				( member ( signalRef "M_K_DQS_DP<8>") )
				( member ( signalRef "M_K_DQS_DP<9>") )
				( member ( signalRef "M_K_DQS_DP<10>") )
				( member ( signalRef "M_K_DQS_DP<11>") )
				( member ( signalRef "M_K_DQS_DP<12>") )
				( member ( signalRef "M_K_DQS_DP<13>") )
				( member ( signalRef "M_K_DQS_DP<14>") )
				( member ( signalRef "M_K_DQS_DP<15>") )
				( member ( signalRef "M_K_DQS_DP<16>") )
				( member ( signalRef "M_K_DQS_DP<17>") )
				( objectStatus "@baseboard_fab2_lib.baseboard_fab2(sch_1):m_k_dqs_dp" )
			)
			( bus "M_K_ECC"
				( memberType ( signal ) )
				( member ( signalRef "M_K_ECC<0>") )
				( member ( signalRef "M_K_ECC<1>") )
				( member ( signalRef "M_K_ECC<2>") )
				( member ( signalRef "M_K_ECC<3>") )
				( member ( signalRef "M_K_ECC<4>") )
				( member ( signalRef "M_K_ECC<5>") )
				( member ( signalRef "M_K_ECC<6>") )
				( member ( signalRef "M_K_ECC<7>") )
				( objectStatus "@baseboard_fab2_lib.baseboard_fab2(sch_1):m_k_ecc" )
			)
			( bus "M_K_MA"
				( memberType ( signal ) )
				( member ( signalRef "M_K_MA<0>") )
				( member ( signalRef "M_K_MA<1>") )
				( member ( signalRef "M_K_MA<2>") )
				( member ( signalRef "M_K_MA<3>") )
				( member ( signalRef "M_K_MA<4>") )
				( member ( signalRef "M_K_MA<5>") )
				( member ( signalRef "M_K_MA<6>") )
				( member ( signalRef "M_K_MA<7>") )
				( member ( signalRef "M_K_MA<8>") )
				( member ( signalRef "M_K_MA<9>") )
				( member ( signalRef "M_K_MA<10>") )
				( member ( signalRef "M_K_MA<11>") )
				( member ( signalRef "M_K_MA<12>") )
				( member ( signalRef "M_K_MA<13>") )
				( member ( signalRef "M_K_MA<14>") )
				( member ( signalRef "M_K_MA<15>") )
				( member ( signalRef "M_K_MA<16>") )
				( member ( signalRef "M_K_MA<17>") )
				( objectStatus "@baseboard_fab2_lib.baseboard_fab2(sch_1):m_k_ma" )
			)
			( bus "M_K_ODT"
				( memberType ( signal ) )
				( member ( signalRef "M_K_ODT<0>") )
				( member ( signalRef "M_K_ODT<1>") )
				( member ( signalRef "M_K_ODT<2>") )
				( member ( signalRef "M_K_ODT<3>") )
				( objectStatus "@baseboard_fab2_lib.baseboard_fab2(sch_1):m_k_odt" )
			)
			( bus "M_L_BA"
				( memberType ( signal ) )
				( member ( signalRef "M_L_BA<0>") )
				( member ( signalRef "M_L_BA<1>") )
				( objectStatus "@baseboard_fab2_lib.baseboard_fab2(sch_1):m_l_ba" )
			)
			( bus "M_L_BG"
				( memberType ( signal ) )
				( member ( signalRef "M_L_BG<0>") )
				( member ( signalRef "M_L_BG<1>") )
				( objectStatus "@baseboard_fab2_lib.baseboard_fab2(sch_1):m_l_bg" )
			)
			( bus "M_L_C"
				( memberType ( signal ) )
				( member ( signalRef "M_L_C<2>") )
				( objectStatus "@baseboard_fab2_lib.baseboard_fab2(sch_1):m_l_c" )
			)
			( bus "M_L_CKE"
				( memberType ( signal ) )
				( member ( signalRef "M_L_CKE<0>") )
				( member ( signalRef "M_L_CKE<1>") )
				( member ( signalRef "M_L_CKE<2>") )
				( member ( signalRef "M_L_CKE<3>") )
				( objectStatus "@baseboard_fab2_lib.baseboard_fab2(sch_1):m_l_cke" )
			)
			( bus "M_L_CLK_DN"
				( memberType ( signal ) )
				( member ( signalRef "M_L_CLK_DN<0>") )
				( member ( signalRef "M_L_CLK_DN<1>") )
				( member ( signalRef "M_L_CLK_DN<2>") )
				( member ( signalRef "M_L_CLK_DN<3>") )
				( objectStatus "@baseboard_fab2_lib.baseboard_fab2(sch_1):m_l_clk_dn" )
			)
			( bus "M_L_CLK_DP"
				( memberType ( signal ) )
				( member ( signalRef "M_L_CLK_DP<0>") )
				( member ( signalRef "M_L_CLK_DP<1>") )
				( member ( signalRef "M_L_CLK_DP<2>") )
				( member ( signalRef "M_L_CLK_DP<3>") )
				( objectStatus "@baseboard_fab2_lib.baseboard_fab2(sch_1):m_l_clk_dp" )
			)
			( bus "M_L_CS_N"
				( memberType ( signal ) )
				( member ( signalRef "M_L_CS_N<0>") )
				( member ( signalRef "M_L_CS_N<1>") )
				( member ( signalRef "M_L_CS_N<2>") )
				( member ( signalRef "M_L_CS_N<3>") )
				( member ( signalRef "M_L_CS_N<4>") )
				( member ( signalRef "M_L_CS_N<5>") )
				( member ( signalRef "M_L_CS_N<6>") )
				( member ( signalRef "M_L_CS_N<7>") )
				( objectStatus "@baseboard_fab2_lib.baseboard_fab2(sch_1):m_l_cs_n" )
			)
			( bus "M_L_DQ"
				( memberType ( signal ) )
				( member ( signalRef "M_L_DQ<0>") )
				( member ( signalRef "M_L_DQ<1>") )
				( member ( signalRef "M_L_DQ<2>") )
				( member ( signalRef "M_L_DQ<3>") )
				( member ( signalRef "M_L_DQ<4>") )
				( member ( signalRef "M_L_DQ<5>") )
				( member ( signalRef "M_L_DQ<6>") )
				( member ( signalRef "M_L_DQ<7>") )
				( member ( signalRef "M_L_DQ<8>") )
				( member ( signalRef "M_L_DQ<9>") )
				( member ( signalRef "M_L_DQ<10>") )
				( member ( signalRef "M_L_DQ<11>") )
				( member ( signalRef "M_L_DQ<12>") )
				( member ( signalRef "M_L_DQ<13>") )
				( member ( signalRef "M_L_DQ<14>") )
				( member ( signalRef "M_L_DQ<15>") )
				( member ( signalRef "M_L_DQ<16>") )
				( member ( signalRef "M_L_DQ<17>") )
				( member ( signalRef "M_L_DQ<18>") )
				( member ( signalRef "M_L_DQ<19>") )
				( member ( signalRef "M_L_DQ<20>") )
				( member ( signalRef "M_L_DQ<21>") )
				( member ( signalRef "M_L_DQ<22>") )
				( member ( signalRef "M_L_DQ<23>") )
				( member ( signalRef "M_L_DQ<24>") )
				( member ( signalRef "M_L_DQ<25>") )
				( member ( signalRef "M_L_DQ<26>") )
				( member ( signalRef "M_L_DQ<27>") )
				( member ( signalRef "M_L_DQ<28>") )
				( member ( signalRef "M_L_DQ<29>") )
				( member ( signalRef "M_L_DQ<30>") )
				( member ( signalRef "M_L_DQ<31>") )
				( member ( signalRef "M_L_DQ<32>") )
				( member ( signalRef "M_L_DQ<33>") )
				( member ( signalRef "M_L_DQ<34>") )
				( member ( signalRef "M_L_DQ<35>") )
				( member ( signalRef "M_L_DQ<36>") )
				( member ( signalRef "M_L_DQ<37>") )
				( member ( signalRef "M_L_DQ<38>") )
				( member ( signalRef "M_L_DQ<39>") )
				( member ( signalRef "M_L_DQ<40>") )
				( member ( signalRef "M_L_DQ<41>") )
				( member ( signalRef "M_L_DQ<42>") )
				( member ( signalRef "M_L_DQ<43>") )
				( member ( signalRef "M_L_DQ<44>") )
				( member ( signalRef "M_L_DQ<45>") )
				( member ( signalRef "M_L_DQ<46>") )
				( member ( signalRef "M_L_DQ<47>") )
				( member ( signalRef "M_L_DQ<48>") )
				( member ( signalRef "M_L_DQ<49>") )
				( member ( signalRef "M_L_DQ<50>") )
				( member ( signalRef "M_L_DQ<51>") )
				( member ( signalRef "M_L_DQ<52>") )
				( member ( signalRef "M_L_DQ<53>") )
				( member ( signalRef "M_L_DQ<54>") )
				( member ( signalRef "M_L_DQ<55>") )
				( member ( signalRef "M_L_DQ<56>") )
				( member ( signalRef "M_L_DQ<57>") )
				( member ( signalRef "M_L_DQ<58>") )
				( member ( signalRef "M_L_DQ<59>") )
				( member ( signalRef "M_L_DQ<60>") )
				( member ( signalRef "M_L_DQ<61>") )
				( member ( signalRef "M_L_DQ<62>") )
				( member ( signalRef "M_L_DQ<63>") )
				( objectStatus "@baseboard_fab2_lib.baseboard_fab2(sch_1):m_l_dq" )
			)
			( bus "M_L_DQS_DN"
				( memberType ( signal ) )
				( member ( signalRef "M_L_DQS_DN<0>") )
				( member ( signalRef "M_L_DQS_DN<1>") )
				( member ( signalRef "M_L_DQS_DN<2>") )
				( member ( signalRef "M_L_DQS_DN<3>") )
				( member ( signalRef "M_L_DQS_DN<4>") )
				( member ( signalRef "M_L_DQS_DN<5>") )
				( member ( signalRef "M_L_DQS_DN<6>") )
				( member ( signalRef "M_L_DQS_DN<7>") )
				( member ( signalRef "M_L_DQS_DN<8>") )
				( member ( signalRef "M_L_DQS_DN<9>") )
				( member ( signalRef "M_L_DQS_DN<10>") )
				( member ( signalRef "M_L_DQS_DN<11>") )
				( member ( signalRef "M_L_DQS_DN<12>") )
				( member ( signalRef "M_L_DQS_DN<13>") )
				( member ( signalRef "M_L_DQS_DN<14>") )
				( member ( signalRef "M_L_DQS_DN<15>") )
				( member ( signalRef "M_L_DQS_DN<16>") )
				( member ( signalRef "M_L_DQS_DN<17>") )
				( objectStatus "@baseboard_fab2_lib.baseboard_fab2(sch_1):m_l_dqs_dn" )
			)
			( bus "M_L_DQS_DP"
				( memberType ( signal ) )
				( member ( signalRef "M_L_DQS_DP<0>") )
				( member ( signalRef "M_L_DQS_DP<1>") )
				( member ( signalRef "M_L_DQS_DP<2>") )
				( member ( signalRef "M_L_DQS_DP<3>") )
				( member ( signalRef "M_L_DQS_DP<4>") )
				( member ( signalRef "M_L_DQS_DP<5>") )
				( member ( signalRef "M_L_DQS_DP<6>") )
				( member ( signalRef "M_L_DQS_DP<7>") )
				( member ( signalRef "M_L_DQS_DP<8>") )
				( member ( signalRef "M_L_DQS_DP<9>") )
				( member ( signalRef "M_L_DQS_DP<10>") )
				( member ( signalRef "M_L_DQS_DP<11>") )
				( member ( signalRef "M_L_DQS_DP<12>") )
				( member ( signalRef "M_L_DQS_DP<13>") )
				( member ( signalRef "M_L_DQS_DP<14>") )
				( member ( signalRef "M_L_DQS_DP<15>") )
				( member ( signalRef "M_L_DQS_DP<16>") )
				( member ( signalRef "M_L_DQS_DP<17>") )
				( objectStatus "@baseboard_fab2_lib.baseboard_fab2(sch_1):m_l_dqs_dp" )
			)
			( bus "M_L_ECC"
				( memberType ( signal ) )
				( member ( signalRef "M_L_ECC<0>") )
				( member ( signalRef "M_L_ECC<1>") )
				( member ( signalRef "M_L_ECC<2>") )
				( member ( signalRef "M_L_ECC<3>") )
				( member ( signalRef "M_L_ECC<4>") )
				( member ( signalRef "M_L_ECC<5>") )
				( member ( signalRef "M_L_ECC<6>") )
				( member ( signalRef "M_L_ECC<7>") )
				( objectStatus "@baseboard_fab2_lib.baseboard_fab2(sch_1):m_l_ecc" )
			)
			( bus "M_L_MA"
				( memberType ( signal ) )
				( member ( signalRef "M_L_MA<0>") )
				( member ( signalRef "M_L_MA<1>") )
				( member ( signalRef "M_L_MA<2>") )
				( member ( signalRef "M_L_MA<3>") )
				( member ( signalRef "M_L_MA<4>") )
				( member ( signalRef "M_L_MA<5>") )
				( member ( signalRef "M_L_MA<6>") )
				( member ( signalRef "M_L_MA<7>") )
				( member ( signalRef "M_L_MA<8>") )
				( member ( signalRef "M_L_MA<9>") )
				( member ( signalRef "M_L_MA<10>") )
				( member ( signalRef "M_L_MA<11>") )
				( member ( signalRef "M_L_MA<12>") )
				( member ( signalRef "M_L_MA<13>") )
				( member ( signalRef "M_L_MA<14>") )
				( member ( signalRef "M_L_MA<15>") )
				( member ( signalRef "M_L_MA<16>") )
				( member ( signalRef "M_L_MA<17>") )
				( objectStatus "@baseboard_fab2_lib.baseboard_fab2(sch_1):m_l_ma" )
			)
			( bus "M_L_ODT"
				( memberType ( signal ) )
				( member ( signalRef "M_L_ODT<0>") )
				( member ( signalRef "M_L_ODT<1>") )
				( member ( signalRef "M_L_ODT<2>") )
				( member ( signalRef "M_L_ODT<3>") )
				( objectStatus "@baseboard_fab2_lib.baseboard_fab2(sch_1):m_l_odt" )
			)
			( bus "M_M_BA"
				( memberType ( signal ) )
				( member ( signalRef "M_M_BA<0>") )
				( member ( signalRef "M_M_BA<1>") )
				( objectStatus "@baseboard_fab2_lib.baseboard_fab2(sch_1):m_m_ba" )
			)
			( bus "M_M_BG"
				( memberType ( signal ) )
				( member ( signalRef "M_M_BG<0>") )
				( member ( signalRef "M_M_BG<1>") )
				( objectStatus "@baseboard_fab2_lib.baseboard_fab2(sch_1):m_m_bg" )
			)
			( bus "M_M_C"
				( memberType ( signal ) )
				( member ( signalRef "M_M_C<2>") )
				( objectStatus "@baseboard_fab2_lib.baseboard_fab2(sch_1):m_m_c" )
			)
			( bus "M_M_CKE"
				( memberType ( signal ) )
				( member ( signalRef "M_M_CKE<0>") )
				( member ( signalRef "M_M_CKE<1>") )
				( member ( signalRef "M_M_CKE<2>") )
				( member ( signalRef "M_M_CKE<3>") )
				( objectStatus "@baseboard_fab2_lib.baseboard_fab2(sch_1):m_m_cke" )
			)
			( bus "M_M_CLK_DN"
				( memberType ( signal ) )
				( member ( signalRef "M_M_CLK_DN<0>") )
				( member ( signalRef "M_M_CLK_DN<1>") )
				( member ( signalRef "M_M_CLK_DN<2>") )
				( member ( signalRef "M_M_CLK_DN<3>") )
				( objectStatus "@baseboard_fab2_lib.baseboard_fab2(sch_1):m_m_clk_dn" )
			)
			( bus "M_M_CLK_DP"
				( memberType ( signal ) )
				( member ( signalRef "M_M_CLK_DP<0>") )
				( member ( signalRef "M_M_CLK_DP<1>") )
				( member ( signalRef "M_M_CLK_DP<2>") )
				( member ( signalRef "M_M_CLK_DP<3>") )
				( objectStatus "@baseboard_fab2_lib.baseboard_fab2(sch_1):m_m_clk_dp" )
			)
			( bus "M_M_CS_N"
				( memberType ( signal ) )
				( member ( signalRef "M_M_CS_N<0>") )
				( member ( signalRef "M_M_CS_N<1>") )
				( member ( signalRef "M_M_CS_N<2>") )
				( member ( signalRef "M_M_CS_N<3>") )
				( member ( signalRef "M_M_CS_N<4>") )
				( member ( signalRef "M_M_CS_N<5>") )
				( member ( signalRef "M_M_CS_N<6>") )
				( member ( signalRef "M_M_CS_N<7>") )
				( objectStatus "@baseboard_fab2_lib.baseboard_fab2(sch_1):m_m_cs_n" )
			)
			( bus "M_M_DQ"
				( memberType ( signal ) )
				( member ( signalRef "M_M_DQ<0>") )
				( member ( signalRef "M_M_DQ<1>") )
				( member ( signalRef "M_M_DQ<2>") )
				( member ( signalRef "M_M_DQ<3>") )
				( member ( signalRef "M_M_DQ<4>") )
				( member ( signalRef "M_M_DQ<5>") )
				( member ( signalRef "M_M_DQ<6>") )
				( member ( signalRef "M_M_DQ<7>") )
				( member ( signalRef "M_M_DQ<8>") )
				( member ( signalRef "M_M_DQ<9>") )
				( member ( signalRef "M_M_DQ<10>") )
				( member ( signalRef "M_M_DQ<11>") )
				( member ( signalRef "M_M_DQ<12>") )
				( member ( signalRef "M_M_DQ<13>") )
				( member ( signalRef "M_M_DQ<14>") )
				( member ( signalRef "M_M_DQ<15>") )
				( member ( signalRef "M_M_DQ<16>") )
				( member ( signalRef "M_M_DQ<17>") )
				( member ( signalRef "M_M_DQ<18>") )
				( member ( signalRef "M_M_DQ<19>") )
				( member ( signalRef "M_M_DQ<20>") )
				( member ( signalRef "M_M_DQ<21>") )
				( member ( signalRef "M_M_DQ<22>") )
				( member ( signalRef "M_M_DQ<23>") )
				( member ( signalRef "M_M_DQ<24>") )
				( member ( signalRef "M_M_DQ<25>") )
				( member ( signalRef "M_M_DQ<26>") )
				( member ( signalRef "M_M_DQ<27>") )
				( member ( signalRef "M_M_DQ<28>") )
				( member ( signalRef "M_M_DQ<29>") )
				( member ( signalRef "M_M_DQ<30>") )
				( member ( signalRef "M_M_DQ<31>") )
				( member ( signalRef "M_M_DQ<32>") )
				( member ( signalRef "M_M_DQ<33>") )
				( member ( signalRef "M_M_DQ<34>") )
				( member ( signalRef "M_M_DQ<35>") )
				( member ( signalRef "M_M_DQ<36>") )
				( member ( signalRef "M_M_DQ<37>") )
				( member ( signalRef "M_M_DQ<38>") )
				( member ( signalRef "M_M_DQ<39>") )
				( member ( signalRef "M_M_DQ<40>") )
				( member ( signalRef "M_M_DQ<41>") )
				( member ( signalRef "M_M_DQ<42>") )
				( member ( signalRef "M_M_DQ<43>") )
				( member ( signalRef "M_M_DQ<44>") )
				( member ( signalRef "M_M_DQ<45>") )
				( member ( signalRef "M_M_DQ<46>") )
				( member ( signalRef "M_M_DQ<47>") )
				( member ( signalRef "M_M_DQ<48>") )
				( member ( signalRef "M_M_DQ<49>") )
				( member ( signalRef "M_M_DQ<50>") )
				( member ( signalRef "M_M_DQ<51>") )
				( member ( signalRef "M_M_DQ<52>") )
				( member ( signalRef "M_M_DQ<53>") )
				( member ( signalRef "M_M_DQ<54>") )
				( member ( signalRef "M_M_DQ<55>") )
				( member ( signalRef "M_M_DQ<56>") )
				( member ( signalRef "M_M_DQ<57>") )
				( member ( signalRef "M_M_DQ<58>") )
				( member ( signalRef "M_M_DQ<59>") )
				( member ( signalRef "M_M_DQ<60>") )
				( member ( signalRef "M_M_DQ<61>") )
				( member ( signalRef "M_M_DQ<62>") )
				( member ( signalRef "M_M_DQ<63>") )
				( objectStatus "@baseboard_fab2_lib.baseboard_fab2(sch_1):m_m_dq" )
			)
			( bus "M_M_DQS_DN"
				( memberType ( signal ) )
				( member ( signalRef "M_M_DQS_DN<0>") )
				( member ( signalRef "M_M_DQS_DN<1>") )
				( member ( signalRef "M_M_DQS_DN<2>") )
				( member ( signalRef "M_M_DQS_DN<3>") )
				( member ( signalRef "M_M_DQS_DN<4>") )
				( member ( signalRef "M_M_DQS_DN<5>") )
				( member ( signalRef "M_M_DQS_DN<6>") )
				( member ( signalRef "M_M_DQS_DN<7>") )
				( member ( signalRef "M_M_DQS_DN<8>") )
				( member ( signalRef "M_M_DQS_DN<9>") )
				( member ( signalRef "M_M_DQS_DN<10>") )
				( member ( signalRef "M_M_DQS_DN<11>") )
				( member ( signalRef "M_M_DQS_DN<12>") )
				( member ( signalRef "M_M_DQS_DN<13>") )
				( member ( signalRef "M_M_DQS_DN<14>") )
				( member ( signalRef "M_M_DQS_DN<15>") )
				( member ( signalRef "M_M_DQS_DN<16>") )
				( member ( signalRef "M_M_DQS_DN<17>") )
				( objectStatus "@baseboard_fab2_lib.baseboard_fab2(sch_1):m_m_dqs_dn" )
			)
			( bus "M_M_DQS_DP"
				( memberType ( signal ) )
				( member ( signalRef "M_M_DQS_DP<0>") )
				( member ( signalRef "M_M_DQS_DP<1>") )
				( member ( signalRef "M_M_DQS_DP<2>") )
				( member ( signalRef "M_M_DQS_DP<3>") )
				( member ( signalRef "M_M_DQS_DP<4>") )
				( member ( signalRef "M_M_DQS_DP<5>") )
				( member ( signalRef "M_M_DQS_DP<6>") )
				( member ( signalRef "M_M_DQS_DP<7>") )
				( member ( signalRef "M_M_DQS_DP<8>") )
				( member ( signalRef "M_M_DQS_DP<9>") )
				( member ( signalRef "M_M_DQS_DP<10>") )
				( member ( signalRef "M_M_DQS_DP<11>") )
				( member ( signalRef "M_M_DQS_DP<12>") )
				( member ( signalRef "M_M_DQS_DP<13>") )
				( member ( signalRef "M_M_DQS_DP<14>") )
				( member ( signalRef "M_M_DQS_DP<15>") )
				( member ( signalRef "M_M_DQS_DP<16>") )
				( member ( signalRef "M_M_DQS_DP<17>") )
				( objectStatus "@baseboard_fab2_lib.baseboard_fab2(sch_1):m_m_dqs_dp" )
			)
			( bus "M_M_ECC"
				( memberType ( signal ) )
				( member ( signalRef "M_M_ECC<0>") )
				( member ( signalRef "M_M_ECC<1>") )
				( member ( signalRef "M_M_ECC<2>") )
				( member ( signalRef "M_M_ECC<3>") )
				( member ( signalRef "M_M_ECC<4>") )
				( member ( signalRef "M_M_ECC<5>") )
				( member ( signalRef "M_M_ECC<6>") )
				( member ( signalRef "M_M_ECC<7>") )
				( objectStatus "@baseboard_fab2_lib.baseboard_fab2(sch_1):m_m_ecc" )
			)
			( bus "M_M_MA"
				( memberType ( signal ) )
				( member ( signalRef "M_M_MA<0>") )
				( member ( signalRef "M_M_MA<1>") )
				( member ( signalRef "M_M_MA<2>") )
				( member ( signalRef "M_M_MA<3>") )
				( member ( signalRef "M_M_MA<4>") )
				( member ( signalRef "M_M_MA<5>") )
				( member ( signalRef "M_M_MA<6>") )
				( member ( signalRef "M_M_MA<7>") )
				( member ( signalRef "M_M_MA<8>") )
				( member ( signalRef "M_M_MA<9>") )
				( member ( signalRef "M_M_MA<10>") )
				( member ( signalRef "M_M_MA<11>") )
				( member ( signalRef "M_M_MA<12>") )
				( member ( signalRef "M_M_MA<13>") )
				( member ( signalRef "M_M_MA<14>") )
				( member ( signalRef "M_M_MA<15>") )
				( member ( signalRef "M_M_MA<16>") )
				( member ( signalRef "M_M_MA<17>") )
				( objectStatus "@baseboard_fab2_lib.baseboard_fab2(sch_1):m_m_ma" )
			)
			( bus "M_M_ODT"
				( memberType ( signal ) )
				( member ( signalRef "M_M_ODT<0>") )
				( member ( signalRef "M_M_ODT<1>") )
				( member ( signalRef "M_M_ODT<2>") )
				( member ( signalRef "M_M_ODT<3>") )
				( objectStatus "@baseboard_fab2_lib.baseboard_fab2(sch_1):m_m_odt" )
			)
			( bus "TP_P3E_CPU1_PE1_MP_RXN"
				( memberType ( signal ) )
				( member ( signalRef "TP_P3E_CPU1_PE1_MP_RXN<0>") )
				( member ( signalRef "TP_P3E_CPU1_PE1_MP_RXN<1>") )
				( member ( signalRef "TP_P3E_CPU1_PE1_MP_RXN<2>") )
				( member ( signalRef "TP_P3E_CPU1_PE1_MP_RXN<3>") )
				( member ( signalRef "TP_P3E_CPU1_PE1_MP_RXN<4>") )
				( member ( signalRef "TP_P3E_CPU1_PE1_MP_RXN<5>") )
				( member ( signalRef "TP_P3E_CPU1_PE1_MP_RXN<6>") )
				( member ( signalRef "TP_P3E_CPU1_PE1_MP_RXN<7>") )
				( objectStatus "@baseboard_fab2_lib.baseboard_fab2(sch_1):tp_p3e_cpu1_pe1_mp_rxn" )
			)
			( bus "TP_P3E_CPU1_PE1_MP_RXP"
				( memberType ( signal ) )
				( member ( signalRef "TP_P3E_CPU1_PE1_MP_RXP<0>") )
				( member ( signalRef "TP_P3E_CPU1_PE1_MP_RXP<1>") )
				( member ( signalRef "TP_P3E_CPU1_PE1_MP_RXP<2>") )
				( member ( signalRef "TP_P3E_CPU1_PE1_MP_RXP<3>") )
				( member ( signalRef "TP_P3E_CPU1_PE1_MP_RXP<4>") )
				( member ( signalRef "TP_P3E_CPU1_PE1_MP_RXP<5>") )
				( member ( signalRef "TP_P3E_CPU1_PE1_MP_RXP<6>") )
				( member ( signalRef "TP_P3E_CPU1_PE1_MP_RXP<7>") )
				( objectStatus "@baseboard_fab2_lib.baseboard_fab2(sch_1):tp_p3e_cpu1_pe1_mp_rxp" )
			)
			( bus "TP_P3E_CPU1_PE1_MP_TXN"
				( memberType ( signal ) )
				( member ( signalRef "TP_P3E_CPU1_PE1_MP_TXN<0>") )
				( member ( signalRef "TP_P3E_CPU1_PE1_MP_TXN<1>") )
				( member ( signalRef "TP_P3E_CPU1_PE1_MP_TXN<2>") )
				( member ( signalRef "TP_P3E_CPU1_PE1_MP_TXN<3>") )
				( member ( signalRef "TP_P3E_CPU1_PE1_MP_TXN<4>") )
				( member ( signalRef "TP_P3E_CPU1_PE1_MP_TXN<5>") )
				( member ( signalRef "TP_P3E_CPU1_PE1_MP_TXN<6>") )
				( member ( signalRef "TP_P3E_CPU1_PE1_MP_TXN<7>") )
				( objectStatus "@baseboard_fab2_lib.baseboard_fab2(sch_1):tp_p3e_cpu1_pe1_mp_txn" )
			)
			( bus "TP_P3E_CPU1_PE1_MP_TXP"
				( memberType ( signal ) )
				( member ( signalRef "TP_P3E_CPU1_PE1_MP_TXP<0>") )
				( member ( signalRef "TP_P3E_CPU1_PE1_MP_TXP<1>") )
				( member ( signalRef "TP_P3E_CPU1_PE1_MP_TXP<2>") )
				( member ( signalRef "TP_P3E_CPU1_PE1_MP_TXP<3>") )
				( member ( signalRef "TP_P3E_CPU1_PE1_MP_TXP<4>") )
				( member ( signalRef "TP_P3E_CPU1_PE1_MP_TXP<5>") )
				( member ( signalRef "TP_P3E_CPU1_PE1_MP_TXP<6>") )
				( member ( signalRef "TP_P3E_CPU1_PE1_MP_TXP<7>") )
				( objectStatus "@baseboard_fab2_lib.baseboard_fab2(sch_1):tp_p3e_cpu1_pe1_mp_txp" )
			)
			( bus "TP_P3E_CPU1_PE1_RSR3_RXN"
				( memberType ( signal ) )
				( member ( signalRef "TP_P3E_CPU1_PE1_RSR3_RXN<8>") )
				( member ( signalRef "TP_P3E_CPU1_PE1_RSR3_RXN<9>") )
				( member ( signalRef "TP_P3E_CPU1_PE1_RSR3_RXN<10>") )
				( member ( signalRef "TP_P3E_CPU1_PE1_RSR3_RXN<11>") )
				( member ( signalRef "TP_P3E_CPU1_PE1_RSR3_RXN<12>") )
				( member ( signalRef "TP_P3E_CPU1_PE1_RSR3_RXN<13>") )
				( member ( signalRef "TP_P3E_CPU1_PE1_RSR3_RXN<14>") )
				( member ( signalRef "TP_P3E_CPU1_PE1_RSR3_RXN<15>") )
				( objectStatus "@baseboard_fab2_lib.baseboard_fab2(sch_1):tp_p3e_cpu1_pe1_rsr3_rxn" )
			)
			( bus "TP_P3E_CPU1_PE1_RSR3_RXP"
				( memberType ( signal ) )
				( member ( signalRef "TP_P3E_CPU1_PE1_RSR3_RXP<8>") )
				( member ( signalRef "TP_P3E_CPU1_PE1_RSR3_RXP<9>") )
				( member ( signalRef "TP_P3E_CPU1_PE1_RSR3_RXP<10>") )
				( member ( signalRef "TP_P3E_CPU1_PE1_RSR3_RXP<11>") )
				( member ( signalRef "TP_P3E_CPU1_PE1_RSR3_RXP<12>") )
				( member ( signalRef "TP_P3E_CPU1_PE1_RSR3_RXP<13>") )
				( member ( signalRef "TP_P3E_CPU1_PE1_RSR3_RXP<14>") )
				( member ( signalRef "TP_P3E_CPU1_PE1_RSR3_RXP<15>") )
				( objectStatus "@baseboard_fab2_lib.baseboard_fab2(sch_1):tp_p3e_cpu1_pe1_rsr3_rxp" )
			)
			( bus "TP_P3E_CPU1_PE1_RSR3_TXN"
				( memberType ( signal ) )
				( member ( signalRef "TP_P3E_CPU1_PE1_RSR3_TXN<8>") )
				( member ( signalRef "TP_P3E_CPU1_PE1_RSR3_TXN<9>") )
				( member ( signalRef "TP_P3E_CPU1_PE1_RSR3_TXN<10>") )
				( member ( signalRef "TP_P3E_CPU1_PE1_RSR3_TXN<11>") )
				( member ( signalRef "TP_P3E_CPU1_PE1_RSR3_TXN<12>") )
				( member ( signalRef "TP_P3E_CPU1_PE1_RSR3_TXN<13>") )
				( member ( signalRef "TP_P3E_CPU1_PE1_RSR3_TXN<14>") )
				( member ( signalRef "TP_P3E_CPU1_PE1_RSR3_TXN<15>") )
				( objectStatus "@baseboard_fab2_lib.baseboard_fab2(sch_1):tp_p3e_cpu1_pe1_rsr3_txn" )
			)
			( bus "TP_P3E_CPU1_PE1_RSR3_TXP"
				( memberType ( signal ) )
				( member ( signalRef "TP_P3E_CPU1_PE1_RSR3_TXP<8>") )
				( member ( signalRef "TP_P3E_CPU1_PE1_RSR3_TXP<9>") )
				( member ( signalRef "TP_P3E_CPU1_PE1_RSR3_TXP<10>") )
				( member ( signalRef "TP_P3E_CPU1_PE1_RSR3_TXP<11>") )
				( member ( signalRef "TP_P3E_CPU1_PE1_RSR3_TXP<12>") )
				( member ( signalRef "TP_P3E_CPU1_PE1_RSR3_TXP<13>") )
				( member ( signalRef "TP_P3E_CPU1_PE1_RSR3_TXP<14>") )
				( member ( signalRef "TP_P3E_CPU1_PE1_RSR3_TXP<15>") )
				( objectStatus "@baseboard_fab2_lib.baseboard_fab2(sch_1):tp_p3e_cpu1_pe1_rsr3_txp" )
			)
			( bus "TP_P3E_CPU1_PE2_RSR_RXN"
				( memberType ( signal ) )
				( member ( signalRef "TP_P3E_CPU1_PE2_RSR_RXN<0>") )
				( member ( signalRef "TP_P3E_CPU1_PE2_RSR_RXN<1>") )
				( member ( signalRef "TP_P3E_CPU1_PE2_RSR_RXN<2>") )
				( member ( signalRef "TP_P3E_CPU1_PE2_RSR_RXN<3>") )
				( member ( signalRef "TP_P3E_CPU1_PE2_RSR_RXN<4>") )
				( member ( signalRef "TP_P3E_CPU1_PE2_RSR_RXN<5>") )
				( member ( signalRef "TP_P3E_CPU1_PE2_RSR_RXN<6>") )
				( member ( signalRef "TP_P3E_CPU1_PE2_RSR_RXN<7>") )
				( member ( signalRef "TP_P3E_CPU1_PE2_RSR_RXN<8>") )
				( member ( signalRef "TP_P3E_CPU1_PE2_RSR_RXN<9>") )
				( member ( signalRef "TP_P3E_CPU1_PE2_RSR_RXN<10>") )
				( member ( signalRef "TP_P3E_CPU1_PE2_RSR_RXN<11>") )
				( member ( signalRef "TP_P3E_CPU1_PE2_RSR_RXN<12>") )
				( member ( signalRef "TP_P3E_CPU1_PE2_RSR_RXN<13>") )
				( member ( signalRef "TP_P3E_CPU1_PE2_RSR_RXN<14>") )
				( member ( signalRef "TP_P3E_CPU1_PE2_RSR_RXN<15>") )
				( objectStatus "@baseboard_fab2_lib.baseboard_fab2(sch_1):tp_p3e_cpu1_pe2_rsr_rxn" )
			)
			( bus "TP_P3E_CPU1_PE2_RSR_RXP"
				( memberType ( signal ) )
				( member ( signalRef "TP_P3E_CPU1_PE2_RSR_RXP<0>") )
				( member ( signalRef "TP_P3E_CPU1_PE2_RSR_RXP<1>") )
				( member ( signalRef "TP_P3E_CPU1_PE2_RSR_RXP<2>") )
				( member ( signalRef "TP_P3E_CPU1_PE2_RSR_RXP<3>") )
				( member ( signalRef "TP_P3E_CPU1_PE2_RSR_RXP<4>") )
				( member ( signalRef "TP_P3E_CPU1_PE2_RSR_RXP<5>") )
				( member ( signalRef "TP_P3E_CPU1_PE2_RSR_RXP<6>") )
				( member ( signalRef "TP_P3E_CPU1_PE2_RSR_RXP<7>") )
				( member ( signalRef "TP_P3E_CPU1_PE2_RSR_RXP<8>") )
				( member ( signalRef "TP_P3E_CPU1_PE2_RSR_RXP<9>") )
				( member ( signalRef "TP_P3E_CPU1_PE2_RSR_RXP<10>") )
				( member ( signalRef "TP_P3E_CPU1_PE2_RSR_RXP<11>") )
				( member ( signalRef "TP_P3E_CPU1_PE2_RSR_RXP<12>") )
				( member ( signalRef "TP_P3E_CPU1_PE2_RSR_RXP<13>") )
				( member ( signalRef "TP_P3E_CPU1_PE2_RSR_RXP<14>") )
				( member ( signalRef "TP_P3E_CPU1_PE2_RSR_RXP<15>") )
				( objectStatus "@baseboard_fab2_lib.baseboard_fab2(sch_1):tp_p3e_cpu1_pe2_rsr_rxp" )
			)
			( bus "TP_P3E_CPU1_PE2_RSR_TXN"
				( memberType ( signal ) )
				( member ( signalRef "TP_P3E_CPU1_PE2_RSR_TXN<0>") )
				( member ( signalRef "TP_P3E_CPU1_PE2_RSR_TXN<1>") )
				( member ( signalRef "TP_P3E_CPU1_PE2_RSR_TXN<2>") )
				( member ( signalRef "TP_P3E_CPU1_PE2_RSR_TXN<3>") )
				( member ( signalRef "TP_P3E_CPU1_PE2_RSR_TXN<4>") )
				( member ( signalRef "TP_P3E_CPU1_PE2_RSR_TXN<5>") )
				( member ( signalRef "TP_P3E_CPU1_PE2_RSR_TXN<6>") )
				( member ( signalRef "TP_P3E_CPU1_PE2_RSR_TXN<7>") )
				( member ( signalRef "TP_P3E_CPU1_PE2_RSR_TXN<8>") )
				( member ( signalRef "TP_P3E_CPU1_PE2_RSR_TXN<9>") )
				( member ( signalRef "TP_P3E_CPU1_PE2_RSR_TXN<10>") )
				( member ( signalRef "TP_P3E_CPU1_PE2_RSR_TXN<11>") )
				( member ( signalRef "TP_P3E_CPU1_PE2_RSR_TXN<12>") )
				( member ( signalRef "TP_P3E_CPU1_PE2_RSR_TXN<13>") )
				( member ( signalRef "TP_P3E_CPU1_PE2_RSR_TXN<14>") )
				( member ( signalRef "TP_P3E_CPU1_PE2_RSR_TXN<15>") )
				( objectStatus "@baseboard_fab2_lib.baseboard_fab2(sch_1):tp_p3e_cpu1_pe2_rsr_txn" )
			)
			( bus "TP_P3E_CPU1_PE2_RSR_TXP"
				( memberType ( signal ) )
				( member ( signalRef "TP_P3E_CPU1_PE2_RSR_TXP<0>") )
				( member ( signalRef "TP_P3E_CPU1_PE2_RSR_TXP<1>") )
				( member ( signalRef "TP_P3E_CPU1_PE2_RSR_TXP<2>") )
				( member ( signalRef "TP_P3E_CPU1_PE2_RSR_TXP<3>") )
				( member ( signalRef "TP_P3E_CPU1_PE2_RSR_TXP<4>") )
				( member ( signalRef "TP_P3E_CPU1_PE2_RSR_TXP<5>") )
				( member ( signalRef "TP_P3E_CPU1_PE2_RSR_TXP<6>") )
				( member ( signalRef "TP_P3E_CPU1_PE2_RSR_TXP<7>") )
				( member ( signalRef "TP_P3E_CPU1_PE2_RSR_TXP<8>") )
				( member ( signalRef "TP_P3E_CPU1_PE2_RSR_TXP<9>") )
				( member ( signalRef "TP_P3E_CPU1_PE2_RSR_TXP<10>") )
				( member ( signalRef "TP_P3E_CPU1_PE2_RSR_TXP<11>") )
				( member ( signalRef "TP_P3E_CPU1_PE2_RSR_TXP<12>") )
				( member ( signalRef "TP_P3E_CPU1_PE2_RSR_TXP<13>") )
				( member ( signalRef "TP_P3E_CPU1_PE2_RSR_TXP<14>") )
				( member ( signalRef "TP_P3E_CPU1_PE2_RSR_TXP<15>") )
				( objectStatus "@baseboard_fab2_lib.baseboard_fab2(sch_1):tp_p3e_cpu1_pe2_rsr_txp" )
			)
			( bus "P3E_CPU1_PE3_MP_RXN"
				( memberType ( signal ) )
				( member ( signalRef "P3E_CPU1_PE3_MP_RXN<0>") )
				( member ( signalRef "P3E_CPU1_PE3_MP_RXN<1>") )
				( member ( signalRef "P3E_CPU1_PE3_MP_RXN<2>") )
				( member ( signalRef "P3E_CPU1_PE3_MP_RXN<3>") )
				( member ( signalRef "P3E_CPU1_PE3_MP_RXN<4>") )
				( member ( signalRef "P3E_CPU1_PE3_MP_RXN<5>") )
				( member ( signalRef "P3E_CPU1_PE3_MP_RXN<6>") )
				( member ( signalRef "P3E_CPU1_PE3_MP_RXN<7>") )
				( member ( signalRef "P3E_CPU1_PE3_MP_RXN<8>") )
				( member ( signalRef "P3E_CPU1_PE3_MP_RXN<9>") )
				( member ( signalRef "P3E_CPU1_PE3_MP_RXN<10>") )
				( member ( signalRef "P3E_CPU1_PE3_MP_RXN<11>") )
				( member ( signalRef "P3E_CPU1_PE3_MP_RXN<12>") )
				( member ( signalRef "P3E_CPU1_PE3_MP_RXN<13>") )
				( member ( signalRef "P3E_CPU1_PE3_MP_RXN<14>") )
				( member ( signalRef "P3E_CPU1_PE3_MP_RXN<15>") )
				( objectStatus "@baseboard_fab2_lib.baseboard_fab2(sch_1):p3e_cpu1_pe3_mp_rxn" )
			)
			( bus "P3E_CPU1_PE3_MP_RXP"
				( memberType ( signal ) )
				( member ( signalRef "P3E_CPU1_PE3_MP_RXP<0>") )
				( member ( signalRef "P3E_CPU1_PE3_MP_RXP<1>") )
				( member ( signalRef "P3E_CPU1_PE3_MP_RXP<2>") )
				( member ( signalRef "P3E_CPU1_PE3_MP_RXP<3>") )
				( member ( signalRef "P3E_CPU1_PE3_MP_RXP<4>") )
				( member ( signalRef "P3E_CPU1_PE3_MP_RXP<5>") )
				( member ( signalRef "P3E_CPU1_PE3_MP_RXP<6>") )
				( member ( signalRef "P3E_CPU1_PE3_MP_RXP<7>") )
				( member ( signalRef "P3E_CPU1_PE3_MP_RXP<8>") )
				( member ( signalRef "P3E_CPU1_PE3_MP_RXP<9>") )
				( member ( signalRef "P3E_CPU1_PE3_MP_RXP<10>") )
				( member ( signalRef "P3E_CPU1_PE3_MP_RXP<11>") )
				( member ( signalRef "P3E_CPU1_PE3_MP_RXP<12>") )
				( member ( signalRef "P3E_CPU1_PE3_MP_RXP<13>") )
				( member ( signalRef "P3E_CPU1_PE3_MP_RXP<14>") )
				( member ( signalRef "P3E_CPU1_PE3_MP_RXP<15>") )
				( objectStatus "@baseboard_fab2_lib.baseboard_fab2(sch_1):p3e_cpu1_pe3_mp_rxp" )
			)
			( bus "P3E_CPU1_PE3_MP_TXN"
				( memberType ( signal ) )
				( member ( signalRef "P3E_CPU1_PE3_MP_TXN<0>") )
				( member ( signalRef "P3E_CPU1_PE3_MP_TXN<1>") )
				( member ( signalRef "P3E_CPU1_PE3_MP_TXN<2>") )
				( member ( signalRef "P3E_CPU1_PE3_MP_TXN<3>") )
				( member ( signalRef "P3E_CPU1_PE3_MP_TXN<4>") )
				( member ( signalRef "P3E_CPU1_PE3_MP_TXN<5>") )
				( member ( signalRef "P3E_CPU1_PE3_MP_TXN<6>") )
				( member ( signalRef "P3E_CPU1_PE3_MP_TXN<7>") )
				( member ( signalRef "P3E_CPU1_PE3_MP_TXN<8>") )
				( member ( signalRef "P3E_CPU1_PE3_MP_TXN<9>") )
				( member ( signalRef "P3E_CPU1_PE3_MP_TXN<10>") )
				( member ( signalRef "P3E_CPU1_PE3_MP_TXN<11>") )
				( member ( signalRef "P3E_CPU1_PE3_MP_TXN<12>") )
				( member ( signalRef "P3E_CPU1_PE3_MP_TXN<13>") )
				( member ( signalRef "P3E_CPU1_PE3_MP_TXN<14>") )
				( member ( signalRef "P3E_CPU1_PE3_MP_TXN<15>") )
				( objectStatus "@baseboard_fab2_lib.baseboard_fab2(sch_1):p3e_cpu1_pe3_mp_txn" )
			)
			( bus "P3E_CPU1_PE3_MP_TXP"
				( memberType ( signal ) )
				( member ( signalRef "P3E_CPU1_PE3_MP_TXP<0>") )
				( member ( signalRef "P3E_CPU1_PE3_MP_TXP<1>") )
				( member ( signalRef "P3E_CPU1_PE3_MP_TXP<2>") )
				( member ( signalRef "P3E_CPU1_PE3_MP_TXP<3>") )
				( member ( signalRef "P3E_CPU1_PE3_MP_TXP<4>") )
				( member ( signalRef "P3E_CPU1_PE3_MP_TXP<5>") )
				( member ( signalRef "P3E_CPU1_PE3_MP_TXP<6>") )
				( member ( signalRef "P3E_CPU1_PE3_MP_TXP<7>") )
				( member ( signalRef "P3E_CPU1_PE3_MP_TXP<8>") )
				( member ( signalRef "P3E_CPU1_PE3_MP_TXP<9>") )
				( member ( signalRef "P3E_CPU1_PE3_MP_TXP<10>") )
				( member ( signalRef "P3E_CPU1_PE3_MP_TXP<11>") )
				( member ( signalRef "P3E_CPU1_PE3_MP_TXP<12>") )
				( member ( signalRef "P3E_CPU1_PE3_MP_TXP<13>") )
				( member ( signalRef "P3E_CPU1_PE3_MP_TXP<14>") )
				( member ( signalRef "P3E_CPU1_PE3_MP_TXP<15>") )
				( objectStatus "@baseboard_fab2_lib.baseboard_fab2(sch_1):p3e_cpu1_pe3_mp_txp" )
			)
			( bus "NC_DB1200ZL"
				( memberType ( signal ) )
				( member ( signalRef "NC_DB1200ZL<0>") )
				( member ( signalRef "NC_DB1200ZL<1>") )
				( member ( signalRef "NC_DB1200ZL<2>") )
				( objectStatus "@baseboard_fab2_lib.baseboard_fab2(sch_1):nc_db1200zl" )
			)
			( bus "P3E_CPU0_PE1_PCH_C_TXN"
				( memberType ( signal ) )
				( member ( signalRef "P3E_CPU0_PE1_PCH_C_TXN<8>") )
				( member ( signalRef "P3E_CPU0_PE1_PCH_C_TXN<9>") )
				( member ( signalRef "P3E_CPU0_PE1_PCH_C_TXN<10>") )
				( member ( signalRef "P3E_CPU0_PE1_PCH_C_TXN<11>") )
				( member ( signalRef "P3E_CPU0_PE1_PCH_C_TXN<12>") )
				( member ( signalRef "P3E_CPU0_PE1_PCH_C_TXN<13>") )
				( member ( signalRef "P3E_CPU0_PE1_PCH_C_TXN<14>") )
				( member ( signalRef "P3E_CPU0_PE1_PCH_C_TXN<15>") )
				( objectStatus "@baseboard_fab2_lib.baseboard_fab2(sch_1):p3e_cpu0_pe1_pch_c_txn" )
			)
			( bus "P3E_CPU0_PE1_PCH_C_TXP"
				( memberType ( signal ) )
				( member ( signalRef "P3E_CPU0_PE1_PCH_C_TXP<8>") )
				( member ( signalRef "P3E_CPU0_PE1_PCH_C_TXP<9>") )
				( member ( signalRef "P3E_CPU0_PE1_PCH_C_TXP<10>") )
				( member ( signalRef "P3E_CPU0_PE1_PCH_C_TXP<11>") )
				( member ( signalRef "P3E_CPU0_PE1_PCH_C_TXP<12>") )
				( member ( signalRef "P3E_CPU0_PE1_PCH_C_TXP<13>") )
				( member ( signalRef "P3E_CPU0_PE1_PCH_C_TXP<14>") )
				( member ( signalRef "P3E_CPU0_PE1_PCH_C_TXP<15>") )
				( objectStatus "@baseboard_fab2_lib.baseboard_fab2(sch_1):p3e_cpu0_pe1_pch_c_txp" )
			)
			( bus "P3E_CPU0_PE1_PCH_R_RXN"
				( memberType ( signal ) )
				( member ( signalRef "P3E_CPU0_PE1_PCH_R_RXN<8>") )
				( member ( signalRef "P3E_CPU0_PE1_PCH_R_RXN<9>") )
				( member ( signalRef "P3E_CPU0_PE1_PCH_R_RXN<10>") )
				( member ( signalRef "P3E_CPU0_PE1_PCH_R_RXN<11>") )
				( member ( signalRef "P3E_CPU0_PE1_PCH_R_RXN<12>") )
				( member ( signalRef "P3E_CPU0_PE1_PCH_R_RXN<13>") )
				( member ( signalRef "P3E_CPU0_PE1_PCH_R_RXN<14>") )
				( member ( signalRef "P3E_CPU0_PE1_PCH_R_RXN<15>") )
				( objectStatus "@baseboard_fab2_lib.baseboard_fab2(sch_1):p3e_cpu0_pe1_pch_r_rxn" )
			)
			( bus "P3E_CPU0_PE1_PCH_R_RXP"
				( memberType ( signal ) )
				( member ( signalRef "P3E_CPU0_PE1_PCH_R_RXP<8>") )
				( member ( signalRef "P3E_CPU0_PE1_PCH_R_RXP<9>") )
				( member ( signalRef "P3E_CPU0_PE1_PCH_R_RXP<10>") )
				( member ( signalRef "P3E_CPU0_PE1_PCH_R_RXP<11>") )
				( member ( signalRef "P3E_CPU0_PE1_PCH_R_RXP<12>") )
				( member ( signalRef "P3E_CPU0_PE1_PCH_R_RXP<13>") )
				( member ( signalRef "P3E_CPU0_PE1_PCH_R_RXP<14>") )
				( member ( signalRef "P3E_CPU0_PE1_PCH_R_RXP<15>") )
				( objectStatus "@baseboard_fab2_lib.baseboard_fab2(sch_1):p3e_cpu0_pe1_pch_r_rxp" )
			)
			( bus "P3E_CPU0_PE2_SS_C_TXN"
				( memberType ( signal ) )
				( member ( signalRef "P3E_CPU0_PE2_SS_C_TXN<0>") )
				( member ( signalRef "P3E_CPU0_PE2_SS_C_TXN<1>") )
				( member ( signalRef "P3E_CPU0_PE2_SS_C_TXN<2>") )
				( member ( signalRef "P3E_CPU0_PE2_SS_C_TXN<3>") )
				( member ( signalRef "P3E_CPU0_PE2_SS_C_TXN<4>") )
				( member ( signalRef "P3E_CPU0_PE2_SS_C_TXN<5>") )
				( member ( signalRef "P3E_CPU0_PE2_SS_C_TXN<6>") )
				( member ( signalRef "P3E_CPU0_PE2_SS_C_TXN<7>") )
				( member ( signalRef "P3E_CPU0_PE2_SS_C_TXN<8>") )
				( member ( signalRef "P3E_CPU0_PE2_SS_C_TXN<9>") )
				( member ( signalRef "P3E_CPU0_PE2_SS_C_TXN<10>") )
				( member ( signalRef "P3E_CPU0_PE2_SS_C_TXN<11>") )
				( member ( signalRef "P3E_CPU0_PE2_SS_C_TXN<12>") )
				( member ( signalRef "P3E_CPU0_PE2_SS_C_TXN<13>") )
				( member ( signalRef "P3E_CPU0_PE2_SS_C_TXN<14>") )
				( member ( signalRef "P3E_CPU0_PE2_SS_C_TXN<15>") )
				( objectStatus "@baseboard_fab2_lib.baseboard_fab2(sch_1):p3e_cpu0_pe2_ss_c_txn" )
			)
			( bus "P3E_CPU0_PE2_SS_C_TXP"
				( memberType ( signal ) )
				( member ( signalRef "P3E_CPU0_PE2_SS_C_TXP<0>") )
				( member ( signalRef "P3E_CPU0_PE2_SS_C_TXP<1>") )
				( member ( signalRef "P3E_CPU0_PE2_SS_C_TXP<2>") )
				( member ( signalRef "P3E_CPU0_PE2_SS_C_TXP<3>") )
				( member ( signalRef "P3E_CPU0_PE2_SS_C_TXP<4>") )
				( member ( signalRef "P3E_CPU0_PE2_SS_C_TXP<5>") )
				( member ( signalRef "P3E_CPU0_PE2_SS_C_TXP<6>") )
				( member ( signalRef "P3E_CPU0_PE2_SS_C_TXP<7>") )
				( member ( signalRef "P3E_CPU0_PE2_SS_C_TXP<8>") )
				( member ( signalRef "P3E_CPU0_PE2_SS_C_TXP<9>") )
				( member ( signalRef "P3E_CPU0_PE2_SS_C_TXP<10>") )
				( member ( signalRef "P3E_CPU0_PE2_SS_C_TXP<11>") )
				( member ( signalRef "P3E_CPU0_PE2_SS_C_TXP<12>") )
				( member ( signalRef "P3E_CPU0_PE2_SS_C_TXP<13>") )
				( member ( signalRef "P3E_CPU0_PE2_SS_C_TXP<14>") )
				( member ( signalRef "P3E_CPU0_PE2_SS_C_TXP<15>") )
				( objectStatus "@baseboard_fab2_lib.baseboard_fab2(sch_1):p3e_cpu0_pe2_ss_c_txp" )
			)
			( bus "P3E_OCP_CPU0_PE3_C_TXN"
				( memberType ( signal ) )
				( member ( signalRef "P3E_OCP_CPU0_PE3_C_TXN<0>") )
				( member ( signalRef "P3E_OCP_CPU0_PE3_C_TXN<1>") )
				( member ( signalRef "P3E_OCP_CPU0_PE3_C_TXN<2>") )
				( member ( signalRef "P3E_OCP_CPU0_PE3_C_TXN<3>") )
				( member ( signalRef "P3E_OCP_CPU0_PE3_C_TXN<4>") )
				( member ( signalRef "P3E_OCP_CPU0_PE3_C_TXN<5>") )
				( member ( signalRef "P3E_OCP_CPU0_PE3_C_TXN<6>") )
				( member ( signalRef "P3E_OCP_CPU0_PE3_C_TXN<7>") )
				( member ( signalRef "P3E_OCP_CPU0_PE3_C_TXN<8>") )
				( member ( signalRef "P3E_OCP_CPU0_PE3_C_TXN<9>") )
				( member ( signalRef "P3E_OCP_CPU0_PE3_C_TXN<10>") )
				( member ( signalRef "P3E_OCP_CPU0_PE3_C_TXN<11>") )
				( member ( signalRef "P3E_OCP_CPU0_PE3_C_TXN<12>") )
				( member ( signalRef "P3E_OCP_CPU0_PE3_C_TXN<13>") )
				( member ( signalRef "P3E_OCP_CPU0_PE3_C_TXN<14>") )
				( member ( signalRef "P3E_OCP_CPU0_PE3_C_TXN<15>") )
				( objectStatus "@baseboard_fab2_lib.baseboard_fab2(sch_1):p3e_ocp_cpu0_pe3_c_txn" )
			)
			( bus "P3E_OCP_CPU0_PE3_C_TXP"
				( memberType ( signal ) )
				( member ( signalRef "P3E_OCP_CPU0_PE3_C_TXP<0>") )
				( member ( signalRef "P3E_OCP_CPU0_PE3_C_TXP<1>") )
				( member ( signalRef "P3E_OCP_CPU0_PE3_C_TXP<2>") )
				( member ( signalRef "P3E_OCP_CPU0_PE3_C_TXP<3>") )
				( member ( signalRef "P3E_OCP_CPU0_PE3_C_TXP<4>") )
				( member ( signalRef "P3E_OCP_CPU0_PE3_C_TXP<5>") )
				( member ( signalRef "P3E_OCP_CPU0_PE3_C_TXP<6>") )
				( member ( signalRef "P3E_OCP_CPU0_PE3_C_TXP<7>") )
				( member ( signalRef "P3E_OCP_CPU0_PE3_C_TXP<8>") )
				( member ( signalRef "P3E_OCP_CPU0_PE3_C_TXP<9>") )
				( member ( signalRef "P3E_OCP_CPU0_PE3_C_TXP<10>") )
				( member ( signalRef "P3E_OCP_CPU0_PE3_C_TXP<11>") )
				( member ( signalRef "P3E_OCP_CPU0_PE3_C_TXP<12>") )
				( member ( signalRef "P3E_OCP_CPU0_PE3_C_TXP<13>") )
				( member ( signalRef "P3E_OCP_CPU0_PE3_C_TXP<14>") )
				( member ( signalRef "P3E_OCP_CPU0_PE3_C_TXP<15>") )
				( objectStatus "@baseboard_fab2_lib.baseboard_fab2(sch_1):p3e_ocp_cpu0_pe3_c_txp" )
			)
			( bus "P3E_CPU0_PE1_SS_C_TXN"
				( memberType ( signal ) )
				( member ( signalRef "P3E_CPU0_PE1_SS_C_TXN<0>") )
				( member ( signalRef "P3E_CPU0_PE1_SS_C_TXN<1>") )
				( member ( signalRef "P3E_CPU0_PE1_SS_C_TXN<2>") )
				( member ( signalRef "P3E_CPU0_PE1_SS_C_TXN<3>") )
				( member ( signalRef "P3E_CPU0_PE1_SS_C_TXN<4>") )
				( member ( signalRef "P3E_CPU0_PE1_SS_C_TXN<5>") )
				( member ( signalRef "P3E_CPU0_PE1_SS_C_TXN<6>") )
				( member ( signalRef "P3E_CPU0_PE1_SS_C_TXN<7>") )
				( objectStatus "@baseboard_fab2_lib.baseboard_fab2(sch_1):p3e_cpu0_pe1_ss_c_txn" )
			)
			( bus "P3E_CPU0_PE1_SS_C_TXP"
				( memberType ( signal ) )
				( member ( signalRef "P3E_CPU0_PE1_SS_C_TXP<0>") )
				( member ( signalRef "P3E_CPU0_PE1_SS_C_TXP<1>") )
				( member ( signalRef "P3E_CPU0_PE1_SS_C_TXP<2>") )
				( member ( signalRef "P3E_CPU0_PE1_SS_C_TXP<3>") )
				( member ( signalRef "P3E_CPU0_PE1_SS_C_TXP<4>") )
				( member ( signalRef "P3E_CPU0_PE1_SS_C_TXP<5>") )
				( member ( signalRef "P3E_CPU0_PE1_SS_C_TXP<6>") )
				( member ( signalRef "P3E_CPU0_PE1_SS_C_TXP<7>") )
				( objectStatus "@baseboard_fab2_lib.baseboard_fab2(sch_1):p3e_cpu0_pe1_ss_c_txp" )
			)
			( bus "P3E_CPU0_PE1_SS_R_RXN"
				( memberType ( signal ) )
				( member ( signalRef "P3E_CPU0_PE1_SS_R_RXN<0>") )
				( member ( signalRef "P3E_CPU0_PE1_SS_R_RXN<1>") )
				( member ( signalRef "P3E_CPU0_PE1_SS_R_RXN<2>") )
				( member ( signalRef "P3E_CPU0_PE1_SS_R_RXN<3>") )
				( member ( signalRef "P3E_CPU0_PE1_SS_R_RXN<4>") )
				( member ( signalRef "P3E_CPU0_PE1_SS_R_RXN<5>") )
				( member ( signalRef "P3E_CPU0_PE1_SS_R_RXN<6>") )
				( member ( signalRef "P3E_CPU0_PE1_SS_R_RXN<7>") )
				( objectStatus "@baseboard_fab2_lib.baseboard_fab2(sch_1):p3e_cpu0_pe1_ss_r_rxn" )
			)
			( bus "P3E_CPU0_PE1_SS_R_RXP"
				( memberType ( signal ) )
				( member ( signalRef "P3E_CPU0_PE1_SS_R_RXP<0>") )
				( member ( signalRef "P3E_CPU0_PE1_SS_R_RXP<1>") )
				( member ( signalRef "P3E_CPU0_PE1_SS_R_RXP<2>") )
				( member ( signalRef "P3E_CPU0_PE1_SS_R_RXP<3>") )
				( member ( signalRef "P3E_CPU0_PE1_SS_R_RXP<4>") )
				( member ( signalRef "P3E_CPU0_PE1_SS_R_RXP<5>") )
				( member ( signalRef "P3E_CPU0_PE1_SS_R_RXP<6>") )
				( member ( signalRef "P3E_CPU0_PE1_SS_R_RXP<7>") )
				( objectStatus "@baseboard_fab2_lib.baseboard_fab2(sch_1):p3e_cpu0_pe1_ss_r_rxp" )
			)
			( bus "P3E_PCH_M2_RX_DN"
				( memberType ( signal ) )
				( member ( signalRef "P3E_PCH_M2_RX_DN<1>") )
				( member ( signalRef "P3E_PCH_M2_RX_DN<2>") )
				( member ( signalRef "P3E_PCH_M2_RX_DN<3>") )
				( objectStatus "@baseboard_fab2_lib.baseboard_fab2(sch_1):p3e_pch_m2_rx_dn" )
			)
			( bus "P3E_PCH_M2_RX_DP"
				( memberType ( signal ) )
				( member ( signalRef "P3E_PCH_M2_RX_DP<1>") )
				( member ( signalRef "P3E_PCH_M2_RX_DP<2>") )
				( member ( signalRef "P3E_PCH_M2_RX_DP<3>") )
				( objectStatus "@baseboard_fab2_lib.baseboard_fab2(sch_1):p3e_pch_m2_rx_dp" )
			)
			( bus "P3E_PCH_M2_TX_DN"
				( memberType ( signal ) )
				( member ( signalRef "P3E_PCH_M2_TX_DN<1>") )
				( member ( signalRef "P3E_PCH_M2_TX_DN<2>") )
				( member ( signalRef "P3E_PCH_M2_TX_DN<3>") )
				( objectStatus "@baseboard_fab2_lib.baseboard_fab2(sch_1):p3e_pch_m2_tx_dn" )
			)
			( bus "P3E_PCH_M2_TX_DP"
				( memberType ( signal ) )
				( member ( signalRef "P3E_PCH_M2_TX_DP<1>") )
				( member ( signalRef "P3E_PCH_M2_TX_DP<2>") )
				( member ( signalRef "P3E_PCH_M2_TX_DP<3>") )
				( objectStatus "@baseboard_fab2_lib.baseboard_fab2(sch_1):p3e_pch_m2_tx_dp" )
			)
			( bus "SATA6G_PCH_PCIE_UP_SATA_RXN"
				( memberType ( signal ) )
				( member ( signalRef "SATA6G_PCH_PCIE_UP_SATA_RXN<0>") )
				( member ( signalRef "SATA6G_PCH_PCIE_UP_SATA_RXN<1>") )
				( member ( signalRef "SATA6G_PCH_PCIE_UP_SATA_RXN<2>") )
				( member ( signalRef "SATA6G_PCH_PCIE_UP_SATA_RXN<3>") )
				( member ( signalRef "SATA6G_PCH_PCIE_UP_SATA_RXN<4>") )
				( member ( signalRef "SATA6G_PCH_PCIE_UP_SATA_RXN<5>") )
				( member ( signalRef "SATA6G_PCH_PCIE_UP_SATA_RXN<6>") )
				( member ( signalRef "SATA6G_PCH_PCIE_UP_SATA_RXN<7>") )
				( objectStatus "@baseboard_fab2_lib.baseboard_fab2(sch_1):sata6g_pch_pcie_up_sata_rxn" )
			)
			( bus "SATA6G_PCH_PCIE_UP_SATA_RXP"
				( memberType ( signal ) )
				( member ( signalRef "SATA6G_PCH_PCIE_UP_SATA_RXP<0>") )
				( member ( signalRef "SATA6G_PCH_PCIE_UP_SATA_RXP<1>") )
				( member ( signalRef "SATA6G_PCH_PCIE_UP_SATA_RXP<2>") )
				( member ( signalRef "SATA6G_PCH_PCIE_UP_SATA_RXP<3>") )
				( member ( signalRef "SATA6G_PCH_PCIE_UP_SATA_RXP<4>") )
				( member ( signalRef "SATA6G_PCH_PCIE_UP_SATA_RXP<5>") )
				( member ( signalRef "SATA6G_PCH_PCIE_UP_SATA_RXP<6>") )
				( member ( signalRef "SATA6G_PCH_PCIE_UP_SATA_RXP<7>") )
				( objectStatus "@baseboard_fab2_lib.baseboard_fab2(sch_1):sata6g_pch_pcie_up_sata_rxp" )
			)
			( bus "SATA6G_PCH_PCIE_UP_SATA_TXN"
				( memberType ( signal ) )
				( member ( signalRef "SATA6G_PCH_PCIE_UP_SATA_TXN<0>") )
				( member ( signalRef "SATA6G_PCH_PCIE_UP_SATA_TXN<1>") )
				( member ( signalRef "SATA6G_PCH_PCIE_UP_SATA_TXN<2>") )
				( member ( signalRef "SATA6G_PCH_PCIE_UP_SATA_TXN<3>") )
				( member ( signalRef "SATA6G_PCH_PCIE_UP_SATA_TXN<4>") )
				( member ( signalRef "SATA6G_PCH_PCIE_UP_SATA_TXN<5>") )
				( member ( signalRef "SATA6G_PCH_PCIE_UP_SATA_TXN<6>") )
				( member ( signalRef "SATA6G_PCH_PCIE_UP_SATA_TXN<7>") )
				( objectStatus "@baseboard_fab2_lib.baseboard_fab2(sch_1):sata6g_pch_pcie_up_sata_txn" )
			)
			( bus "SATA6G_PCH_PCIE_UP_SATA_TXP"
				( memberType ( signal ) )
				( member ( signalRef "SATA6G_PCH_PCIE_UP_SATA_TXP<0>") )
				( member ( signalRef "SATA6G_PCH_PCIE_UP_SATA_TXP<1>") )
				( member ( signalRef "SATA6G_PCH_PCIE_UP_SATA_TXP<2>") )
				( member ( signalRef "SATA6G_PCH_PCIE_UP_SATA_TXP<3>") )
				( member ( signalRef "SATA6G_PCH_PCIE_UP_SATA_TXP<4>") )
				( member ( signalRef "SATA6G_PCH_PCIE_UP_SATA_TXP<5>") )
				( member ( signalRef "SATA6G_PCH_PCIE_UP_SATA_TXP<6>") )
				( member ( signalRef "SATA6G_PCH_PCIE_UP_SATA_TXP<7>") )
				( objectStatus "@baseboard_fab2_lib.baseboard_fab2(sch_1):sata6g_pch_pcie_up_sata_txp" )
			)
			( bus "SATA6G_RX_DN"
				( memberType ( signal ) )
				( member ( signalRef "SATA6G_RX_DN<0>") )
				( member ( signalRef "SATA6G_RX_DN<1>") )
				( member ( signalRef "SATA6G_RX_DN<2>") )
				( member ( signalRef "SATA6G_RX_DN<3>") )
				( objectStatus "@baseboard_fab2_lib.baseboard_fab2(sch_1):sata6g_rx_dn" )
			)
			( bus "SATA6G_RX_DP"
				( memberType ( signal ) )
				( member ( signalRef "SATA6G_RX_DP<0>") )
				( member ( signalRef "SATA6G_RX_DP<1>") )
				( member ( signalRef "SATA6G_RX_DP<2>") )
				( member ( signalRef "SATA6G_RX_DP<3>") )
				( objectStatus "@baseboard_fab2_lib.baseboard_fab2(sch_1):sata6g_rx_dp" )
			)
			( bus "SATA6G_TX_DN"
				( memberType ( signal ) )
				( member ( signalRef "SATA6G_TX_DN<0>") )
				( member ( signalRef "SATA6G_TX_DN<1>") )
				( member ( signalRef "SATA6G_TX_DN<2>") )
				( member ( signalRef "SATA6G_TX_DN<3>") )
				( objectStatus "@baseboard_fab2_lib.baseboard_fab2(sch_1):sata6g_tx_dn" )
			)
			( bus "SATA6G_TX_DP"
				( memberType ( signal ) )
				( member ( signalRef "SATA6G_TX_DP<0>") )
				( member ( signalRef "SATA6G_TX_DP<1>") )
				( member ( signalRef "SATA6G_TX_DP<2>") )
				( member ( signalRef "SATA6G_TX_DP<3>") )
				( objectStatus "@baseboard_fab2_lib.baseboard_fab2(sch_1):sata6g_tx_dp" )
			)
			( bus "DMI_CPU0_PCH_RX_DN"
				( memberType ( signal ) )
				( member ( signalRef "DMI_CPU0_PCH_RX_DN<0>") )
				( member ( signalRef "DMI_CPU0_PCH_RX_DN<1>") )
				( member ( signalRef "DMI_CPU0_PCH_RX_DN<2>") )
				( member ( signalRef "DMI_CPU0_PCH_RX_DN<3>") )
				( objectStatus "@baseboard_fab2_lib.baseboard_fab2(sch_1):dmi_cpu0_pch_rx_dn" )
			)
			( bus "DMI_CPU0_PCH_RX_DP"
				( memberType ( signal ) )
				( member ( signalRef "DMI_CPU0_PCH_RX_DP<0>") )
				( member ( signalRef "DMI_CPU0_PCH_RX_DP<1>") )
				( member ( signalRef "DMI_CPU0_PCH_RX_DP<2>") )
				( member ( signalRef "DMI_CPU0_PCH_RX_DP<3>") )
				( objectStatus "@baseboard_fab2_lib.baseboard_fab2(sch_1):dmi_cpu0_pch_rx_dp" )
			)
			( bus "DMI_CPU0_PCH_TX_C_DN"
				( memberType ( signal ) )
				( member ( signalRef "DMI_CPU0_PCH_TX_C_DN<0>") )
				( member ( signalRef "DMI_CPU0_PCH_TX_C_DN<1>") )
				( member ( signalRef "DMI_CPU0_PCH_TX_C_DN<2>") )
				( member ( signalRef "DMI_CPU0_PCH_TX_C_DN<3>") )
				( objectStatus "@baseboard_fab2_lib.baseboard_fab2(sch_1):dmi_cpu0_pch_tx_c_dn" )
			)
			( bus "DMI_CPU0_PCH_TX_C_DP"
				( memberType ( signal ) )
				( member ( signalRef "DMI_CPU0_PCH_TX_C_DP<0>") )
				( member ( signalRef "DMI_CPU0_PCH_TX_C_DP<1>") )
				( member ( signalRef "DMI_CPU0_PCH_TX_C_DP<2>") )
				( member ( signalRef "DMI_CPU0_PCH_TX_C_DP<3>") )
				( objectStatus "@baseboard_fab2_lib.baseboard_fab2(sch_1):dmi_cpu0_pch_tx_c_dp" )
			)
			( bus "LPC_LAD_IO"
				( memberType ( signal ) )
				( member ( signalRef "LPC_LAD0_IO0") )
				( member ( signalRef "LPC_LAD1_IO1") )
				( member ( signalRef "LPC_LAD2_IO2") )
				( member ( signalRef "LPC_LAD3_IO3") )
				( objectStatus "@baseboard_fab2_lib.baseboard_fab2(sch_1):lpc_lad_io" )
			)
			( bus "FM_ROMA"
				( memberType ( signal ) )
				( member ( signalRef "FM_ROMA<0>") )
				( member ( signalRef "FM_ROMA<1>") )
				( member ( signalRef "FM_ROMA<2>") )
				( member ( signalRef "FM_ROMA<3>") )
				( member ( signalRef "FM_ROMA<4>") )
				( member ( signalRef "FM_ROMA<5>") )
				( member ( signalRef "FM_ROMA<6>") )
				( member ( signalRef "FM_ROMA<7>") )
				( member ( signalRef "FM_ROMA<8>") )
				( member ( signalRef "FM_ROMA<9>") )
				( member ( signalRef "FM_ROMA<10>") )
				( member ( signalRef "FM_ROMA<11>") )
				( member ( signalRef "FM_ROMA<12>") )
				( member ( signalRef "FM_ROMA<13>") )
				( member ( signalRef "FM_ROMA<14>") )
				( member ( signalRef "FM_ROMA<15>") )
				( member ( signalRef "FM_ROMA<16>") )
				( member ( signalRef "FM_ROMA<17>") )
				( member ( signalRef "FM_ROMA<18>") )
				( member ( signalRef "FM_ROMA<19>") )
				( member ( signalRef "FM_ROMA<20>") )
				( member ( signalRef "FM_ROMA<21>") )
				( member ( signalRef "FM_ROMA<22>") )
				( member ( signalRef "FM_ROMA<23>") )
				( objectStatus "@baseboard_fab2_lib.baseboard_fab2(sch_1):fm_roma" )
			)
			( bus "M_BMC_DDR3_DQ"
				( memberType ( signal ) )
				( member ( signalRef "M_BMC_DDR3_DQ<0>") )
				( member ( signalRef "M_BMC_DDR3_DQ<1>") )
				( member ( signalRef "M_BMC_DDR3_DQ<2>") )
				( member ( signalRef "M_BMC_DDR3_DQ<3>") )
				( member ( signalRef "M_BMC_DDR3_DQ<4>") )
				( member ( signalRef "M_BMC_DDR3_DQ<5>") )
				( member ( signalRef "M_BMC_DDR3_DQ<6>") )
				( member ( signalRef "M_BMC_DDR3_DQ<7>") )
				( member ( signalRef "M_BMC_DDR3_DQ<8>") )
				( member ( signalRef "M_BMC_DDR3_DQ<9>") )
				( member ( signalRef "M_BMC_DDR3_DQ<10>") )
				( member ( signalRef "M_BMC_DDR3_DQ<11>") )
				( member ( signalRef "M_BMC_DDR3_DQ<12>") )
				( member ( signalRef "M_BMC_DDR3_DQ<13>") )
				( member ( signalRef "M_BMC_DDR3_DQ<14>") )
				( member ( signalRef "M_BMC_DDR3_DQ<15>") )
				( objectStatus "@baseboard_fab2_lib.baseboard_fab2(sch_1):m_bmc_ddr3_dq" )
			)
			( bus "M_BMC_DDR3_MA"
				( memberType ( signal ) )
				( member ( signalRef "M_BMC_DDR3_MA<0>") )
				( member ( signalRef "M_BMC_DDR3_MA<1>") )
				( member ( signalRef "M_BMC_DDR3_MA<2>") )
				( member ( signalRef "M_BMC_DDR3_MA<3>") )
				( member ( signalRef "M_BMC_DDR3_MA<4>") )
				( member ( signalRef "M_BMC_DDR3_MA<5>") )
				( member ( signalRef "M_BMC_DDR3_MA<6>") )
				( member ( signalRef "M_BMC_DDR3_MA<7>") )
				( member ( signalRef "M_BMC_DDR3_MA<8>") )
				( member ( signalRef "M_BMC_DDR3_MA<9>") )
				( member ( signalRef "M_BMC_DDR3_MA<10>") )
				( member ( signalRef "M_BMC_DDR3_MA<11>") )
				( member ( signalRef "M_BMC_DDR3_MA<12>") )
				( member ( signalRef "M_BMC_DDR3_MA<13>") )
				( member ( signalRef "M_BMC_DDR3_MA<14>") )
				( objectStatus "@baseboard_fab2_lib.baseboard_fab2(sch_1):m_bmc_ddr3_ma" )
			)
			( bus "P3E_CPU1_PE3_MP_C_TXN"
				( memberType ( signal ) )
				( member ( signalRef "P3E_CPU1_PE3_MP_C_TXN<0>") )
				( member ( signalRef "P3E_CPU1_PE3_MP_C_TXN<1>") )
				( member ( signalRef "P3E_CPU1_PE3_MP_C_TXN<2>") )
				( member ( signalRef "P3E_CPU1_PE3_MP_C_TXN<3>") )
				( member ( signalRef "P3E_CPU1_PE3_MP_C_TXN<4>") )
				( member ( signalRef "P3E_CPU1_PE3_MP_C_TXN<5>") )
				( member ( signalRef "P3E_CPU1_PE3_MP_C_TXN<6>") )
				( member ( signalRef "P3E_CPU1_PE3_MP_C_TXN<7>") )
				( member ( signalRef "P3E_CPU1_PE3_MP_C_TXN<8>") )
				( member ( signalRef "P3E_CPU1_PE3_MP_C_TXN<9>") )
				( member ( signalRef "P3E_CPU1_PE3_MP_C_TXN<10>") )
				( member ( signalRef "P3E_CPU1_PE3_MP_C_TXN<11>") )
				( member ( signalRef "P3E_CPU1_PE3_MP_C_TXN<12>") )
				( member ( signalRef "P3E_CPU1_PE3_MP_C_TXN<13>") )
				( member ( signalRef "P3E_CPU1_PE3_MP_C_TXN<14>") )
				( member ( signalRef "P3E_CPU1_PE3_MP_C_TXN<15>") )
				( objectStatus "@baseboard_fab2_lib.baseboard_fab2(sch_1):p3e_cpu1_pe3_mp_c_txn" )
			)
			( bus "P3E_CPU1_PE3_MP_C_TXP"
				( memberType ( signal ) )
				( member ( signalRef "P3E_CPU1_PE3_MP_C_TXP<0>") )
				( member ( signalRef "P3E_CPU1_PE3_MP_C_TXP<1>") )
				( member ( signalRef "P3E_CPU1_PE3_MP_C_TXP<2>") )
				( member ( signalRef "P3E_CPU1_PE3_MP_C_TXP<3>") )
				( member ( signalRef "P3E_CPU1_PE3_MP_C_TXP<4>") )
				( member ( signalRef "P3E_CPU1_PE3_MP_C_TXP<5>") )
				( member ( signalRef "P3E_CPU1_PE3_MP_C_TXP<6>") )
				( member ( signalRef "P3E_CPU1_PE3_MP_C_TXP<7>") )
				( member ( signalRef "P3E_CPU1_PE3_MP_C_TXP<8>") )
				( member ( signalRef "P3E_CPU1_PE3_MP_C_TXP<9>") )
				( member ( signalRef "P3E_CPU1_PE3_MP_C_TXP<10>") )
				( member ( signalRef "P3E_CPU1_PE3_MP_C_TXP<11>") )
				( member ( signalRef "P3E_CPU1_PE3_MP_C_TXP<12>") )
				( member ( signalRef "P3E_CPU1_PE3_MP_C_TXP<13>") )
				( member ( signalRef "P3E_CPU1_PE3_MP_C_TXP<14>") )
				( member ( signalRef "P3E_CPU1_PE3_MP_C_TXP<15>") )
				( objectStatus "@baseboard_fab2_lib.baseboard_fab2(sch_1):p3e_cpu1_pe3_mp_c_txp" )
			)
			( bus "NC_M2"
				( memberType ( signal ) )
				( member ( signalRef "NC_M2<0>") )
				( member ( signalRef "NC_M2<1>") )
				( member ( signalRef "NC_M2<2>") )
				( member ( signalRef "NC_M2<3>") )
				( member ( signalRef "NC_M2<4>") )
				( member ( signalRef "NC_M2<5>") )
				( member ( signalRef "NC_M2<6>") )
				( member ( signalRef "NC_M2<7>") )
				( member ( signalRef "NC_M2<8>") )
				( member ( signalRef "NC_M2<9>") )
				( member ( signalRef "NC_M2<10>") )
				( member ( signalRef "NC_M2<11>") )
				( member ( signalRef "NC_M2<12>") )
				( member ( signalRef "NC_M2<13>") )
				( member ( signalRef "NC_M2<14>") )
				( member ( signalRef "NC_M2<15>") )
				( member ( signalRef "NC_M2<16>") )
				( member ( signalRef "NC_M2<17>") )
				( member ( signalRef "NC_M2<18>") )
				( objectStatus "@baseboard_fab2_lib.baseboard_fab2(sch_1):nc_m2" )
			)
			( bus "P3E_PCH_M2_TX_C_DN"
				( memberType ( signal ) )
				( member ( signalRef "P3E_PCH_M2_TX_C_DN<1>") )
				( member ( signalRef "P3E_PCH_M2_TX_C_DN<2>") )
				( member ( signalRef "P3E_PCH_M2_TX_C_DN<3>") )
				( objectStatus "@baseboard_fab2_lib.baseboard_fab2(sch_1):p3e_pch_m2_tx_c_dn" )
			)
			( bus "P3E_PCH_M2_TX_C_DP"
				( memberType ( signal ) )
				( member ( signalRef "P3E_PCH_M2_TX_C_DP<1>") )
				( member ( signalRef "P3E_PCH_M2_TX_C_DP<2>") )
				( member ( signalRef "P3E_PCH_M2_TX_C_DP<3>") )
				( objectStatus "@baseboard_fab2_lib.baseboard_fab2(sch_1):p3e_pch_m2_tx_c_dp" )
			)
			( bus "TP_RSVD"
				( memberType ( signal ) )
				( member ( signalRef "TP_RSVD<0>") )
				( objectStatus "@baseboard_fab2_lib.baseboard_fab2(sch_1):tp_rsvd" )
			)
		)
	)
)
 